G04 ================== begin FILE IDENTIFICATION RECORD ==================*
G04 Layout Name:  15126-1b.brd*
G04 Film Name:    L6GND*
G04 File Format:  Gerber RS274X*
G04 File Origin:  Cadence Allegro 16.6-2015-S079*
G04 Origin Date:  Fri Feb 10 17:22:28 2017*
G04 *
G04 Layer:  VIA CLASS/L6GND*
G04 Layer:  PIN/L6GND*
G04 Layer:  ETCH/L6GND*
G04 Layer:  DRAWING FORMAT/LAYER_PCB_STORY*
G04 Layer:  DRAWING FORMAT/LAYER_L6GND*
G04 *
G04 Offset:    (0.00 0.00)*
G04 Mirror:    No*
G04 Mode:      Positive*
G04 Rotation:  0*
G04 FullContactRelief:  No*
G04 UndefLineWidth:     6.00*
G04 ================== end FILE IDENTIFICATION RECORD ====================*
%FSLAX35Y35*MOIN*%
%IR0*IPPOS*OFA0.00000B0.00000*MIA0B0*SFA1.00000B1.00000*%
%ADD12C,.02*%
%ADD40C,.03*%
%ADD28C,.031*%
%ADD10C,.022*%
%ADD23C,.05*%
%ADD21C,.06*%
%ADD29C,.052*%
%ADD13C,.034*%
%ADD17C,.071*%
%ADD16C,.044*%
%ADD37C,.045*%
%ADD26C,.054*%
%ADD22C,.018*%
%ADD38C,.055*%
%ADD25C,.064*%
%ADD20C,.028*%
%ADD14C,.046*%
%ADD32C,.047*%
%ADD24C,.056*%
%ADD19C,.039*%
%ADD18C,.057*%
%ADD34O,.041X.06*%
%AMMACRO36*
4,1,48,.0225,.036,
.026668,.035635,
.030708,.034553,
.0345,.032785,
.037927,.030385,
.040885,.027427,
.043285,.024,
.045053,.020208,
.046135,.016168,
.0465,.012,
.046135,.007832,
.045053,.003792,
.043285,0.0,
.040885,-.003427,
.037927,-.006385,
.0345,-.008785,
.030708,-.010553,
.026668,-.011635,
.0225,-.012,
.0015,-.012,
.001135,-.016168,
.000053,-.020208,
-.001715,-.024,
-.004115,-.027427,
-.007073,-.030385,
-.0105,-.032785,
-.014292,-.034553,
-.018332,-.035635,
-.0225,-.036,
-.026668,-.035635,
-.030708,-.034553,
-.0345,-.032785,
-.037927,-.030385,
-.040885,-.027427,
-.043285,-.024,
-.045053,-.020208,
-.046135,-.016168,
-.0465,-.012,
-.0465,.012,
-.046135,.016168,
-.045053,.020208,
-.043285,.024,
-.040885,.027427,
-.037927,.030385,
-.0345,.032785,
-.030708,.034553,
-.026668,.035635,
-.0225,.036,
.0225,.036,
0.0*
%
%ADD36MACRO36*%
%ADD30O,.07X.046*%
%ADD15C,.14*%
%ADD39O,.094X.048*%
%ADD11C,.238*%
%ADD31O,.098X.046*%
%ADD27C,.276*%
%ADD33O,.099X.048*%
%ADD41C,.01*%
%ADD42C,.025*%
%ADD43C,.006*%
%ADD44C,.0045*%
%ADD87R,.05948X.06858*%
%ADD50O,.07202X.12102*%
%ADD66C,.03004*%
%ADD80C,.04004*%
%ADD69C,.03204*%
%ADD89C,.06104*%
%ADD63C,.07004*%
%ADD82C,.08004*%
%ADD74C,.06204*%
%ADD71C,.02604*%
%ADD60C,.04404*%
%ADD76C,.07204*%
%ADD72C,.02704*%
%ADD86C,.05504*%
%ADD77C,.06404*%
%ADD47C,.02804*%
%ADD85C,.06504*%
%ADD79C,.04704*%
%ADD65C,.07404*%
%ADD46C,.05604*%
%ADD88C,.05506*%
%ADD83C,.05704*%
%ADD81C,.09304*%
%ADD73C,.07504*%
%ADD62C,.08404*%
%ADD57C,.04804*%
%ADD64C,.07604*%
%ADD84C,.06804*%
%ADD68C,.05904*%
%ADD59C,.08604*%
%ADD75C,.07804*%
%ADD53C,.06943*%
%ADD55C,.11211*%
%ADD67C,.12104*%
%ADD58C,.11204*%
%ADD56C,.261*%
%ADD61C,.15004*%
%ADD49O,.15402X.21902*%
%ADD45C,.11404*%
%ADD54C,.11209*%
%ADD48O,.15404X.21904*%
%ADD51C,.15504*%
%ADD52C,.15506*%
%ADD78C,.28404*%
%ADD70C,.17804*%
G75*
%LPD*%
G75*
G36*
G01X1973300Y-60000D02*
X-19810D01*
Y-34500D01*
X1973300D01*
Y-60000D01*
G37*
G36*
G01X1974577Y-15700D02*
Y-19685D01*
G02X1972441Y-21821I-2136J0D01*
G01X1966914D01*
X1966913Y-21822D01*
X1921616Y-21771D01*
X1894767D01*
G02X1894393Y-21230I0J400D01*
G03X1891769I-1312J495D01*
G02X1891395Y-21771I-374J-141D01*
G01X1397253D01*
X1394100Y-21822D01*
X1105041D01*
G02X1104666Y-21284I0J400D01*
G03X1102034I-1316J484D01*
G02X1101659Y-21822I-375J-138D01*
G01X1100391D01*
G02X1100016Y-21284I0J400D01*
G03X1097384I-1316J484D01*
G02X1097009Y-21822I-375J-138D01*
G01X1096711D01*
G02X1096367Y-21218I0J400D01*
G03X1093957I-1205J716D01*
G02X1093613Y-21822I-344J-204D01*
G01X977651D01*
G02X977285Y-21262I0J400D01*
G03X974715I-1285J562D01*
G02X974349Y-21822I-366J-160D01*
G01X658436D01*
G02X658075Y-21251I0J400D01*
G03X655539I-1268J599D01*
G02X655178Y-21822I-361J-171D01*
G01X455500D01*
Y-20900D01*
X455200Y-20600D01*
X455097D01*
X455058Y-20450D01*
G03X452342I-1358J-350D01*
G01X452303Y-20600D01*
X451797D01*
X451758Y-20450D01*
G03X449052Y-20412I-1358J-350D01*
G01X449038Y-20462D01*
X448600Y-20900D01*
Y-21822D01*
X75262Y-21785D01*
X69248Y-21787D01*
G02X68874Y-21245I0J400D01*
G03X67065Y-19435I-1310J500D01*
G02X66532Y-19149I-143J374D01*
G03X64216Y-18423I-1368J-307D01*
G02X63622Y-18362I-270J295D01*
G03X63434Y-20217I-1136J-822D01*
G02X64028Y-20278I270J-295D01*
G03X65663Y-20766I1136J822D01*
G02X66196Y-21052I143J-374D01*
G03X66255Y-21246I1367J310D01*
G02X65881Y-21789I-374J-143D01*
G01X52243Y-21794D01*
G02X51875Y-21237I0J400D01*
G03X49297Y-21239I-1289J550D01*
G02X48929Y-21796I-368J-157D01*
G01X39780Y-21800D01*
G02X39435Y-21197I0J400D01*
G03X37020Y-21198I-1208J712D01*
G02X36675Y-21801I-345J-203D01*
G01X-14469Y-21822D01*
G02X-21822Y-14469I0J7353D01*
G01Y617225D01*
G02X-16285Y624350I7353J-1D01*
G01X-15329Y624573D01*
X385284D01*
G02X385658Y624032I0J-400D01*
G03X388282I1312J-493D01*
G02X388656Y624573I374J141D01*
G01X451663D01*
G02X452015Y623984I0J-400D01*
G03X454485I1235J-664D01*
G02X454837Y624573I352J189D01*
G01X455323D01*
G02X455675Y623984I0J-400D01*
G03X458145I1235J-664D01*
G02X458497Y624573I352J189D01*
G01X726328D01*
G02X726699Y624024I0J-400D01*
G03X729301I1301J-524D01*
G02X729672Y624573I371J149D01*
G01X734299D01*
X1044829Y624575D01*
G02X1045200Y624025I0J-400D01*
G03X1047800I1300J-525D01*
G02X1048171Y624575I371J150D01*
G01X1476500Y624578D01*
Y624549D01*
X1486300D01*
Y624578D01*
X1549800D01*
Y624538D01*
X1550521D01*
G02X1550893Y623992I0J-400D01*
G03X1553503I1305J-513D01*
G02X1553875Y624538I372J146D01*
G01X1555869D01*
G02X1556247Y624010I-1J-400D01*
G03X1558813Y622900I1328J-451D01*
G02X1559517Y622904I353J-188D01*
G03X1562079Y624013I1230J673D01*
G02X1562459Y624538I380J125D01*
G01X1564884D01*
G02X1565247Y623970I0J-400D01*
G03X1567673Y622584I1273J-589D01*
G02X1568333Y622580I329J-228D01*
G03X1570761Y623966I1161J785D01*
G02X1571122Y624538I361J172D01*
G01X1571762D01*
X1571780Y624556D01*
X1967788D01*
G02X1974510Y618222I-565J-7334D01*
G01Y598619D01*
G02X1973864Y598304I-400J0D01*
G03Y596096I-864J-1104D01*
G02X1974510Y595781I246J-315D01*
G01Y566437D01*
G02X1973819Y566163I-400J0D01*
G03Y564237I-1019J-963D01*
G02X1974510Y563963I291J-274D01*
G01Y538037D01*
G02X1973819Y537763I-400J0D01*
G03Y535837I-1019J-963D01*
G02X1974510Y535563I291J-274D01*
G01Y440749D01*
G02X1968106Y434448I-7284J999D01*
G01X1923348D01*
X1922100Y435695D01*
X1922092Y435764D01*
G03X1919539Y436386I-1392J-164D01*
G03X1919533Y436377I1163J-782D01*
G02X1918867I-333J222D01*
G03X1916533I-1167J-777D01*
G02X1915867I-333J222D01*
G03X1915864Y436382I-1204J-719D01*
G03X1913300Y435668I-1164J-782D01*
G01X1913296Y435591D01*
X1912202Y434498D01*
X1683498D01*
X1680050Y431050D01*
Y306416D01*
G02X1679528Y306035I-400J0D01*
G03X1678129Y303689I-428J-1335D01*
G02Y303111I-277J-289D01*
G03Y301089I971J-1011D01*
G02Y300511I-277J-289D01*
G03X1678090Y298527I971J-1011D01*
G02Y297973I-288J-277D01*
G03Y296027I1010J-973D01*
G02Y295473I-288J-277D01*
G03Y293527I1010J-973D01*
G02Y292973I-288J-277D01*
G03Y291027I1010J-973D01*
G02Y290473I-288J-277D01*
G03X1678271Y288369I1010J-973D01*
G02Y287724I-236J-323D01*
G03X1678090Y285620I829J-1131D01*
G02Y285066I-288J-277D01*
G03Y283120I1010J-973D01*
G02Y282566I-288J-277D01*
G03X1678158Y280555I1010J-972D01*
G02Y279962I-269J-297D01*
G03X1678099Y277942I942J-1038D01*
G02Y277382I-285J-280D01*
G03X1678090Y275427I1001J-982D01*
G02Y274873I-288J-277D01*
G03X1678129Y272889I1010J-973D01*
G02Y272311I-277J-289D01*
G03X1679528Y269965I971J-1011D01*
G02X1680050Y269584I122J-381D01*
G01Y268800D01*
X1683450Y265400D01*
X1870726D01*
G02X1871080Y264815I-1J-400D01*
G03X1873566I1243J-648D01*
G02X1873920Y265400I355J185D01*
G01X1883450D01*
X1883667Y265183D01*
G02X1883455Y264507I-283J-282D01*
G03X1882526Y263936I268J-1478D01*
G02X1881876Y263953I-319J241D01*
G03X1879710Y261924I-1242J-844D01*
G02Y261294I-246J-315D01*
G03X1881830Y259202I923J-1185D01*
G02X1882480Y259185I319J-241D01*
G03X1884646Y261214I1242J844D01*
G02Y261844I246J315D01*
G03X1885221Y263132I-923J1185D01*
G01X1885215Y263223D01*
X1885421Y263429D01*
X1885800Y263050D01*
Y248350D01*
X1889300Y244850D01*
X1912314D01*
G02X1912676Y244281I-1J-400D01*
G03X1915398I1361J-635D01*
G02X1915760Y244850I363J169D01*
G01X1946598D01*
Y236102D01*
X1954390D01*
G03X1959543Y236615I2500J1024D01*
G02X1960225Y236815I393J-76D01*
G03X1959666Y239000I1665J1590D01*
G02X1958972Y238849I-386J104D01*
G03X1957693Y239706I-2081J-1723D01*
G01X1957552Y239750D01*
Y244850D01*
X1965840D01*
Y239440D01*
X1974348D01*
G02X1974578Y237616I-7123J-1825D01*
G01Y210008D01*
X1965840D01*
Y204006D01*
X1974578D01*
Y148891D01*
G02X1973989Y148539I-400J1D01*
G03Y146067I-661J-1236D01*
G02X1974578Y145715I189J-353D01*
G01Y144487D01*
G02X1973917Y144184I-400J0D01*
G03Y142056I-913J-1064D01*
G02X1974578Y141753I261J-303D01*
G01Y75500D01*
X1974577D01*
Y66929D01*
G02X1974569Y66750I-2136J6D01*
G01Y58929D01*
X1972570Y56930D01*
X1905340D01*
X1903120Y54710D01*
Y52760D01*
G02X1902523Y52412I-400J0D01*
G03X1897805Y48998I-1578J-2786D01*
G02X1897250Y48554I-392J-79D01*
G03Y42706I-1305J-2924D01*
G02X1897805Y42262I163J-365D01*
G03Y41006I3140J-628D01*
G02X1897250Y40562I-392J-79D01*
G03Y34714I-1305J-2924D01*
G02X1897805Y34270I163J-365D01*
G03Y33014I3140J-628D01*
G02X1897250Y32570I-392J-79D01*
G03Y26722I-1305J-2924D01*
G02X1897805Y26278I163J-365D01*
G03X1897829Y24913I3140J-628D01*
G02X1897269Y24459I-389J-92D01*
G03Y18849I-1324J-2805D01*
G02X1897829Y18395I171J-362D01*
G03X1897805Y17030I3116J-737D01*
G02X1897250Y16586I-392J-79D01*
G03Y10738I-1305J-2924D01*
G02X1897805Y10294I163J-365D01*
G03Y9038I3140J-628D01*
G02X1897250Y8594I-392J-79D01*
G03Y2746I-1305J-2924D01*
G02X1897805Y2302I163J-365D01*
G03Y1046I3140J-628D01*
G02X1897250Y602I-392J-79D01*
G03Y-5246I-1305J-2924D01*
G02X1897805Y-5690I163J-365D01*
G03X1902505Y-9114I3140J-628D01*
G02X1903100Y-9463I195J-349D01*
G01Y-11390D01*
X1905330Y-13620D01*
X1972497D01*
X1974577Y-15700D01*
G37*
G36*
G01X-20621Y661811D02*
G02X-19685Y662747I936J0D01*
G01X1972600D01*
Y637600D01*
X-20412D01*
G02X-20621Y638189I726J589D01*
G01Y661811D01*
G37*
%LPC*%
G75*
G36*
G01X1603820Y433694D02*
G02X1602241Y433668I-770J-1171D01*
G03X1602230Y434329I-231J327D01*
G02X1603809Y434355I770J1171D01*
G03X1603820Y433694I231J-327D01*
G37*
G36*
G01X1685017Y192029D02*
G02X1685249Y190205I1166J-778D01*
G03X1684650Y190129I-266J-298D01*
G02X1684418Y191953I-1166J778D01*
G03X1685017Y192029I266J298D01*
G37*
G36*
G01X1675832Y195852D02*
G03X1675197Y195838I-312J-250D01*
G02X1675158Y197545I-1131J828D01*
G03X1675793Y197559I312J250D01*
G02X1675832Y195852I1131J-828D01*
G37*
G36*
G01X1606022Y557644D02*
Y561645D01*
G02X1607233Y563125I1511J-1D01*
G03X1607452Y563785I-79J393D01*
G02X1616289Y570393I3831J4090D01*
G02X1611415Y562272I-5004J-2520D01*
G02X1609474Y562570I-133J5602D01*
G03X1608983Y562072I-108J-385D01*
G02X1609044Y561654I-1450J-425D01*
G01Y557559D01*
X1609035Y557475D01*
G02X1606022Y557644I-1502J169D01*
G37*
G36*
G01X1514847Y92931D02*
X1514848D01*
Y92928D01*
X1514846D01*
Y92924D01*
X1514847D01*
G02X1514846Y92853I-1512J-14D01*
G01Y92836D01*
X1514844Y92817D01*
G02X1511844Y92664I-1509J102D01*
G01X1511820Y92780D01*
Y92784D01*
X1511819D01*
X1511496Y96414D01*
X1511497D01*
Y96415D01*
X1511501Y96542D01*
G02X1512516Y97974I1512J4D01*
G02X1513224Y98044I499J-1427D01*
G02X1514519Y96682I-211J-1498D01*
G01X1514529Y96683D01*
X1514541Y96554D01*
X1514534D01*
X1514535Y96548D01*
X1514541D01*
X1514852Y93055D01*
X1514849Y93053D01*
X1514848D01*
X1514843Y93048D01*
X1514844Y93026D01*
G02X1514847Y92931I-1509J-95D01*
G37*
G36*
G01X1756912Y37661D02*
Y37615D01*
X1756908Y37577D01*
G02X1754912Y36269I-1507J123D01*
G01X1754909Y36259D01*
X1751506Y37425D01*
Y37430D01*
X1751440Y37460D01*
G02X1751250Y37551I557J1406D01*
G03X1751065Y37198I-78J-184D01*
G02X1751762Y35935I-815J-1273D01*
G01Y35840D01*
X1751752Y35756D01*
G02X1750250Y34414I-1502J170D01*
G01X1746550D01*
G02X1745673Y37156I0J1511D01*
G03X1745687Y37796I-233J325D01*
G02X1747684Y38073I865J1104D01*
G03X1748006Y37436I323J-237D01*
G01X1750251D01*
G02X1750363Y37432I2J-1511D01*
G03X1750741Y38027I29J399D01*
G02X1752488Y40296I1260J837D01*
G01X1752491Y40306D01*
X1755896Y39140D01*
Y39138D01*
X1756013Y39082D01*
G02X1756350Y38877I-611J-1383D01*
G01Y38876D01*
G02X1756360Y38868I-939J-1184D01*
G01X1756362D01*
G02X1756912Y37710I-963J-1167D01*
G01Y37702D01*
G02Y37661I-1512J-20D01*
G37*
G36*
G01X47679Y260603D02*
X58221Y271145D01*
X74615D01*
X79069Y266691D01*
Y222931D01*
X75339Y219201D01*
X51302D01*
X47679Y222824D01*
Y260603D01*
G37*
G36*
G01X1928253Y535242D02*
X1930653D01*
G02Y529840I0J-2701D01*
G01X1928253D01*
G02Y535242I0J2701D01*
G37*
G36*
G01X1926853Y513904D02*
X1932053D01*
G02Y508500I0J-2702D01*
G01X1926853D01*
G02Y513904I0J2702D01*
G37*
G36*
G01X1951554Y127860D02*
X1958054D01*
G02Y112456I0J-7702D01*
G01X1951554D01*
G02Y127860I0J7702D01*
G37*
G36*
G01X1884727Y535242D02*
X1889927D01*
G02Y529840I0J-2701D01*
G01X1884727D01*
G02Y535242I0J2701D01*
G37*
G36*
G01X1886127Y513904D02*
X1888527D01*
G02Y508500I0J-2702D01*
G01X1886127D01*
G02Y513904I0J2702D01*
G37*
G36*
G01X1833443Y127860D02*
X1839943D01*
G02Y112456I0J-7702D01*
G01X1833443D01*
G02Y127860I0J7702D01*
G37*
G36*
G01X1857035Y602728D02*
X1854331D01*
G02Y618532I1J7902D01*
G01X1857044D01*
G03X1860510Y619640I-2J5982D01*
G02X1860511Y601620I7622J-9010D01*
G03X1857035Y602728I-3476J-4898D01*
G37*
G36*
G01Y-15776D02*
X1854331D01*
G02Y28I1J7902D01*
G01X1857044D01*
G03X1860510Y1136I-2J5982D01*
G02X1860511Y-16884I7622J-9010D01*
G03X1857035Y-15776I-3476J-4898D01*
G37*
G36*
G01X1675404Y616622D02*
X1678356Y611110D01*
G02X1674210Y608890I-2073J-1110D01*
G01X1671258Y614402D01*
G02X1675404Y616622I2073J1110D01*
G37*
G36*
G01X1684261Y601662D02*
X1687214Y596150D01*
G02X1683070Y593928I-2072J-1111D01*
G01X1680117Y599440D01*
G02X1684261Y601662I2072J1111D01*
G37*
G36*
G01X1675404Y601661D02*
X1678356Y596149D01*
G02X1674210Y593929I-2073J-1110D01*
G01X1671258Y599441D01*
G02X1675404Y601661I2073J1110D01*
G37*
G36*
G01X1684261Y616623D02*
X1687214Y611111D01*
G02X1683070Y608889I-2072J-1111D01*
G01X1680117Y614401D01*
G02X1684261Y616623I2072J1111D01*
G37*
G36*
G01X1408216Y602728D02*
X1405512D01*
G02Y618532I1J7902D01*
G01X1408225D01*
G03X1411691Y619640I-2J5982D01*
G02X1411692Y601620I7622J-9010D01*
G03X1408216Y602728I-3476J-4898D01*
G37*
G36*
G01Y-15776D02*
X1405512D01*
G02Y28I1J7902D01*
G01X1408225D01*
G03X1411691Y1136I-2J5982D01*
G02X1411692Y-16884I7622J-9010D01*
G03X1408216Y-15776I-3476J-4898D01*
G37*
G36*
G01X679869Y602728D02*
X677165D01*
G02Y618532I1J7902D01*
G01X679878D01*
G03X683344Y619640I-2J5982D01*
G02X683345Y601620I7622J-9010D01*
G03X679869Y602728I-3476J-4898D01*
G37*
G36*
G01Y-15776D02*
X677165D01*
G02Y28I1J7902D01*
G01X679878D01*
G03X683344Y1136I-2J5982D01*
G02X683345Y-16884I7622J-9010D01*
G03X679869Y-15776I-3476J-4898D01*
G37*
G36*
G01X2704Y602728D02*
X0D01*
G02Y618532I1J7902D01*
G01X2713D01*
G03X6179Y619640I-2J5982D01*
G02X6180Y601620I7622J-9010D01*
G03X2704Y602728I-3476J-4898D01*
G37*
G36*
G01X1313465Y618530D02*
G03X1312887I-289J-277D01*
G02Y620472I-1011J971D01*
G03X1313465I289J277D01*
G02Y618530I1011J-971D01*
G37*
G36*
G01X1591926Y619723D02*
G03X1592512Y619711I299J266D01*
G02X1592474Y617801I1007J-975D01*
G03X1591888Y617813I-299J-266D01*
G02X1591926Y619723I-1007J975D01*
G37*
G36*
G01X1602539Y617279D02*
G03X1601961I-289J-277D01*
G02Y619221I-1011J971D01*
G03X1602539I289J277D01*
G02Y617279I1011J-971D01*
G37*
G36*
G01X1962583Y618411D02*
G03Y617789I252J-311D01*
G02X1960817I-883J-1089D01*
G03Y618411I-252J311D01*
G02X1962583I883J1089D01*
G37*
G36*
G01X713345Y616607D02*
G03X712901Y616223I-44J-398D01*
G02X711655Y617667I-1401J51D01*
G03X712099Y618051I44J398D01*
G02X713345Y616607I1401J-51D01*
G37*
G36*
G01X1931383Y617811D02*
G03Y617189I252J-311D01*
G02X1929617I-883J-1089D01*
G03Y617811I-252J311D01*
G02X1931383I883J1089D01*
G37*
G36*
G01X1372904Y615115D02*
G03X1372297Y615025I-266J-298D01*
G02X1372034Y616802I-1197J731D01*
G03X1372641Y616892I266J298D01*
G02X1372904Y615115I1197J-731D01*
G37*
G36*
G01X629517Y611700D02*
G03X629012Y611466I-132J-378D01*
G02X628165Y613297I-1307J507D01*
G03X628670Y613531I132J378D01*
G02X629517Y611700I1307J-507D01*
G37*
G36*
G01X1015360Y612989D02*
G03X1015938Y612881I339J213D01*
G02X1015591Y611012I840J-1123D01*
G03X1015013Y611120I-339J-213D01*
G02X1015360Y612989I-840J1123D01*
G37*
G36*
G01X365752D02*
G03X366330Y612881I339J213D01*
G02X365983Y611012I840J-1123D01*
G03X365405Y611120I-339J-213D01*
G02X365752Y612989I-840J1123D01*
G37*
G36*
G01X656071Y613089D02*
G03Y612511I277J-289D01*
G02X654129I-971J-1011D01*
G03Y613089I-277J289D01*
G02X656071I971J1011D01*
G37*
G36*
G01X1533154Y612419D02*
G03X1533178Y611832I283J-282D01*
G02X1531276Y611753I-908J-1068D01*
G03X1531252Y612340I-283J282D01*
G02X1531212Y612375I903J1072D01*
G03X1530665Y612370I-271J-294D01*
G02X1528802Y612305I-968J1014D01*
G03X1528215Y612219I-255J-308D01*
G02X1527945Y614079I-1165J781D01*
G03X1528532Y614165I255J308D01*
G02X1528563Y614209I1162J-786D01*
G03X1528485Y614509I-161J118D01*
G02X1530296Y615109I582J1275D01*
G03X1530435Y614576I350J-193D01*
G02X1530645Y614417I-738J-1192D01*
G03X1531192Y614422I271J294D01*
G02X1533154Y612419I969J-1014D01*
G37*
G36*
G01X1383607Y611122D02*
G03X1383603Y610567I286J-280D01*
G02X1381584Y610582I-1017J-965D01*
G03X1381588Y611137I-286J280D01*
G02X1383607Y611122I1017J965D01*
G37*
G36*
G01X1652380Y614210D02*
Y609115D01*
X1652371Y609031D01*
G02X1649358Y609200I-1502J169D01*
G01Y614201D01*
G02X1652380Y614210I1511J-1D01*
G37*
G36*
G01X1637045Y616571D02*
X1637046Y616569D01*
X1639942Y611164D01*
X1639943Y611162D01*
G02X1635798Y608941I-2045J-1162D01*
G01X1635797Y608943D01*
X1632901Y614348D01*
X1632900Y614350D01*
G02X1637045Y616571I2045J1162D01*
G37*
G36*
G01X1628179Y616586D02*
X1628180Y616585D01*
X1631092Y611148D01*
X1631093Y611146D01*
G02X1626947Y608926I-2054J-1146D01*
G01X1626946Y608927D01*
X1624034Y614364D01*
X1624033Y614366D01*
G02X1628179Y616586I2054J1146D01*
G37*
G36*
G01X1505671Y610089D02*
G03Y609511I277J-289D01*
G02X1503729I-971J-1011D01*
G03Y610089I-277J289D01*
G02X1505671I971J1011D01*
G37*
G36*
G01X1307614Y609031D02*
G03X1307604Y608489I289J-276D01*
G02X1305542Y608527I-1049J-931D01*
G03X1305552Y609069I-289J276D01*
G02X1307614Y609031I1049J931D01*
G37*
G36*
G01X1225735Y608978D02*
G03X1225740Y608390I274J-292D01*
G02X1223839Y608371I-940J-1040D01*
G03X1223834Y608959I-274J292D01*
G02X1225735Y608978I940J1040D01*
G37*
G36*
G01X1188924D02*
G03X1188929Y608390I274J-292D01*
G02X1187028Y608371I-940J-1040D01*
G03X1187023Y608959I-274J292D01*
G02X1188924Y608978I940J1040D01*
G37*
G36*
G01X1152113D02*
G03X1152118Y608390I274J-292D01*
G02X1150217Y608371I-940J-1040D01*
G03X1150212Y608959I-274J292D01*
G02X1152113Y608978I940J1040D01*
G37*
G36*
G01X1115301D02*
G03X1115306Y608390I274J-292D01*
G02X1113405Y608371I-940J-1040D01*
G03X1113400Y608959I-274J292D01*
G02X1115301Y608978I940J1040D01*
G37*
G36*
G01X934593D02*
G03X934598Y608390I274J-292D01*
G02X932697Y608371I-940J-1040D01*
G03X932692Y608959I-274J292D01*
G02X934593Y608978I940J1040D01*
G37*
G36*
G01X897782D02*
G03X897787Y608390I274J-292D01*
G02X895886Y608371I-940J-1040D01*
G03X895881Y608959I-274J292D01*
G02X897782Y608978I940J1040D01*
G37*
G36*
G01X860971D02*
G03X860976Y608390I274J-292D01*
G02X859075Y608371I-940J-1040D01*
G03X859070Y608959I-274J292D01*
G02X860971Y608978I940J1040D01*
G37*
G36*
G01X824160D02*
G03X824165Y608390I274J-292D01*
G02X822264Y608371I-940J-1040D01*
G03X822259Y608959I-274J292D01*
G02X824160Y608978I940J1040D01*
G37*
G36*
G01X785453Y608371D02*
G03X785448Y608959I-274J292D01*
G02X787349Y608978I940J1040D01*
G03X787354Y608390I274J-292D01*
G02X785453Y608371I-940J-1040D01*
G37*
G36*
G01X576127Y608978D02*
G03X576132Y608390I274J-292D01*
G02X574231Y608371I-940J-1040D01*
G03X574226Y608959I-274J292D01*
G02X576127Y608978I940J1040D01*
G37*
G36*
G01X539316D02*
G03X539321Y608390I274J-292D01*
G02X537420Y608371I-940J-1040D01*
G03X537415Y608959I-274J292D01*
G02X539316Y608978I940J1040D01*
G37*
G36*
G01X502505D02*
G03X502510Y608390I274J-292D01*
G02X500609Y608371I-940J-1040D01*
G03X500604Y608959I-274J292D01*
G02X502505Y608978I940J1040D01*
G37*
G36*
G01X465693D02*
G03X465698Y608390I274J-292D01*
G02X463797Y608371I-940J-1040D01*
G03X463792Y608959I-274J292D01*
G02X465693Y608978I940J1040D01*
G37*
G36*
G01X284985D02*
G03X284990Y608390I274J-292D01*
G02X283089Y608371I-940J-1040D01*
G03X283084Y608959I-274J292D01*
G02X284985Y608978I940J1040D01*
G37*
G36*
G01X248174D02*
G03X248179Y608390I274J-292D01*
G02X246278Y608371I-940J-1040D01*
G03X246273Y608959I-274J292D01*
G02X248174Y608978I940J1040D01*
G37*
G36*
G01X211363D02*
G03X211368Y608390I274J-292D01*
G02X209467Y608371I-940J-1040D01*
G03X209462Y608959I-274J292D01*
G02X211363Y608978I940J1040D01*
G37*
G36*
G01X174552D02*
G03X174557Y608390I274J-292D01*
G02X172656Y608371I-940J-1040D01*
G03X172651Y608959I-274J292D01*
G02X174552Y608978I940J1040D01*
G37*
G36*
G01X135845Y608371D02*
G03X135840Y608959I-274J292D01*
G02X137741Y608978I940J1040D01*
G03X137746Y608390I274J-292D01*
G02X135845Y608371I-940J-1040D01*
G37*
G36*
G01X1230841Y608734D02*
G03Y608155I276J-290D01*
G02X1228907I-967J-1015D01*
G03Y608734I-276J289D01*
G02X1230841I967J1015D01*
G37*
G36*
G01X1194030D02*
G03Y608155I276J-290D01*
G02X1192096I-967J-1015D01*
G03Y608734I-276J289D01*
G02X1194030I967J1015D01*
G37*
G36*
G01X1157219D02*
G03Y608155I276J-290D01*
G02X1155285I-967J-1015D01*
G03Y608734I-276J289D01*
G02X1157219I967J1015D01*
G37*
G36*
G01X1120407D02*
G03Y608155I276J-290D01*
G02X1118473I-967J-1015D01*
G03Y608734I-276J289D01*
G02X1120407I967J1015D01*
G37*
G36*
G01X939699D02*
G03Y608155I276J-290D01*
G02X937765I-967J-1015D01*
G03Y608734I-276J289D01*
G02X939699I967J1015D01*
G37*
G36*
G01X902888D02*
G03Y608155I276J-290D01*
G02X900954I-967J-1015D01*
G03Y608734I-276J289D01*
G02X902888I967J1015D01*
G37*
G36*
G01X866077D02*
G03Y608155I276J-290D01*
G02X864143I-967J-1015D01*
G03Y608734I-276J289D01*
G02X866077I967J1015D01*
G37*
G36*
G01X829266D02*
G03Y608155I276J-290D01*
G02X827332I-967J-1015D01*
G03Y608734I-276J289D01*
G02X829266I967J1015D01*
G37*
G36*
G01X792455D02*
G03Y608155I276J-290D01*
G02X790521I-967J-1015D01*
G03Y608734I-276J289D01*
G02X792455I967J1015D01*
G37*
G36*
G01X581233D02*
G03Y608155I276J-290D01*
G02X579299I-967J-1015D01*
G03Y608734I-276J289D01*
G02X581233I967J1015D01*
G37*
G36*
G01X544422D02*
G03Y608155I276J-290D01*
G02X542488I-967J-1015D01*
G03Y608734I-276J289D01*
G02X544422I967J1015D01*
G37*
G36*
G01X507611D02*
G03Y608155I276J-290D01*
G02X505677I-967J-1015D01*
G03Y608734I-276J289D01*
G02X507611I967J1015D01*
G37*
G36*
G01X470800D02*
G03Y608155I276J-290D01*
G02X468865I-968J-1015D01*
G03Y608734I-276J289D01*
G02X470800I967J1015D01*
G37*
G36*
G01X290091D02*
G03Y608155I276J-290D01*
G02X288157I-967J-1015D01*
G03Y608734I-276J289D01*
G02X290091I967J1015D01*
G37*
G36*
G01X253280D02*
G03Y608155I276J-290D01*
G02X251346I-967J-1015D01*
G03Y608734I-276J289D01*
G02X253280I967J1015D01*
G37*
G36*
G01X216469D02*
G03Y608155I276J-290D01*
G02X214535I-967J-1015D01*
G03Y608734I-276J289D01*
G02X216469I967J1015D01*
G37*
G36*
G01X179658D02*
G03Y608155I276J-290D01*
G02X177724I-967J-1015D01*
G03Y608734I-276J289D01*
G02X179658I967J1015D01*
G37*
G36*
G01X142847D02*
G03Y608155I276J-290D01*
G02X140913I-967J-1015D01*
G03Y608734I-276J289D01*
G02X142847I967J1015D01*
G37*
G36*
G01X1545090Y606559D02*
G03X1545469Y606114I397J-46D01*
G02X1544014Y604873I-62J-1401D01*
G03X1543635Y605318I-397J46D01*
G02X1542337Y606379I62J1401D01*
G03X1541774Y606642I-388J-97D01*
G02X1542522Y608243I-612J1261D01*
G03X1543085Y607980I388J97D01*
G02X1545090Y606559I612J-1261D01*
G37*
G36*
G01X1605380Y608460D02*
Y604365D01*
X1605371Y604281D01*
G02X1602358Y604450I-1502J169D01*
G01Y608451D01*
G02X1605380Y608460I1511J-1D01*
G37*
G36*
G01X1659880Y606260D02*
Y602165D01*
X1659871Y602081D01*
G02X1656858Y602250I-1502J169D01*
G01Y606251D01*
G02X1659880Y606260I1511J-1D01*
G37*
G36*
G01X1572237Y600367D02*
G03X1571718Y600360I-255J-308D01*
G02X1571683Y602796I-1058J1203D01*
G03X1572202Y602803I255J308D01*
G02X1572237Y600367I1058J-1203D01*
G37*
G36*
G01X1804772Y601902D02*
G03X1804178Y601662I-207J-342D01*
G02X1803850Y604145I-3193J841D01*
G03X1804486Y604068I347J199D01*
G02X1804772Y601902I1014J-968D01*
G37*
G36*
G01X1614860Y603260D02*
Y599165D01*
X1614851Y599081D01*
G02X1611838Y599250I-1502J169D01*
G01Y603251D01*
G02X1614860Y603260I1511J-1D01*
G37*
G36*
G01X1325210Y599127D02*
G03Y598573I288J-277D01*
G02X1323190I-1010J-973D01*
G03Y599127I-288J277D01*
G02X1323229Y601111I1010J973D01*
G03Y601689I-277J289D01*
G02X1323154Y603634I971J1011D01*
G03Y604166I-298J266D01*
G02Y606034I1046J934D01*
G03Y606566I-298J266D01*
G02X1323229Y608511I1046J934D01*
G03Y609089I-277J289D01*
G02X1325171I971J1011D01*
G03Y608511I277J-289D01*
G02X1325246Y606566I-971J-1011D01*
G03Y606034I298J-266D01*
G02Y604166I-1046J-934D01*
G03Y603634I298J-266D01*
G02X1325171Y601689I-1046J-934D01*
G03Y601111I277J-289D01*
G02X1325210Y599127I-971J-1011D01*
G37*
G36*
G01X713010Y598527D02*
G03Y597973I288J-277D01*
G02X710990I-1010J-973D01*
G03Y598527I-288J277D01*
G02X713010I1010J973D01*
G37*
G36*
G01X1589293Y595924D02*
G03X1588711Y595918I-288J-277D01*
G02X1586692Y595871I-1032J949D01*
G03X1586137Y595879I-282J-284D01*
G02X1586166Y597898I-958J1023D01*
G03X1586721Y597890I282J284D01*
G02X1588690Y597839I959J-1023D01*
G03X1589272Y597845I288J277D01*
G02X1589293Y595924I1032J-949D01*
G37*
G36*
G01X709771Y598289D02*
G03Y597711I277J-289D01*
G02X707829I-971J-1011D01*
G03Y598289I-277J289D01*
G02X709771I971J1011D01*
G37*
G36*
G01X1637045Y601610D02*
X1637046Y601608D01*
X1639942Y596203D01*
X1639943Y596201D01*
G02X1635798Y593980I-2045J-1162D01*
G01X1635797Y593982D01*
X1632901Y599387D01*
X1632900Y599389D01*
G02X1637045Y601610I2045J1162D01*
G37*
G36*
G01X1628179Y601625D02*
X1628180Y601624D01*
X1631092Y596187D01*
X1631093Y596185D01*
G02X1626947Y593965I-2054J-1146D01*
G01X1626946Y593966D01*
X1624034Y599403D01*
X1624033Y599405D01*
G02X1628179Y601625I2054J1146D01*
G37*
G36*
G01X1654010Y597960D02*
Y593865D01*
X1654001Y593781D01*
G02X1650988Y593950I-1502J169D01*
G01Y597951D01*
G02X1654010Y597960I1511J-1D01*
G37*
G36*
G01X1016508Y592671D02*
G03X1015930I-289J-277D01*
G02Y594613I-1011J971D01*
G03X1016508I289J277D01*
G02X1018582Y594556I1011J-971D01*
G03X1019200Y594569I304J260D01*
G02X1019237Y592786I1100J-869D01*
G03X1018619Y592773I-304J-260D01*
G02X1016508Y592671I-1100J869D01*
G37*
G36*
G01X1005042Y594590D02*
G03X1005613Y594602I280J286D01*
G02X1005601Y592694I1021J-960D01*
G03X1005031Y592713I-294J-271D01*
G02X1005042Y594590I-897J944D01*
G37*
G36*
G01X366900Y592671D02*
G03X366322I-289J-277D01*
G02Y594613I-1011J971D01*
G03X366900I289J277D01*
G02X368964Y594568I1011J-971D01*
G03X369574Y594579I300J264D01*
G02X369606Y592765I1085J-888D01*
G03X368996Y592754I-300J-264D01*
G02X366900Y592671I-1085J888D01*
G37*
G36*
G01X355434Y594590D02*
G03X356005Y594602I280J286D01*
G02X355993Y592694I1021J-960D01*
G03X355423Y592713I-294J-271D01*
G02X355434Y594590I-897J944D01*
G37*
G36*
G01X754907Y592660D02*
G03X754330Y592649I-283J-282D01*
G02X754293Y594590I-1030J951D01*
G03X754870Y594601I283J282D01*
G02X754907Y592660I1030J-951D01*
G37*
G36*
G01X1801343Y595110D02*
G03X1801349Y594538I283J-283D01*
G02X1799387Y594518I-971J-1011D01*
G03X1799381Y595090I-283J283D01*
G02X1801343Y595110I971J1011D01*
G37*
G36*
G01X1710951Y594470D02*
G03X1710940Y593893I271J-294D01*
G02X1708999Y593930I-990J-993D01*
G03X1709010Y594507I-271J294D01*
G02X1710951Y594470I990J993D01*
G37*
G36*
G01X1605430Y596760D02*
Y592665D01*
X1605421Y592581D01*
G02X1602408Y592750I-1502J169D01*
G01Y596751D01*
G02X1605430Y596760I1511J-1D01*
G37*
G36*
G01X1718962Y593631D02*
G03X1718956Y593035I264J-301D01*
G02X1717083Y593055I-948J-1033D01*
G03X1717089Y593651I-264J301D01*
G02X1717027Y595657I948J1033D01*
G03Y596211I-288J277D01*
G02X1719047I1010J973D01*
G03Y595657I288J-277D01*
G02X1718962Y593631I-1010J-972D01*
G37*
G36*
G01X1554589Y590129D02*
G03X1554011I-289J-277D01*
G02Y592071I-1011J971D01*
G03X1554589I289J277D01*
G02Y590129I1011J-971D01*
G37*
G36*
G01X648104Y592592D02*
G03X648419Y592084I383J-114D01*
G02X646836Y591102I-239J-1382D01*
G03X646521Y591610I-383J114D01*
G02X645381Y592738I239J1382D01*
G03X644880Y593050I-393J-73D01*
G02X645879Y594654I-380J1350D01*
G03X646380Y594342I393J73D01*
G02X648104Y592592I380J-1350D01*
G37*
G36*
G01X2455Y591389D02*
G03X2419Y590786I244J-317D01*
G02X584Y590894I-980J-1003D01*
G03X620Y591497I-244J317D01*
G02X506Y591623I981J1002D01*
G03X194I-156J-125D01*
G02X73Y593510I-1094J877D01*
G03X627I277J288D01*
G02X2455Y591389I972J-1010D01*
G37*
G36*
G01X1763216Y590944D02*
G03Y590666I144J-139D01*
G02X1760908I-1154J-1111D01*
G03Y590944I-144J139D01*
G02X1763216I1154J1111D01*
G37*
G36*
G01X1230845Y590103D02*
G03Y589525I277J-289D01*
G02X1228903I-971J-1011D01*
G03Y590103I-277J289D01*
G02X1230845I971J1011D01*
G37*
G36*
G01X1194034D02*
G03Y589525I277J-289D01*
G02X1192092I-971J-1011D01*
G03Y590103I-277J289D01*
G02X1194034I971J1011D01*
G37*
G36*
G01X1157223D02*
G03Y589525I277J-289D01*
G02X1155281I-971J-1011D01*
G03Y590103I-277J289D01*
G02X1157223I971J1011D01*
G37*
G36*
G01X1120411D02*
G03Y589525I277J-289D01*
G02X1118469I-971J-1011D01*
G03Y590103I-277J289D01*
G02X1120411I971J1011D01*
G37*
G36*
G01X939703D02*
G03Y589525I277J-289D01*
G02X937761I-971J-1011D01*
G03Y590103I-277J289D01*
G02X939703I971J1011D01*
G37*
G36*
G01X902892D02*
G03Y589525I277J-289D01*
G02X900950I-971J-1011D01*
G03Y590103I-277J289D01*
G02X902892I971J1011D01*
G37*
G36*
G01X866081D02*
G03Y589525I277J-289D01*
G02X864139I-971J-1011D01*
G03Y590103I-277J289D01*
G02X866081I971J1011D01*
G37*
G36*
G01X829270D02*
G03Y589525I277J-289D01*
G02X827328I-971J-1011D01*
G03Y590103I-277J289D01*
G02X829270I971J1011D01*
G37*
G36*
G01X792459D02*
G03Y589525I277J-289D01*
G02X790517I-971J-1011D01*
G03Y590103I-277J289D01*
G02X792459I971J1011D01*
G37*
G36*
G01X581237D02*
G03Y589525I277J-289D01*
G02X579295I-971J-1011D01*
G03Y590103I-277J289D01*
G02X581237I971J1011D01*
G37*
G36*
G01X544426D02*
G03Y589525I277J-289D01*
G02X542484I-971J-1011D01*
G03Y590103I-277J289D01*
G02X544426I971J1011D01*
G37*
G36*
G01X507615D02*
G03Y589525I277J-289D01*
G02X505673I-971J-1011D01*
G03Y590103I-277J289D01*
G02X507615I971J1011D01*
G37*
G36*
G01X470803D02*
G03Y589525I277J-289D01*
G02X468861I-971J-1011D01*
G03Y590103I-277J289D01*
G02X470803I971J1011D01*
G37*
G36*
G01X290095D02*
G03Y589525I277J-289D01*
G02X288153I-971J-1011D01*
G03Y590103I-277J289D01*
G02X290095I971J1011D01*
G37*
G36*
G01X253284D02*
G03Y589525I277J-289D01*
G02X251342I-971J-1011D01*
G03Y590103I-277J289D01*
G02X253284I971J1011D01*
G37*
G36*
G01X216473D02*
G03Y589525I277J-289D01*
G02X214531I-971J-1011D01*
G03Y590103I-277J289D01*
G02X216473I971J1011D01*
G37*
G36*
G01X179662D02*
G03Y589525I277J-289D01*
G02X177720I-971J-1011D01*
G03Y590103I-277J289D01*
G02X179662I971J1011D01*
G37*
G36*
G01X142851D02*
G03Y589525I277J-289D01*
G02X140909I-971J-1011D01*
G03Y590103I-277J289D01*
G02X142851I971J1011D01*
G37*
G36*
G01X1225745Y589889D02*
G03Y589311I277J-289D01*
G02X1223803I-971J-1011D01*
G03Y589889I-277J289D01*
G02X1225745I971J1011D01*
G37*
G36*
G01X1188934D02*
G03Y589311I277J-289D01*
G02X1186992I-971J-1011D01*
G03Y589889I-277J289D01*
G02X1188934I971J1011D01*
G37*
G36*
G01X1152123D02*
G03Y589311I277J-289D01*
G02X1150181I-971J-1011D01*
G03Y589889I-277J289D01*
G02X1152123I971J1011D01*
G37*
G36*
G01X1115311D02*
G03Y589311I277J-289D01*
G02X1113369I-971J-1011D01*
G03Y589889I-277J289D01*
G02X1115311I971J1011D01*
G37*
G36*
G01X934603D02*
G03Y589311I277J-289D01*
G02X932661I-971J-1011D01*
G03Y589889I-277J289D01*
G02X934603I971J1011D01*
G37*
G36*
G01X897792D02*
G03Y589311I277J-289D01*
G02X895850I-971J-1011D01*
G03Y589889I-277J289D01*
G02X897792I971J1011D01*
G37*
G36*
G01X860981D02*
G03Y589311I277J-289D01*
G02X859039I-971J-1011D01*
G03Y589889I-277J289D01*
G02X860981I971J1011D01*
G37*
G36*
G01X824170D02*
G03Y589311I277J-289D01*
G02X822228I-971J-1011D01*
G03Y589889I-277J289D01*
G02X824170I971J1011D01*
G37*
G36*
G01X787359D02*
G03Y589311I277J-289D01*
G02X785417I-971J-1011D01*
G03Y589889I-277J289D01*
G02X787359I971J1011D01*
G37*
G36*
G01X576137D02*
G03Y589311I277J-289D01*
G02X574195I-971J-1011D01*
G03Y589889I-277J289D01*
G02X576137I971J1011D01*
G37*
G36*
G01X539326D02*
G03Y589311I277J-289D01*
G02X537384I-971J-1011D01*
G03Y589889I-277J289D01*
G02X539326I971J1011D01*
G37*
G36*
G01X502515D02*
G03Y589311I277J-289D01*
G02X500573I-971J-1011D01*
G03Y589889I-277J289D01*
G02X502515I971J1011D01*
G37*
G36*
G01X465703D02*
G03Y589311I277J-289D01*
G02X463761I-971J-1011D01*
G03Y589889I-277J289D01*
G02X465703I971J1011D01*
G37*
G36*
G01X284995D02*
G03Y589311I277J-289D01*
G02X283053I-971J-1011D01*
G03Y589889I-277J289D01*
G02X284995I971J1011D01*
G37*
G36*
G01X248184D02*
G03Y589311I277J-289D01*
G02X246242I-971J-1011D01*
G03Y589889I-277J289D01*
G02X248184I971J1011D01*
G37*
G36*
G01X211373D02*
G03Y589311I277J-289D01*
G02X209431I-971J-1011D01*
G03Y589889I-277J289D01*
G02X211373I971J1011D01*
G37*
G36*
G01X174562D02*
G03Y589311I277J-289D01*
G02X172620I-971J-1011D01*
G03Y589889I-277J289D01*
G02X174562I971J1011D01*
G37*
G36*
G01X137751D02*
G03Y589311I277J-289D01*
G02X135809I-971J-1011D01*
G03Y589889I-277J289D01*
G02X137751I971J1011D01*
G37*
G36*
G01X1662192Y590760D02*
Y586665D01*
X1662182Y586581D01*
G02X1659168Y586750I-1502J169D01*
G01Y590751D01*
G02X1662192Y590760I1512J-1D01*
G37*
G36*
G01X1419447Y585240D02*
G03X1418893I-277J-288D01*
G02X1416824Y585375I-973J1010D01*
G03X1416215Y585394I-313J-249D01*
G02X1414200Y585322I-1042J938D01*
G03X1413646I-277J-288D01*
G02Y587342I-973J1010D01*
G03X1414200I277J288D01*
G02X1416269Y587207I973J-1010D01*
G03X1416878Y587188I313J249D01*
G02X1418893Y587260I1042J-938D01*
G03X1419447I277J288D01*
G02X1421393I973J-1010D01*
G03X1421947I277J288D01*
G02Y585240I973J-1010D01*
G03X1421393I-277J-288D01*
G02X1419447I-973J1010D01*
G37*
G36*
G01X1611008Y590005D02*
G02X1614030Y590014I1511J-1D01*
G01Y586004D01*
X1614031D01*
Y585919D01*
X1614021Y585835D01*
G02X1611008Y586004I-1502J169D01*
G01Y590005D01*
G37*
G36*
G01X1544189Y584753D02*
G03X1543611I-289J-277D01*
G02Y586695I-1011J971D01*
G03X1544189I289J277D01*
G02Y584753I1011J-971D01*
G37*
G36*
G01X1012804Y584806D02*
G03X1012195I-305J-258D01*
G02Y586622I-1069J908D01*
G03X1012804I304J258D01*
G02Y584806I1069J-908D01*
G37*
G36*
G01X1005039Y586657D02*
G03X1005609Y586672I278J288D01*
G02X1005603Y584763I1024J-958D01*
G03X1005033Y584781I-294J-271D01*
G02X1005039Y586657I-900J941D01*
G37*
G36*
G01X363196Y584806D02*
G03X362587I-305J-258D01*
G02Y586622I-1069J908D01*
G03X363196I305J258D01*
G02X365183Y586774I1069J-908D01*
G03X365765Y586837I262J302D01*
G02X365972Y584940I1125J-837D01*
G03X365390Y584877I-262J-302D01*
G02X363196Y584806I-1125J837D01*
G37*
G36*
G01X355431Y586657D02*
G03X356001Y586672I278J288D01*
G02X355995Y584763I1024J-958D01*
G03X355425Y584781I-294J-271D01*
G02X355431Y586657I-900J941D01*
G37*
G36*
G01X1372689Y583685D02*
G03X1372111I-289J-277D01*
G02Y585627I-1011J971D01*
G03X1372689I289J277D01*
G02Y583685I1011J-971D01*
G37*
G36*
G01X1815255Y582948D02*
G03X1814679Y582814I-227J-329D01*
G02X1814253Y584653I-1223J686D01*
G03X1814829Y584787I227J329D01*
G02X1815255Y582948I1223J-686D01*
G37*
G36*
G01X1731818Y580896D02*
G03X1732393Y580876I297J267D01*
G02X1732324Y578932I975J-1008D01*
G03X1731749Y578952I-297J-267D01*
G02X1731818Y580896I-975J1008D01*
G37*
G36*
G01X1294692Y581162D02*
G03X1295092Y580762I400J0D01*
G02X1293688Y579358I-2J-1402D01*
G03X1293288Y579758I-400J0D01*
G02X1294692Y581162I2J1402D01*
G37*
G36*
G01X1684289Y586650D02*
X1684290Y586648D01*
X1687186Y581243D01*
X1687187Y581241D01*
G02X1683042Y579020I-2045J-1162D01*
G01X1683041Y579022D01*
X1680145Y584427D01*
X1680144Y584429D01*
G02X1684289Y586650I2045J1162D01*
G37*
G36*
G01X1675423Y586665D02*
X1675424Y586664D01*
X1678336Y581227D01*
X1678337Y581225D01*
G02X1674191Y579005I-2054J-1146D01*
G01X1674190Y579006D01*
X1671278Y584443D01*
X1671277Y584445D01*
G02X1675423Y586665I2054J1146D01*
G37*
G36*
G01X1637045Y586650D02*
X1637046Y586648D01*
X1639942Y581243D01*
X1639943Y581241D01*
G02X1635798Y579020I-2045J-1162D01*
G01X1635797Y579022D01*
X1632901Y584427D01*
X1632900Y584429D01*
G02X1637045Y586650I2045J1162D01*
G37*
G36*
G01X1628179Y586665D02*
X1628180Y586664D01*
X1631092Y581227D01*
X1631093Y581225D01*
G02X1626947Y579005I-2054J-1146D01*
G01X1626946Y579006D01*
X1624034Y584443D01*
X1624033Y584445D01*
G02X1628179Y586665I2054J1146D01*
G37*
G36*
G01X1607506Y582510D02*
Y578415D01*
X1607496Y578331D01*
G02X1604482Y578500I-1502J169D01*
G01Y582501D01*
G02X1607506Y582510I1512J-1D01*
G37*
G36*
G01X1654180Y582360D02*
Y578265D01*
X1654171Y578181D01*
G02X1651158Y578350I-1502J169D01*
G01Y582351D01*
G02X1654180Y582360I1511J-1D01*
G37*
G36*
G01X651238Y573438D02*
G03X650696Y573413I-257J-306D01*
G02X648729Y575411I-996J987D01*
G03Y575989I-277J289D01*
G02X650645Y578036I971J1011D01*
G03X651186Y578039I269J296D01*
G02X653150Y576038I954J-1028D01*
G03Y575484I288J-277D01*
G02X651238Y573438I-1009J-973D01*
G37*
G36*
G01X664689Y573229D02*
G03X664111I-289J-277D01*
G02Y575171I-1011J971D01*
G03X664689I289J277D01*
G02Y573229I1011J-971D01*
G37*
G36*
G01X1772522Y574592D02*
G03X1772110Y574142I-15J-400D01*
G02X1770775Y575365I-1391J-178D01*
G03X1771187Y575815I15J400D01*
G02X1772522Y574592I1391J178D01*
G37*
G36*
G01X660489Y568829D02*
G03X659911I-289J-277D01*
G02Y570771I-1011J971D01*
G03X660489I289J277D01*
G02Y568829I1011J-971D01*
G37*
G36*
G01X1225735Y571178D02*
G03X1225740Y570590I274J-292D01*
G02X1223839Y570571I-940J-1040D01*
G03X1223834Y571159I-274J292D01*
G02X1225735Y571178I940J1040D01*
G37*
G36*
G01X1188924D02*
G03X1188929Y570590I274J-292D01*
G02X1187028Y570571I-940J-1040D01*
G03X1187023Y571159I-274J292D01*
G02X1188924Y571178I940J1040D01*
G37*
G36*
G01X1152113D02*
G03X1152118Y570590I274J-292D01*
G02X1150217Y570571I-940J-1040D01*
G03X1150212Y571159I-274J292D01*
G02X1152113Y571178I940J1040D01*
G37*
G36*
G01X1115301D02*
G03X1115306Y570590I274J-292D01*
G02X1113405Y570571I-940J-1040D01*
G03X1113400Y571159I-274J292D01*
G02X1115301Y571178I940J1040D01*
G37*
G36*
G01X934593D02*
G03X934598Y570590I274J-292D01*
G02X932697Y570571I-940J-1040D01*
G03X932692Y571159I-274J292D01*
G02X934593Y571178I940J1040D01*
G37*
G36*
G01X897782D02*
G03X897787Y570590I274J-292D01*
G02X895886Y570571I-940J-1040D01*
G03X895881Y571159I-274J292D01*
G02X897782Y571178I940J1040D01*
G37*
G36*
G01X860971D02*
G03X860976Y570590I274J-292D01*
G02X859075Y570571I-940J-1040D01*
G03X859070Y571159I-274J292D01*
G02X860971Y571178I940J1040D01*
G37*
G36*
G01X824160D02*
G03X824165Y570590I274J-292D01*
G02X822264Y570571I-940J-1040D01*
G03X822259Y571159I-274J292D01*
G02X824160Y571178I940J1040D01*
G37*
G36*
G01X787349D02*
G03X787354Y570590I274J-292D01*
G02X785453Y570571I-940J-1040D01*
G03X785448Y571159I-274J292D01*
G02X787349Y571178I940J1040D01*
G37*
G36*
G01X576127D02*
G03X576132Y570590I274J-292D01*
G02X574231Y570571I-940J-1040D01*
G03X574226Y571159I-274J292D01*
G02X576127Y571178I940J1040D01*
G37*
G36*
G01X539316D02*
G03X539321Y570590I274J-292D01*
G02X537420Y570571I-940J-1040D01*
G03X537415Y571159I-274J292D01*
G02X539316Y571178I940J1040D01*
G37*
G36*
G01X502505D02*
G03X502510Y570590I274J-292D01*
G02X500609Y570571I-940J-1040D01*
G03X500604Y571159I-274J292D01*
G02X502505Y571178I940J1040D01*
G37*
G36*
G01X463797Y570571D02*
G03X463792Y571159I-274J292D01*
G02X465693Y571178I940J1040D01*
G03X465698Y570590I274J-292D01*
G02X463797Y570571I-940J-1040D01*
G37*
G36*
G01X284985Y571178D02*
G03X284990Y570590I274J-292D01*
G02X283089Y570571I-940J-1040D01*
G03X283084Y571159I-274J292D01*
G02X284985Y571178I940J1040D01*
G37*
G36*
G01X248174D02*
G03X248179Y570590I274J-292D01*
G02X246278Y570571I-940J-1040D01*
G03X246273Y571159I-274J292D01*
G02X248174Y571178I940J1040D01*
G37*
G36*
G01X211363D02*
G03X211368Y570590I274J-292D01*
G02X209467Y570571I-940J-1040D01*
G03X209462Y571159I-274J292D01*
G02X211363Y571178I940J1040D01*
G37*
G36*
G01X174552D02*
G03X174557Y570590I274J-292D01*
G02X172656Y570571I-940J-1040D01*
G03X172651Y571159I-274J292D01*
G02X174552Y571178I940J1040D01*
G37*
G36*
G01X135845Y570571D02*
G03X135840Y571159I-274J292D01*
G02X137741Y571178I940J1040D01*
G03X137746Y570590I274J-292D01*
G02X135845Y570571I-940J-1040D01*
G37*
G36*
G01X1230841Y570934D02*
G03Y570355I276J-290D01*
G02X1228907I-967J-1015D01*
G03Y570934I-276J289D01*
G02X1230841I967J1015D01*
G37*
G36*
G01X1194030D02*
G03Y570355I276J-290D01*
G02X1192096I-967J-1015D01*
G03Y570934I-276J289D01*
G02X1194030I967J1015D01*
G37*
G36*
G01X1157219D02*
G03Y570355I276J-290D01*
G02X1155285I-967J-1015D01*
G03Y570934I-276J289D01*
G02X1157219I967J1015D01*
G37*
G36*
G01X1120407D02*
G03Y570355I276J-290D01*
G02X1118473I-967J-1015D01*
G03Y570934I-276J289D01*
G02X1120407I967J1015D01*
G37*
G36*
G01X939699D02*
G03Y570355I276J-290D01*
G02X937765I-967J-1015D01*
G03Y570934I-276J289D01*
G02X939699I967J1015D01*
G37*
G36*
G01X902888D02*
G03Y570355I276J-290D01*
G02X900954I-967J-1015D01*
G03Y570934I-276J289D01*
G02X902888I967J1015D01*
G37*
G36*
G01X866077D02*
G03Y570355I276J-290D01*
G02X864143I-967J-1015D01*
G03Y570934I-276J289D01*
G02X866077I967J1015D01*
G37*
G36*
G01X829266D02*
G03Y570355I276J-290D01*
G02X827332I-967J-1015D01*
G03Y570934I-276J289D01*
G02X829266I967J1015D01*
G37*
G36*
G01X792455D02*
G03Y570355I276J-290D01*
G02X790521I-967J-1015D01*
G03Y570934I-276J289D01*
G02X792455I967J1015D01*
G37*
G36*
G01X581233D02*
G03Y570355I276J-290D01*
G02X579299I-967J-1015D01*
G03Y570934I-276J289D01*
G02X581233I967J1015D01*
G37*
G36*
G01X544422D02*
G03Y570355I276J-290D01*
G02X542488I-967J-1015D01*
G03Y570934I-276J289D01*
G02X544422I967J1015D01*
G37*
G36*
G01X507611D02*
G03Y570355I276J-290D01*
G02X505677I-967J-1015D01*
G03Y570934I-276J289D01*
G02X507611I967J1015D01*
G37*
G36*
G01X470799D02*
G03Y570355I276J-290D01*
G02X468865I-967J-1015D01*
G03Y570934I-276J289D01*
G02X470799I967J1015D01*
G37*
G36*
G01X290091D02*
G03Y570355I276J-290D01*
G02X288157I-967J-1015D01*
G03Y570934I-276J289D01*
G02X290091I967J1015D01*
G37*
G36*
G01X253280D02*
G03Y570355I276J-290D01*
G02X251346I-967J-1015D01*
G03Y570934I-276J289D01*
G02X253280I967J1015D01*
G37*
G36*
G01X216469D02*
G03Y570355I276J-290D01*
G02X214535I-967J-1015D01*
G03Y570934I-276J289D01*
G02X216469I967J1015D01*
G37*
G36*
G01X179658D02*
G03Y570355I276J-290D01*
G02X177724I-967J-1015D01*
G03Y570934I-276J289D01*
G02X179658I967J1015D01*
G37*
G36*
G01X142847D02*
G03Y570355I276J-290D01*
G02X140913I-967J-1015D01*
G03Y570934I-276J289D01*
G02X142847I967J1015D01*
G37*
G36*
G01X703008Y570426D02*
G03X703030Y569849I288J-278D01*
G02X701092Y569774I-930J-1049D01*
G03X701070Y570351I-288J278D01*
G02X703008Y570426I930J1049D01*
G37*
G36*
G01X649000Y567694D02*
G03X648400I-300J-265D01*
G02Y569552I-1050J929D01*
G03X649000I300J265D01*
G02Y567694I1050J-929D01*
G37*
G36*
G01X1603336Y572335D02*
Y568240D01*
X1603327Y568156D01*
G02X1600314Y568325I-1502J169D01*
G01Y572326D01*
G02X1603336Y572335I1511J-1D01*
G37*
G36*
G01X4611Y568271D02*
G03X5189I289J277D01*
G02Y566329I1011J-971D01*
G03X4611I-289J-277D01*
G02Y568271I-1011J971D01*
G37*
G36*
G01X1684289Y571689D02*
X1684290Y571687D01*
X1687186Y566282D01*
X1687187Y566280D01*
G02X1683042Y564059I-2045J-1162D01*
G01X1683041Y564061D01*
X1680145Y569466D01*
X1680144Y569468D01*
G02X1684289Y571689I2045J1162D01*
G37*
G36*
G01X1675423Y571704D02*
X1675424Y571703D01*
X1678336Y566266D01*
X1678337Y566264D01*
G02X1674191Y564044I-2054J-1146D01*
G01X1674190Y564045D01*
X1671278Y569482D01*
X1671277Y569484D01*
G02X1675423Y571704I2054J1146D01*
G37*
G36*
G01X1637045Y571689D02*
X1637046Y571687D01*
X1639942Y566282D01*
X1639943Y566280D01*
G02X1635798Y564059I-2045J-1162D01*
G01X1635797Y564061D01*
X1632901Y569466D01*
X1632900Y569468D01*
G02X1637045Y571689I2045J1162D01*
G37*
G36*
G01X1628179Y571704D02*
X1628180Y571703D01*
X1631092Y566266D01*
X1631093Y566264D01*
G02X1626947Y564044I-2054J-1146D01*
G01X1626946Y564045D01*
X1624034Y569482D01*
X1624033Y569484D01*
G02X1628179Y571704I2054J1146D01*
G37*
G36*
G01X1448234Y562842D02*
G03X1447666I-284J-282D01*
G02Y564958I-1066J1058D01*
G03X1448234I284J282D01*
G02X1450327Y564996I1066J-1058D01*
G03X1450873I273J292D01*
G02X1452966Y564958I1027J-1096D01*
G03X1453534I284J282D01*
G02X1455666I1066J-1058D01*
G03X1456234I284J282D01*
G02Y562842I1066J-1058D01*
G03X1455666I-284J-282D01*
G02X1453534I-1066J1058D01*
G03X1452966I-284J-282D01*
G02X1450873Y562804I-1066J1058D01*
G03X1450327I-273J-292D01*
G02X1448234Y562842I-1027J1096D01*
G37*
G36*
G01X1655911Y562918D02*
G03X1655333Y562646I-187J-354D01*
G02X1653568Y564276I-1373J284D01*
G03X1653794Y564874I-112J384D01*
G02X1655911Y562918I4734J3000D01*
G37*
G36*
G01X1598097Y561256D02*
G03X1597543I-277J-288D01*
G02X1595579Y563258I-973J1010D01*
G03X1595590Y563812I-283J283D01*
G02X1595597Y565723I1030J952D01*
G03X1595593Y566275I-292J274D01*
G02X1597623Y566291I1007J975D01*
G03X1597627Y565739I292J-274D01*
G02X1597714Y565641I-1004J-979D01*
G03X1598026I156J125D01*
G02X1600111Y563772I1093J-878D01*
G03X1600100Y563218I283J-283D01*
G02X1598097Y561256I-1030J-952D01*
G37*
G36*
G01X1469299Y560816D02*
G03X1468752Y560810I-270J-295D01*
G02X1468729Y563003I-1038J1086D01*
G03X1469276Y563009I270J295D01*
G02X1471350Y563010I1038J-1086D01*
G03X1471919Y563027I276J289D01*
G02X1471982Y560916I1099J-1024D01*
G03X1471413Y560899I-276J-289D01*
G02X1469299Y560816I-1099J1024D01*
G37*
G36*
G01X1491088Y560819D02*
G03X1490484Y560798I-293J-273D01*
G02X1490415Y562765I-1168J944D01*
G03X1491019Y562786I293J273D01*
G02X1493372Y562765I1168J-944D01*
G03X1494002I315J246D01*
G02X1496254Y562899I1185J-923D01*
G03X1496828Y562906I284J282D01*
G02X1498949Y562964I1090J-1034D01*
G03X1499499I275J291D01*
G02Y560780I1031J-1092D01*
G03X1498949I-275J-291D01*
G02X1496851Y560815I-1031J1092D01*
G03X1496277Y560808I-284J-282D01*
G02X1494002Y560919I-1090J1034D01*
G03X1493372I-315J-246D01*
G02X1491088Y560819I-1185J923D01*
G37*
G36*
G01X1383118Y561641D02*
G03X1383081Y561073I262J-302D01*
G02X1381114Y561202I-1049J-930D01*
G03X1381151Y561770I-262J302D01*
G02X1383118Y561641I1049J930D01*
G37*
G36*
G01X1739133Y559735D02*
G03X1739297Y559155I335J-218D01*
G02X1737522Y558653I-600J-1267D01*
G03X1737358Y559233I-335J218D01*
G02X1739133Y559735I600J1267D01*
G37*
G36*
G01X1626606Y559210D02*
Y555115D01*
X1626596Y555031D01*
G02X1623582Y555200I-1502J169D01*
G01Y559200D01*
G02X1626606Y559210I1512J0D01*
G37*
G36*
G01X2336Y555456D02*
G03X2345Y554853I267J-298D01*
G02X503Y554827I-906J-1070D01*
G03X494Y555430I-267J298D01*
G02X389Y555529I908J1068D01*
G03X-189I-289J-277D01*
G02Y557471I-1011J971D01*
G03X389I289J277D01*
G02X2336Y555456I1011J-971D01*
G37*
G36*
G01X652611Y551617D02*
G03X651989I-311J-252D01*
G02Y553383I-1089J883D01*
G03X652611I311J252D01*
G02Y551617I1089J-883D01*
G37*
G36*
G01X1663754Y549588D02*
X1658753D01*
G02X1658754Y552412I1J1412D01*
G01X1663754D01*
G02X1665166Y551010I0J-1412D01*
G01Y550916D01*
X1665155Y550832D01*
G02X1663754Y549588I-1401J167D01*
G37*
G36*
G01X1230845Y552303D02*
G03Y551725I277J-289D01*
G02X1228903I-971J-1011D01*
G03Y552303I-277J289D01*
G02X1230845I971J1011D01*
G37*
G36*
G01X1194034D02*
G03Y551725I277J-289D01*
G02X1192092I-971J-1011D01*
G03Y552303I-277J289D01*
G02X1194034I971J1011D01*
G37*
G36*
G01X1157223D02*
G03Y551725I277J-289D01*
G02X1155281I-971J-1011D01*
G03Y552303I-277J289D01*
G02X1157223I971J1011D01*
G37*
G36*
G01X1120411D02*
G03Y551725I277J-289D01*
G02X1118469I-971J-1011D01*
G03Y552303I-277J289D01*
G02X1120411I971J1011D01*
G37*
G36*
G01X939703D02*
G03Y551725I277J-289D01*
G02X937761I-971J-1011D01*
G03Y552303I-277J289D01*
G02X939703I971J1011D01*
G37*
G36*
G01X902892D02*
G03Y551725I277J-289D01*
G02X900950I-971J-1011D01*
G03Y552303I-277J289D01*
G02X902892I971J1011D01*
G37*
G36*
G01X866081D02*
G03Y551725I277J-289D01*
G02X864139I-971J-1011D01*
G03Y552303I-277J289D01*
G02X866081I971J1011D01*
G37*
G36*
G01X829270D02*
G03Y551725I277J-289D01*
G02X827328I-971J-1011D01*
G03Y552303I-277J289D01*
G02X829270I971J1011D01*
G37*
G36*
G01X792459D02*
G03Y551725I277J-289D01*
G02X790517I-971J-1011D01*
G03Y552303I-277J289D01*
G02X792459I971J1011D01*
G37*
G36*
G01X581237D02*
G03Y551725I277J-289D01*
G02X579295I-971J-1011D01*
G03Y552303I-277J289D01*
G02X581237I971J1011D01*
G37*
G36*
G01X544426D02*
G03Y551725I277J-289D01*
G02X542484I-971J-1011D01*
G03Y552303I-277J289D01*
G02X544426I971J1011D01*
G37*
G36*
G01X507615D02*
G03Y551725I277J-289D01*
G02X505673I-971J-1011D01*
G03Y552303I-277J289D01*
G02X507615I971J1011D01*
G37*
G36*
G01X470803D02*
G03Y551725I277J-289D01*
G02X468861I-971J-1011D01*
G03Y552303I-277J289D01*
G02X470803I971J1011D01*
G37*
G36*
G01X290095D02*
G03Y551725I277J-289D01*
G02X288153I-971J-1011D01*
G03Y552303I-277J289D01*
G02X290095I971J1011D01*
G37*
G36*
G01X253284D02*
G03Y551725I277J-289D01*
G02X251342I-971J-1011D01*
G03Y552303I-277J289D01*
G02X253284I971J1011D01*
G37*
G36*
G01X216473D02*
G03Y551725I277J-289D01*
G02X214531I-971J-1011D01*
G03Y552303I-277J289D01*
G02X216473I971J1011D01*
G37*
G36*
G01X179662D02*
G03Y551725I277J-289D01*
G02X177720I-971J-1011D01*
G03Y552303I-277J289D01*
G02X179662I971J1011D01*
G37*
G36*
G01X142851D02*
G03Y551725I277J-289D01*
G02X140909I-971J-1011D01*
G03Y552303I-277J289D01*
G02X142851I971J1011D01*
G37*
G36*
G01X1225745Y552089D02*
G03Y551511I277J-289D01*
G02X1223803I-971J-1011D01*
G03Y552089I-277J289D01*
G02X1225745I971J1011D01*
G37*
G36*
G01X1188934D02*
G03Y551511I277J-289D01*
G02X1186992I-971J-1011D01*
G03Y552089I-277J289D01*
G02X1188934I971J1011D01*
G37*
G36*
G01X1152123D02*
G03Y551511I277J-289D01*
G02X1150181I-971J-1011D01*
G03Y552089I-277J289D01*
G02X1152123I971J1011D01*
G37*
G36*
G01X1115311D02*
G03Y551511I277J-289D01*
G02X1113369I-971J-1011D01*
G03Y552089I-277J289D01*
G02X1115311I971J1011D01*
G37*
G36*
G01X934603D02*
G03Y551511I277J-289D01*
G02X932661I-971J-1011D01*
G03Y552089I-277J289D01*
G02X934603I971J1011D01*
G37*
G36*
G01X897792D02*
G03Y551511I277J-289D01*
G02X895850I-971J-1011D01*
G03Y552089I-277J289D01*
G02X897792I971J1011D01*
G37*
G36*
G01X860981D02*
G03Y551511I277J-289D01*
G02X859039I-971J-1011D01*
G03Y552089I-277J289D01*
G02X860981I971J1011D01*
G37*
G36*
G01X824170D02*
G03Y551511I277J-289D01*
G02X822228I-971J-1011D01*
G03Y552089I-277J289D01*
G02X824170I971J1011D01*
G37*
G36*
G01X787359D02*
G03Y551511I277J-289D01*
G02X785417I-971J-1011D01*
G03Y552089I-277J289D01*
G02X787359I971J1011D01*
G37*
G36*
G01X576137D02*
G03Y551511I277J-289D01*
G02X574195I-971J-1011D01*
G03Y552089I-277J289D01*
G02X576137I971J1011D01*
G37*
G36*
G01X539326D02*
G03Y551511I277J-289D01*
G02X537384I-971J-1011D01*
G03Y552089I-277J289D01*
G02X539326I971J1011D01*
G37*
G36*
G01X502515D02*
G03Y551511I277J-289D01*
G02X500573I-971J-1011D01*
G03Y552089I-277J289D01*
G02X502515I971J1011D01*
G37*
G36*
G01X465703D02*
G03Y551511I277J-289D01*
G02X463761I-971J-1011D01*
G03Y552089I-277J289D01*
G02X465703I971J1011D01*
G37*
G36*
G01X284995D02*
G03Y551511I277J-289D01*
G02X283053I-971J-1011D01*
G03Y552089I-277J289D01*
G02X284995I971J1011D01*
G37*
G36*
G01X248184D02*
G03Y551511I277J-289D01*
G02X246242I-971J-1011D01*
G03Y552089I-277J289D01*
G02X248184I971J1011D01*
G37*
G36*
G01X211373D02*
G03Y551511I277J-289D01*
G02X209431I-971J-1011D01*
G03Y552089I-277J289D01*
G02X211373I971J1011D01*
G37*
G36*
G01X174562D02*
G03Y551511I277J-289D01*
G02X172620I-971J-1011D01*
G03Y552089I-277J289D01*
G02X174562I971J1011D01*
G37*
G36*
G01X137751D02*
G03Y551511I277J-289D01*
G02X135809I-971J-1011D01*
G03Y552089I-277J289D01*
G02X137751I971J1011D01*
G37*
G36*
G01X1685000Y549032D02*
X1679999D01*
G02X1680000Y552056I1J1512D01*
G01X1685000D01*
G02X1686512Y550554I0J-1512D01*
G01Y550459D01*
X1686502Y550375D01*
G02X1685000Y549032I-1502J168D01*
G37*
G36*
G01X1794888Y551715D02*
G03X1794866Y551116I254J-309D01*
G02X1793012Y551185I-966J-1016D01*
G03X1793034Y551784I-254J309D01*
G02X1794888Y551715I966J1016D01*
G37*
G36*
G01X1936731Y551240D02*
G03X1937264Y550995I380J125D01*
G02X1936469Y549260I536J-1295D01*
G03X1935936Y549505I-380J-125D01*
G02X1936731Y551240I-536J1295D01*
G37*
G36*
G01X1739037Y549968D02*
G03X1739065Y549355I270J-295D01*
G02X1737267Y549271I-849J-1116D01*
G03X1737239Y549884I-270J295D01*
G02X1739037Y549968I849J1116D01*
G37*
G36*
G01X1364055Y546944D02*
G03X1363501I-277J-288D01*
G02Y548964I-973J1010D01*
G03X1364055I277J288D01*
G02Y546944I973J-1010D01*
G37*
G36*
G01X1705348Y545122D02*
X1700348D01*
G02Y548144I0J1511D01*
G01X1705348D01*
G02X1706860Y546643I0J-1512D01*
G01Y546548D01*
X1706850Y546464D01*
G02X1705348Y545122I-1502J169D01*
G37*
G36*
G01X1496253Y546907D02*
G03X1496829Y546883I300J265D01*
G02X1496743Y544800I1037J-1086D01*
G03X1496167Y544824I-300J-265D01*
G02X1493945Y544987I-1037J1086D01*
G03X1493315I-315J-246D01*
G02X1490948Y544983I-1185J923D01*
G03X1490356Y545023I-314J-247D01*
G02X1490440Y546948I-976J1007D01*
G03X1491034Y546937I302J262D01*
G02X1493315Y546833I1096J-1027D01*
G03X1493945I315J246D01*
G02X1496253Y546907I1185J-923D01*
G37*
G36*
G01X1439987Y544190D02*
G03X1439915Y543633I247J-315D01*
G02X1437935Y543889I-1116J-848D01*
G03X1438007Y544446I-247J315D01*
G02X1439987Y544190I1116J848D01*
G37*
G36*
G01X1676020Y550027D02*
G03X1676280Y549508I376J-136D01*
G02X1671633Y548350I-1359J-4449D01*
G03X1671350Y549032I-283J282D01*
G01X1669599D01*
G02X1669600Y552056I1J1512D01*
G01X1674600D01*
G02X1676112Y550554I0J-1512D01*
G01Y550459D01*
X1676102Y550375D01*
G02X1676020Y550027I-1502J170D01*
G37*
G36*
G01X1391359Y540723D02*
G03X1391368Y540101I256J-307D01*
G02X1389603Y540077I-868J-1101D01*
G03X1389594Y540699I-256J307D01*
G02X1391359Y540723I868J1101D01*
G37*
G36*
G01X1743894Y534951D02*
G03X1743351I-271J-294D01*
G02Y538631I-1697J1840D01*
G03X1743894I272J294D01*
G02X1747288I1697J-1840D01*
G03X1747831I272J294D01*
G02X1751225I1697J-1840D01*
G03X1751768I271J294D01*
G02X1755162I1697J-1840D01*
G03X1755705I271J294D01*
G02X1759099I1697J-1840D01*
G03X1759642I272J294D01*
G02Y534951I1697J-1840D01*
G03X1759099I-271J-294D01*
G02X1755705I-1697J1840D01*
G03X1755162I-272J-294D01*
G02X1751768I-1697J1840D01*
G03X1751225I-272J-294D01*
G02X1747831I-1697J1840D01*
G03X1747288I-271J-294D01*
G02X1743894I-1697J1840D01*
G37*
G36*
G01X735027Y534190D02*
G03X734473I-277J-288D01*
G02X732490Y536173I-973J1010D01*
G03Y536727I-288J277D01*
G02X734473Y538710I1010J973D01*
G03X735027I277J288D01*
G02X737010Y536727I973J-1010D01*
G03Y536173I288J-277D01*
G02X735027Y534190I-1010J-973D01*
G37*
G36*
G01X1712206Y533780D02*
X1707204D01*
G02X1704820Y534952I0J3011D01*
G03X1704207Y534977I-317J-244D01*
G02X1700203Y534976I-2002J1814D01*
G03X1699590Y534952I-296J-268D01*
G02X1697206Y533780I-2384J1839D01*
G01X1692204D01*
G02X1689820Y534952I0J3011D01*
G03X1689207Y534977I-317J-244D01*
G02Y538605I-2002J1814D01*
G03X1689820Y538630I296J269D01*
G02X1692204Y539802I2384J-1839D01*
G01X1697206D01*
G02X1699590Y538630I0J-3011D01*
G03X1700203Y538606I317J244D01*
G02X1704207Y538605I2002J-1815D01*
G03X1704820Y538630I296J269D01*
G02X1707204Y539802I2384J-1839D01*
G01X1712206D01*
G02X1714590Y538630I0J-3011D01*
G03X1715203Y538606I317J244D01*
G02Y534976I2002J-1815D01*
G03X1714590Y534952I-296J-268D01*
G02X1712206Y533780I-2384J1839D01*
G37*
G36*
G01X1225735Y533378D02*
G03X1225740Y532790I274J-292D01*
G02X1223839Y532771I-940J-1040D01*
G03X1223834Y533359I-274J292D01*
G02X1225735Y533378I940J1040D01*
G37*
G36*
G01X1188924D02*
G03X1188929Y532790I274J-292D01*
G02X1187028Y532771I-940J-1040D01*
G03X1187023Y533359I-274J292D01*
G02X1188924Y533378I940J1040D01*
G37*
G36*
G01X1152113D02*
G03X1152118Y532790I274J-292D01*
G02X1150217Y532771I-940J-1040D01*
G03X1150212Y533359I-274J292D01*
G02X1152113Y533378I940J1040D01*
G37*
G36*
G01X1115301D02*
G03X1115306Y532790I274J-292D01*
G02X1113405Y532771I-940J-1040D01*
G03X1113400Y533359I-274J292D01*
G02X1115301Y533378I940J1040D01*
G37*
G36*
G01X934593D02*
G03X934598Y532790I274J-292D01*
G02X932697Y532771I-940J-1040D01*
G03X932692Y533359I-274J292D01*
G02X934593Y533378I940J1040D01*
G37*
G36*
G01X897782D02*
G03X897787Y532790I274J-292D01*
G02X895886Y532771I-940J-1040D01*
G03X895881Y533359I-274J292D01*
G02X897782Y533378I940J1040D01*
G37*
G36*
G01X860971D02*
G03X860976Y532790I274J-292D01*
G02X859075Y532771I-940J-1040D01*
G03X859070Y533359I-274J292D01*
G02X860971Y533378I940J1040D01*
G37*
G36*
G01X824160D02*
G03X824165Y532790I274J-292D01*
G02X822264Y532771I-940J-1040D01*
G03X822259Y533359I-274J292D01*
G02X824160Y533378I940J1040D01*
G37*
G36*
G01X785453Y532771D02*
G03X785448Y533359I-274J292D01*
G02X787349Y533378I940J1040D01*
G03X787354Y532790I274J-292D01*
G02X785453Y532771I-940J-1040D01*
G37*
G36*
G01X576127Y533378D02*
G03X576132Y532790I274J-292D01*
G02X574231Y532771I-940J-1040D01*
G03X574226Y533359I-274J292D01*
G02X576127Y533378I940J1040D01*
G37*
G36*
G01X539316D02*
G03X539321Y532790I274J-292D01*
G02X537420Y532771I-940J-1040D01*
G03X537415Y533359I-274J292D01*
G02X539316Y533378I940J1040D01*
G37*
G36*
G01X502505D02*
G03X502510Y532790I274J-292D01*
G02X500609Y532771I-940J-1040D01*
G03X500604Y533359I-274J292D01*
G02X502505Y533378I940J1040D01*
G37*
G36*
G01X465693D02*
G03X465698Y532790I274J-292D01*
G02X463797Y532771I-940J-1040D01*
G03X463792Y533359I-274J292D01*
G02X465693Y533378I940J1040D01*
G37*
G36*
G01X284985D02*
G03X284990Y532790I274J-292D01*
G02X283089Y532771I-940J-1040D01*
G03X283084Y533359I-274J292D01*
G02X284985Y533378I940J1040D01*
G37*
G36*
G01X248174D02*
G03X248179Y532790I274J-292D01*
G02X246278Y532771I-940J-1040D01*
G03X246273Y533359I-274J292D01*
G02X248174Y533378I940J1040D01*
G37*
G36*
G01X211363D02*
G03X211368Y532790I274J-292D01*
G02X209467Y532771I-940J-1040D01*
G03X209462Y533359I-274J292D01*
G02X211363Y533378I940J1040D01*
G37*
G36*
G01X174552D02*
G03X174557Y532790I274J-292D01*
G02X172656Y532771I-940J-1040D01*
G03X172651Y533359I-274J292D01*
G02X174552Y533378I940J1040D01*
G37*
G36*
G01X135845Y532771D02*
G03X135840Y533359I-274J292D01*
G02X137741Y533378I940J1040D01*
G03X137746Y532790I274J-292D01*
G02X135845Y532771I-940J-1040D01*
G37*
G36*
G01X1230841Y533134D02*
G03Y532555I276J-290D01*
G02X1228907I-967J-1015D01*
G03Y533134I-276J289D01*
G02X1230841I967J1015D01*
G37*
G36*
G01X1194030D02*
G03Y532555I276J-290D01*
G02X1192096I-967J-1015D01*
G03Y533134I-276J289D01*
G02X1194030I967J1015D01*
G37*
G36*
G01X1157219D02*
G03Y532555I276J-290D01*
G02X1155285I-967J-1015D01*
G03Y533134I-276J289D01*
G02X1157219I967J1015D01*
G37*
G36*
G01X1120407D02*
G03Y532555I276J-290D01*
G02X1118473I-967J-1015D01*
G03Y533134I-276J289D01*
G02X1120407I967J1015D01*
G37*
G36*
G01X939699D02*
G03Y532555I276J-290D01*
G02X937765I-967J-1015D01*
G03Y533134I-276J289D01*
G02X939699I967J1015D01*
G37*
G36*
G01X902888D02*
G03Y532555I276J-290D01*
G02X900954I-967J-1015D01*
G03Y533134I-276J289D01*
G02X902888I967J1015D01*
G37*
G36*
G01X866077D02*
G03Y532555I276J-290D01*
G02X864143I-967J-1015D01*
G03Y533134I-276J289D01*
G02X866077I967J1015D01*
G37*
G36*
G01X829266D02*
G03Y532555I276J-290D01*
G02X827332I-967J-1015D01*
G03Y533134I-276J289D01*
G02X829266I967J1015D01*
G37*
G36*
G01X792455D02*
G03Y532555I276J-290D01*
G02X790521I-967J-1015D01*
G03Y533134I-276J289D01*
G02X792455I967J1015D01*
G37*
G36*
G01X581233D02*
G03Y532555I276J-290D01*
G02X579299I-967J-1015D01*
G03Y533134I-276J289D01*
G02X581233I967J1015D01*
G37*
G36*
G01X544422D02*
G03Y532555I276J-290D01*
G02X542488I-967J-1015D01*
G03Y533134I-276J289D01*
G02X544422I967J1015D01*
G37*
G36*
G01X507611D02*
G03Y532555I276J-290D01*
G02X505677I-967J-1015D01*
G03Y533134I-276J289D01*
G02X507611I967J1015D01*
G37*
G36*
G01X470799D02*
G03Y532555I276J-290D01*
G02X468865I-967J-1015D01*
G03Y533134I-276J289D01*
G02X470799I967J1015D01*
G37*
G36*
G01X290091D02*
G03Y532555I276J-290D01*
G02X288157I-967J-1015D01*
G03Y533134I-276J289D01*
G02X290091I967J1015D01*
G37*
G36*
G01X253280D02*
G03Y532555I276J-290D01*
G02X251346I-967J-1015D01*
G03Y533134I-276J289D01*
G02X253280I967J1015D01*
G37*
G36*
G01X216469D02*
G03Y532555I276J-290D01*
G02X214535I-967J-1015D01*
G03Y533134I-276J289D01*
G02X216469I967J1015D01*
G37*
G36*
G01X179658D02*
G03Y532555I276J-290D01*
G02X177724I-967J-1015D01*
G03Y533134I-276J289D01*
G02X179658I967J1015D01*
G37*
G36*
G01X142847D02*
G03Y532555I276J-290D01*
G02X140913I-967J-1015D01*
G03Y533134I-276J289D01*
G02X142847I967J1015D01*
G37*
G36*
G01X4611Y532271D02*
G03X5189I289J277D01*
G02Y530329I1011J-971D01*
G03X4611I-289J-277D01*
G02Y532271I-1011J971D01*
G37*
G36*
G01X1482727Y530190D02*
G03X1482173I-277J-288D01*
G02Y532210I-973J1010D01*
G03X1482727I277J288D01*
G02Y530190I973J-1010D01*
G37*
G36*
G01X115539Y527414D02*
G03X115435Y526832I214J-338D01*
G02X113575Y527166I-1113J-852D01*
G03X113679Y527748I-214J338D01*
G02X115539Y527414I1113J852D01*
G37*
G36*
G01X1818548Y526492D02*
G03X1818168Y526005I11J-400D01*
G02X1816761Y527101I-1368J-305D01*
G03X1817141Y527588I-11J400D01*
G02X1818548Y526492I1368J305D01*
G37*
G36*
G01X1638728Y528723D02*
G03X1638940Y528154I350J-194D01*
G02X1636593Y527726I-810J-2208D01*
G03X1636591Y528333I-261J303D01*
G02X1638728Y528723I909J1067D01*
G37*
G36*
G01X1785026Y521592D02*
G03X1784449Y521570I-278J-288D01*
G02X1782379Y521539I-1049J930D01*
G03X1781811Y521552I-290J-275D01*
G02X1781859Y523523I-973J1010D01*
G03X1782427Y523510I290J275D01*
G02X1784374Y523508I972J-1010D01*
G03X1784951Y523530I278J288D01*
G02X1785026Y521592I1049J-930D01*
G37*
G36*
G01X702144Y523214D02*
G03X702156Y522612I270J-296D01*
G02X700311Y522574I-901J-1074D01*
G03X700299Y523176I-270J296D01*
G02X702144Y523214I901J1074D01*
G37*
G36*
G01X1629183Y519602D02*
G03X1628572Y519538I-279J-287D01*
G02X1628383Y521324I-1165J780D01*
G03X1628994Y521388I279J287D01*
G02X1629183Y519602I1165J-780D01*
G37*
G36*
G01X1698850Y519221D02*
G03X1698272I-289J-277D01*
G02Y521163I-1011J971D01*
G03X1698850I289J277D01*
G02Y519221I1011J-971D01*
G37*
G36*
G01X1790804Y521062D02*
G03X1790594Y520541I159J-367D01*
G02X1788746Y521288I-1294J-541D01*
G03X1788956Y521809I-159J367D01*
G02X1790804Y521062I1294J541D01*
G37*
G36*
G01X1377636Y518921D02*
G03X1377082I-277J-288D01*
G02X1375031Y519035I-973J1010D01*
G03X1374417Y519037I-308J-256D01*
G02X1374423Y520836I-1072J903D01*
G03X1375037Y520834I308J256D01*
G02X1377082Y520941I1073J-903D01*
G03X1377636I277J288D01*
G02X1379572Y520950I973J-1010D01*
G03X1380124Y520952I275J290D01*
G02X1382173Y520836I970J-1012D01*
G03X1382787Y520834I308J256D01*
G02X1384832Y520941I1073J-903D01*
G03X1385386I277J288D01*
G02Y518921I973J-1010D01*
G03X1384832I-277J-288D01*
G02X1382781Y519035I-973J1010D01*
G03X1382167Y519037I-308J-256D01*
G02X1380132Y518921I-1072J903D01*
G03X1379580Y518919I-275J-290D01*
G02X1377636Y518921I-971J1012D01*
G37*
G36*
G01X1492700Y518498D02*
X1490099D01*
G02X1490100Y521502I1J1502D01*
G01X1492700D01*
G02X1494202Y520010I0J-1502D01*
G01Y519915D01*
X1494192Y519831D01*
G02X1492700Y518498I-1492J168D01*
G37*
G36*
G01X753910Y520148D02*
G03Y519594I288J-277D01*
G02X751890I-1010J-973D01*
G03Y520148I-288J277D01*
G02X753910I1010J973D01*
G37*
G36*
G01X1510005Y516654D02*
X1507404D01*
G02X1507405Y519656I1J1501D01*
G01X1510005D01*
G02X1511506Y518165I0J-1501D01*
G01Y518070D01*
X1511497Y517986D01*
G02X1510005Y516654I-1492J169D01*
G37*
G36*
G01X53987Y525432D02*
G03X54513I263J302D01*
G02X56487I987J-1132D01*
G03X57013I263J302D01*
G02X59132Y523313I987J-1132D01*
G03Y522787I302J-263D01*
G02X59075Y520751I-1132J-987D01*
G03X59061Y520207I286J-280D01*
G02X56933Y518094I-1125J-995D01*
G03X56420Y518113I-268J-297D01*
G02X54397Y518281I-920J1187D01*
G03X54103I-147J-136D01*
G02X54037Y518214I-1102J1020D01*
G03X54036Y517925I138J-145D01*
G02X51848Y517819I-1044J-1079D01*
G03X51849Y518335I-305J259D01*
G02X51868Y520287I1151J965D01*
G03Y520813I-302J263D01*
G02Y522787I1132J987D01*
G03Y523313I-302J263D01*
G02X53987Y525432I1132J987D01*
G37*
G36*
G01X1498054Y517624D02*
X1500655D01*
G02X1502156Y516132I-1J-1502D01*
G01Y516037D01*
X1502147Y515953D01*
G02X1500655Y514620I-1492J169D01*
G01X1498054D01*
G02Y517624I0J1502D01*
G37*
G36*
G01X1483227Y514690D02*
G03X1482673I-277J-288D01*
G02Y516710I-973J1010D01*
G03X1483227I277J288D01*
G02Y514690I973J-1010D01*
G37*
G36*
G01X63468Y516587D02*
G03Y517113I-302J263D01*
G02X63617Y519235I1132J987D01*
G03X63596Y519857I-262J303D01*
G02X63343Y522008I907J1197D01*
G03X63317Y522545I-309J254D01*
G02X63282Y524631I1063J1061D01*
G03Y525177I-292J273D01*
G02X65087Y527527I1098J1025D01*
G03X65604Y527653I188J353D01*
G02X67972Y525813I1237J-852D01*
G03Y525287I302J-263D01*
G02X67864Y523201I-1132J-987D01*
G03X67853Y522919I136J-147D01*
G02X67882Y520913I-1103J-1019D01*
G03Y520387I302J-263D01*
G02Y518413I-1132J-987D01*
G03Y517887I302J-263D01*
G02X66485Y515422I-1132J-987D01*
G03X66032Y515148I-71J-394D01*
G02X63468Y516587I-1432J452D01*
G37*
G36*
G01X1314671Y516789D02*
G03Y516211I277J-289D01*
G02X1312729I-971J-1011D01*
G03Y516789I-277J289D01*
G02X1314671I971J1011D01*
G37*
G36*
G01X1230845Y514503D02*
G03Y513925I277J-289D01*
G02X1228903I-971J-1011D01*
G03Y514503I-277J289D01*
G02X1230845I971J1011D01*
G37*
G36*
G01X1194034D02*
G03Y513925I277J-289D01*
G02X1192092I-971J-1011D01*
G03Y514503I-277J289D01*
G02X1194034I971J1011D01*
G37*
G36*
G01X1157223D02*
G03Y513925I277J-289D01*
G02X1155281I-971J-1011D01*
G03Y514503I-277J289D01*
G02X1157223I971J1011D01*
G37*
G36*
G01X1120411D02*
G03Y513925I277J-289D01*
G02X1118469I-971J-1011D01*
G03Y514503I-277J289D01*
G02X1120411I971J1011D01*
G37*
G36*
G01X939703D02*
G03Y513925I277J-289D01*
G02X937761I-971J-1011D01*
G03Y514503I-277J289D01*
G02X939703I971J1011D01*
G37*
G36*
G01X902892D02*
G03Y513925I277J-289D01*
G02X900950I-971J-1011D01*
G03Y514503I-277J289D01*
G02X902892I971J1011D01*
G37*
G36*
G01X866081D02*
G03Y513925I277J-289D01*
G02X864139I-971J-1011D01*
G03Y514503I-277J289D01*
G02X866081I971J1011D01*
G37*
G36*
G01X829270D02*
G03Y513925I277J-289D01*
G02X827328I-971J-1011D01*
G03Y514503I-277J289D01*
G02X829270I971J1011D01*
G37*
G36*
G01X792459D02*
G03Y513925I277J-289D01*
G02X790517I-971J-1011D01*
G03Y514503I-277J289D01*
G02X792459I971J1011D01*
G37*
G36*
G01X581237D02*
G03Y513925I277J-289D01*
G02X579295I-971J-1011D01*
G03Y514503I-277J289D01*
G02X581237I971J1011D01*
G37*
G36*
G01X544426D02*
G03Y513925I277J-289D01*
G02X542484I-971J-1011D01*
G03Y514503I-277J289D01*
G02X544426I971J1011D01*
G37*
G36*
G01X507615D02*
G03Y513925I277J-289D01*
G02X505673I-971J-1011D01*
G03Y514503I-277J289D01*
G02X507615I971J1011D01*
G37*
G36*
G01X470803D02*
G03Y513925I277J-289D01*
G02X468861I-971J-1011D01*
G03Y514503I-277J289D01*
G02X470803I971J1011D01*
G37*
G36*
G01X290095D02*
G03Y513925I277J-289D01*
G02X288153I-971J-1011D01*
G03Y514503I-277J289D01*
G02X290095I971J1011D01*
G37*
G36*
G01X253284D02*
G03Y513925I277J-289D01*
G02X251342I-971J-1011D01*
G03Y514503I-277J289D01*
G02X253284I971J1011D01*
G37*
G36*
G01X216473D02*
G03Y513925I277J-289D01*
G02X214531I-971J-1011D01*
G03Y514503I-277J289D01*
G02X216473I971J1011D01*
G37*
G36*
G01X179662D02*
G03Y513925I277J-289D01*
G02X177720I-971J-1011D01*
G03Y514503I-277J289D01*
G02X179662I971J1011D01*
G37*
G36*
G01X142851D02*
G03Y513925I277J-289D01*
G02X140909I-971J-1011D01*
G03Y514503I-277J289D01*
G02X142851I971J1011D01*
G37*
G36*
G01X1225745Y514289D02*
G03Y513711I277J-289D01*
G02X1223803I-971J-1011D01*
G03Y514289I-277J289D01*
G02X1225745I971J1011D01*
G37*
G36*
G01X1188934D02*
G03Y513711I277J-289D01*
G02X1186992I-971J-1011D01*
G03Y514289I-277J289D01*
G02X1188934I971J1011D01*
G37*
G36*
G01X1152123D02*
G03Y513711I277J-289D01*
G02X1150181I-971J-1011D01*
G03Y514289I-277J289D01*
G02X1152123I971J1011D01*
G37*
G36*
G01X1115311D02*
G03Y513711I277J-289D01*
G02X1113369I-971J-1011D01*
G03Y514289I-277J289D01*
G02X1115311I971J1011D01*
G37*
G36*
G01X934603D02*
G03Y513711I277J-289D01*
G02X932661I-971J-1011D01*
G03Y514289I-277J289D01*
G02X934603I971J1011D01*
G37*
G36*
G01X897792D02*
G03Y513711I277J-289D01*
G02X895850I-971J-1011D01*
G03Y514289I-277J289D01*
G02X897792I971J1011D01*
G37*
G36*
G01X860981D02*
G03Y513711I277J-289D01*
G02X859039I-971J-1011D01*
G03Y514289I-277J289D01*
G02X860981I971J1011D01*
G37*
G36*
G01X824170D02*
G03Y513711I277J-289D01*
G02X822228I-971J-1011D01*
G03Y514289I-277J289D01*
G02X824170I971J1011D01*
G37*
G36*
G01X787359D02*
G03Y513711I277J-289D01*
G02X785417I-971J-1011D01*
G03Y514289I-277J289D01*
G02X787359I971J1011D01*
G37*
G36*
G01X576137D02*
G03Y513711I277J-289D01*
G02X574195I-971J-1011D01*
G03Y514289I-277J289D01*
G02X576137I971J1011D01*
G37*
G36*
G01X539326D02*
G03Y513711I277J-289D01*
G02X537384I-971J-1011D01*
G03Y514289I-277J289D01*
G02X539326I971J1011D01*
G37*
G36*
G01X502515D02*
G03Y513711I277J-289D01*
G02X500573I-971J-1011D01*
G03Y514289I-277J289D01*
G02X502515I971J1011D01*
G37*
G36*
G01X465703D02*
G03Y513711I277J-289D01*
G02X463761I-971J-1011D01*
G03Y514289I-277J289D01*
G02X465703I971J1011D01*
G37*
G36*
G01X284995D02*
G03Y513711I277J-289D01*
G02X283053I-971J-1011D01*
G03Y514289I-277J289D01*
G02X284995I971J1011D01*
G37*
G36*
G01X248184D02*
G03Y513711I277J-289D01*
G02X246242I-971J-1011D01*
G03Y514289I-277J289D01*
G02X248184I971J1011D01*
G37*
G36*
G01X211373D02*
G03Y513711I277J-289D01*
G02X209431I-971J-1011D01*
G03Y514289I-277J289D01*
G02X211373I971J1011D01*
G37*
G36*
G01X174562D02*
G03Y513711I277J-289D01*
G02X172620I-971J-1011D01*
G03Y514289I-277J289D01*
G02X174562I971J1011D01*
G37*
G36*
G01X137751D02*
G03Y513711I277J-289D01*
G02X135809I-971J-1011D01*
G03Y514289I-277J289D01*
G02X137751I971J1011D01*
G37*
G36*
G01X1775235Y513745D02*
G03X1775789Y513710I295J270D01*
G02X1775660Y511695I906J-1070D01*
G03X1775106Y511730I-295J-270D01*
G02X1775235Y513745I-906J1070D01*
G37*
G36*
G01X1460011Y514043D02*
G03X1459949Y513438I227J-329D01*
G02X1458137Y513623I-1014J-968D01*
G03X1458199Y514228I-227J329D01*
G02X1460186Y516206I1014J968D01*
G03X1460740I277J288D01*
G02Y514186I973J-1010D01*
G03X1460186I-277J-288D01*
G02X1460011Y514043I-972J1011D01*
G37*
G36*
G01X730626Y510592D02*
G03X730049Y510570I-278J-288D01*
G02X729974Y512508I-1049J930D01*
G03X730551Y512530I278J288D01*
G02X730626Y510592I1049J-930D01*
G37*
G36*
G01X1509586Y509144D02*
X1506984D01*
G02X1506985Y512146I1J1501D01*
G01X1509586D01*
G02X1510889Y511390I0J-1501D01*
G02X1511086Y510655I-1304J-744D01*
G01Y510653D01*
X1511087Y510652D01*
G02X1509586Y509144I-1501J-7D01*
G37*
G36*
G01X1614027Y509290D02*
G03X1613473I-277J-288D01*
G02Y511310I-973J1010D01*
G03X1614027I277J288D01*
G02Y509290I973J-1010D01*
G37*
G36*
G01X1549271Y510789D02*
G03Y510211I277J-289D01*
G02X1547329I-971J-1011D01*
G03Y510789I-277J289D01*
G02X1549271I971J1011D01*
G37*
G36*
G01X721845Y510766D02*
G03X722033Y510244I365J-163D01*
G02X720134Y509558I-619J-1258D01*
G03X719946Y510080I-365J163D01*
G02X721845Y510766I619J1258D01*
G37*
G36*
G01X1500877Y506738D02*
X1498276D01*
G02X1498277Y509740I1J1501D01*
G01X1500877D01*
G02X1502378Y508249I0J-1501D01*
G01Y508154D01*
X1502369Y508070D01*
G02X1500877Y506738I-1492J169D01*
G37*
G36*
G01X1485692Y509502D02*
X1488293D01*
G02X1489794Y508010I0J-1501D01*
G01Y507915D01*
X1489785Y507831D01*
G02X1488293Y506498I-1492J168D01*
G01X1485692D01*
G02Y509502I0J1502D01*
G37*
G36*
G01X1481975Y506474D02*
X1479374D01*
G02X1479375Y509476I1J1501D01*
G01X1481975D01*
G02X1483476Y507985I0J-1501D01*
G01Y507890D01*
X1483467Y507806D01*
G02X1481975Y506474I-1492J169D01*
G37*
G36*
G01X115452Y509327D02*
G03Y508773I288J-277D01*
G02X113432I-1010J-973D01*
G03Y509327I-288J277D01*
G02X115452I1010J973D01*
G37*
G36*
G01X1844304Y507840D02*
G03X1843851Y507461I-54J-396D01*
G02X1842636Y508910I-1401J59D01*
G03X1843089Y509289I54J396D01*
G02X1844304Y507840I1401J-59D01*
G37*
G36*
G01X34223Y509289D02*
G03X34058Y509518I-197J32D01*
G02X33490Y509735I241J1482D01*
G03X32964Y509651I-216J-337D01*
G02X32610Y511865I-1164J949D01*
G03X33136Y511949I216J337D01*
G02X35288Y512131I1164J-949D01*
G03X35856Y512173I263J301D01*
G02X38495Y511340I1144J-973D01*
G03X38958Y510982I399J37D01*
G02X39428Y508015I241J-1483D01*
G03X39092Y507574I61J-395D01*
G02X36111Y507205I-1492J-174D01*
G03X35713Y507553I-397J-52D01*
G02X34223Y509289I-6J1502D01*
G37*
G36*
G01X1556448Y508744D02*
G03Y508190I288J-277D01*
G02X1554428I-1010J-973D01*
G03Y508744I-288J277D01*
G02X1556448I1010J973D01*
G37*
G36*
G01X1543446Y508589D02*
G03Y508011I277J-289D01*
G02X1541504I-971J-1011D01*
G03Y508589I-277J289D01*
G02X1543446I971J1011D01*
G37*
G36*
G01X764960Y507567D02*
G03Y507013I288J-277D01*
G02X762940I-1010J-973D01*
G03Y507567I-288J277D01*
G02Y509513I1010J973D01*
G03Y510067I-288J277D01*
G02X764960I1010J973D01*
G03Y509513I288J-277D01*
G02Y507567I-1010J-973D01*
G37*
G36*
G01X703409Y505754D02*
G03X702898Y505399I-112J-384D01*
G02X701891Y506846I-1398J101D01*
G03X702402Y507201I112J384D01*
G02X703409Y505754I1398J-101D01*
G37*
G36*
G01X712207Y504510D02*
G03X711639I-284J-282D01*
G02X709492Y504695I-997J986D01*
G03X708872Y504741I-329J-228D01*
G02X709001Y506501I-1022J960D01*
G03X709621Y506455I329J228D01*
G02X711636Y506486I1022J-959D01*
G03X712204I284J282D01*
G02X714199Y506484I997J-986D01*
G03X714798Y506517I285J280D01*
G02X714901Y504666I1102J-867D01*
G03X714302Y504633I-285J-280D01*
G02X712207Y504510I-1102J867D01*
G37*
G36*
G01X1650037Y503846D02*
G03X1649482Y503744I-226J-330D01*
G02X1648998Y505777I-1152J800D01*
G03X1649539Y505936I191J351D01*
G02X1650037Y503846I1405J-770D01*
G37*
G36*
G01X1568662Y504677D02*
G03X1569135Y505096I74J393D01*
G02X1570261Y502751I3463J220D01*
G03X1569638Y502643I-270J-296D01*
G02X1568662Y504677I-1238J657D01*
G37*
G36*
G01X1508625Y504540D02*
X1511126D01*
G02X1512628Y503048I0J-1502D01*
G01Y503038D01*
G02X1511126Y501536I-1502J0D01*
G01X1508625D01*
G02Y504540I0J1502D01*
G37*
G36*
G01X1549310Y503027D02*
G03Y502473I288J-277D01*
G02X1547290I-1010J-973D01*
G03Y503027I-288J277D01*
G02X1549310I1010J973D01*
G37*
G36*
G01X1528002Y503810D02*
Y501300D01*
G02X1524998I-1502J0D01*
G01Y503801D01*
G02X1528002Y503810I1502J-1D01*
G37*
G36*
G01X675626Y500292D02*
G03X675049Y500270I-278J-288D01*
G02X672987Y500231I-1049J930D01*
G03X672432Y500253I-289J-277D01*
G02X672513Y502269I-932J1047D01*
G03X673068Y502247I289J277D01*
G02X674974Y502208I932J-1047D01*
G03X675551Y502230I278J288D01*
G02X675626Y500292I1049J-930D01*
G37*
G36*
G01X1738703Y502186D02*
G03X1738508Y501612I149J-371D01*
G02X1736777Y502201I-1208J-712D01*
G03X1736972Y502775I-149J371D01*
G02X1738703Y502186I1208J712D01*
G37*
G36*
G01X1874950Y501383D02*
G03X1875469Y501146I376J136D01*
G02X1874655Y499359I504J-1308D01*
G03X1874136Y499596I-376J-136D01*
G02X1874950Y501383I-504J1308D01*
G37*
G36*
G01X648006Y500173D02*
G03X647601Y499757I-5J-400D01*
G02X646219Y501102I-1401J-57D01*
G03X646624Y501518I5J400D01*
G02X648006Y500173I1401J57D01*
G37*
G36*
G01X1269329Y500380D02*
G03X1268968Y499918I34J-398D01*
G02X1267464Y501091I-1384J-224D01*
G03X1267825Y501553I-34J398D01*
G02X1269329Y500380I1384J224D01*
G37*
G36*
G01X745051Y498664D02*
G03X744497I-277J-288D01*
G02X742514Y500647I-973J1010D01*
G03Y501201I-288J277D01*
G02X744497Y503184I1010J973D01*
G03X745051I277J288D01*
G02X746997I973J-1010D01*
G03X747551I277J288D01*
G02X749401Y501080I973J-1010D01*
G03Y500768I125J-156D01*
G02X749485Y500695I-877J-1094D01*
G03X749786Y500725I138J145D01*
G02X750099Y498788I1145J-809D01*
G03X749564Y498734I-238J-322D01*
G02X747551Y498664I-1040J940D01*
G03X746997I-277J-288D01*
G02X745051I-973J1010D01*
G37*
G36*
G01X1532695Y501067D02*
G03Y500513I288J-277D01*
G02X1530675I-1010J-973D01*
G03Y501067I-288J277D01*
G02X1532695I1010J973D01*
G37*
G36*
G01X1556520Y501002D02*
G03Y500448I288J-277D01*
G02X1554500I-1010J-973D01*
G03Y501002I-288J277D01*
G02X1556520I1010J973D01*
G37*
G36*
G01X1543485Y500927D02*
G03Y500373I288J-277D01*
G02X1541465I-1010J-973D01*
G03Y500927I-288J277D01*
G02X1543485I1010J973D01*
G37*
G36*
G01X710341Y498494D02*
G03X709755Y498476I-285J-281D01*
G02X709698Y500384I-1055J923D01*
G03X710284Y500402I285J281D01*
G02X710341Y498494I1055J-923D01*
G37*
G36*
G01X1336011Y498417D02*
G03X1335389I-311J-252D01*
G02Y500183I-1089J883D01*
G03X1336011I311J252D01*
G02Y498417I1089J-883D01*
G37*
G36*
G01X1705601Y500560D02*
G03X1705612Y499982I282J-284D01*
G02X1703453Y497902I-1015J-1107D01*
G03X1702908Y497962I-304J-259D01*
G02X1700871Y500148I-904J1200D01*
G03X1700844Y500702I-301J263D01*
G02X1702995Y502794I1030J1093D01*
G03X1703557Y502759I299J266D01*
G02X1705601Y500560I986J-1133D01*
G37*
G36*
G01X-17651Y498430D02*
G03X-17666Y499031I-271J294D01*
G02X-15815Y499076I900J1075D01*
G03X-15800Y498475I271J-294D01*
G02X-17651Y498430I-900J-1075D01*
G37*
G36*
G01X1673481Y498725D02*
G03X1673416Y498165I250J-313D01*
G02X1671438Y498395I-1103J-865D01*
G03X1671503Y498955I-250J313D01*
G02X1673481Y498725I1103J865D01*
G37*
G36*
G01X113060Y499007D02*
G03X113164Y498418I314J-248D01*
G02X111328Y498095I-737J-1193D01*
G03X111224Y498684I-314J248D01*
G02X113060Y499007I737J1193D01*
G37*
G36*
G01X1758575Y494894D02*
X1753575D01*
G02Y497918I0J1512D01*
G01X1758575D01*
G02X1760086Y496416I-1J-1512D01*
G01Y496321D01*
X1760077Y496237D01*
G02X1758575Y494894I-1502J169D01*
G37*
G36*
G01X1748125Y494888D02*
X1743124D01*
G02X1743125Y497912I1J1512D01*
G01X1748125D01*
G02X1749636Y496410I-1J-1512D01*
G01Y496315D01*
X1749627Y496231D01*
G02X1748125Y494888I-1502J168D01*
G37*
G36*
G01X1157223Y495156D02*
G03Y494578I277J-289D01*
G02X1155281I-971J-1011D01*
G03Y495156I-277J289D01*
G02X1157223I971J1011D01*
G37*
G36*
G01X507615D02*
G03Y494578I277J-289D01*
G02X505673I-971J-1011D01*
G03Y495156I-277J289D01*
G02X507615I971J1011D01*
G37*
G36*
G01X1193992Y495159D02*
G03Y494559I265J-300D01*
G02X1192134I-929J-1050D01*
G03Y495159I-265J300D01*
G02X1193992I929J1050D01*
G37*
G36*
G01X544384D02*
G03Y494559I265J-300D01*
G02X542526I-929J-1050D01*
G03Y495159I-265J300D01*
G02X544384I929J1050D01*
G37*
G36*
G01X1152097Y495117D02*
G03Y494517I265J-300D01*
G02X1150239I-929J-1050D01*
G03Y495117I-265J300D01*
G02X1152097I929J1050D01*
G37*
G36*
G01X502489D02*
G03Y494517I265J-300D01*
G02X500631I-929J-1050D01*
G03Y495117I-265J300D01*
G02X502489I929J1050D01*
G37*
G36*
G01X939703Y494933D02*
G03Y494355I277J-289D01*
G02X937761I-971J-1011D01*
G03Y494933I-277J289D01*
G02X939703I971J1011D01*
G37*
G36*
G01X934618D02*
G03Y494355I277J-289D01*
G02X932676I-971J-1011D01*
G03Y494933I-277J289D01*
G02X934618I971J1011D01*
G37*
G36*
G01X290095D02*
G03Y494355I277J-289D01*
G02X288153I-971J-1011D01*
G03Y494933I-277J289D01*
G02X290095I971J1011D01*
G37*
G36*
G01X285010D02*
G03Y494355I277J-289D01*
G02X283068I-971J-1011D01*
G03Y494933I-277J289D01*
G02X285010I971J1011D01*
G37*
G36*
G01X902892Y494803D02*
G03Y494225I277J-289D01*
G02X900950I-971J-1011D01*
G03Y494803I-277J289D01*
G02X902892I971J1011D01*
G37*
G36*
G01X253284D02*
G03Y494225I277J-289D01*
G02X251342I-971J-1011D01*
G03Y494803I-277J289D01*
G02X253284I971J1011D01*
G37*
G36*
G01X1188907Y494859D02*
G03Y494259I265J-300D01*
G02X1187049I-929J-1050D01*
G03Y494859I-265J300D01*
G02X1188907I929J1050D01*
G37*
G36*
G01X897765D02*
G03Y494259I265J-300D01*
G02X895907I-929J-1050D01*
G03Y494859I-265J300D01*
G02X897765I929J1050D01*
G37*
G36*
G01X539299D02*
G03Y494259I265J-300D01*
G02X537441I-929J-1050D01*
G03Y494859I-265J300D01*
G02X539299I929J1050D01*
G37*
G36*
G01X248157D02*
G03Y494259I265J-300D01*
G02X246299I-929J-1050D01*
G03Y494859I-265J300D01*
G02X248157I929J1050D01*
G37*
G36*
G01X1296341Y494226D02*
G03X1296927Y494180I314J248D01*
G02X1296777Y492283I951J-1030D01*
G03X1296191Y492329I-314J-248D01*
G02X1296341Y494226I-951J1030D01*
G37*
G36*
G01X694614Y493330D02*
G03Y492776I288J-277D01*
G02X692594I-1010J-973D01*
G03Y493330I-288J277D01*
G02X694614I1010J973D01*
G37*
G36*
G01X690835Y493282D02*
G03Y492728I288J-277D01*
G02X688815I-1010J-973D01*
G03Y493282I-288J277D01*
G02X690835I1010J973D01*
G37*
G36*
G01X88867Y500506D02*
G03X89413I273J292D01*
G02X91467I1027J-1096D01*
G03X92013I273J292D01*
G02X94067I1027J-1096D01*
G03X94613I273J292D01*
G02X96667I1027J-1096D01*
G03X97213I273J292D01*
G02X99336Y498383I1027J-1096D01*
G03Y497837I292J-273D01*
G02X97093Y495841I-1096J-1027D01*
G03X96787I-153J-130D01*
G02X96668Y495715I-1150J966D01*
G03X96684Y495410I137J-146D01*
G02X94678Y493190I-907J-1197D01*
G03X94092Y493189I-293J-273D01*
G02X91963Y493114I-1102J1021D01*
G03X91417I-273J-292D01*
G02X91359Y493063I-1020J1102D01*
G03Y492757I130J-153D01*
G02X89363Y490514I-969J-1147D01*
G03X88817I-273J-292D01*
G02X86694Y492637I-1027J1096D01*
G03Y493183I-292J273D01*
G02X86714Y495258I1096J1027D01*
G03X86724Y495804I-287J278D01*
G02X86744Y497837I1116J1006D01*
G03Y498383I-292J273D01*
G02X88867Y500506I1096J1027D01*
G37*
G36*
G01X1842089Y490529D02*
G03X1841511I-289J-277D01*
G02X1839529Y492511I-1011J971D01*
G03Y493089I-277J289D01*
G02X1841511Y495071I971J1011D01*
G03X1842089I289J277D01*
G02X1844071Y493089I1011J-971D01*
G03Y492511I277J-289D01*
G02X1842089Y490529I-971J-1011D01*
G37*
G36*
G01X1249880Y490086D02*
G03X1249721Y489554I196J-348D01*
G02X1247787Y490135I-1247J-641D01*
G03X1247946Y490667I-196J348D01*
G02X1249880Y490086I1247J641D01*
G37*
G36*
G01X1819124Y490442D02*
X1824125D01*
G02X1825636Y488940I-1J-1512D01*
G01Y488845D01*
X1825627Y488761D01*
G02X1824125Y487418I-1502J169D01*
G01X1819124D01*
G02Y490442I0J1512D01*
G37*
G36*
G01X1796124D02*
X1801125D01*
G02X1802636Y488940I-1J-1512D01*
G01Y488845D01*
X1802627Y488761D01*
G02X1801125Y487418I-1502J169D01*
G01X1796124D01*
G02Y490442I0J1512D01*
G37*
G36*
G01X1784524D02*
X1789525D01*
G02X1791036Y488940I-1J-1512D01*
G01Y488845D01*
X1791027Y488761D01*
G02X1789525Y487418I-1502J169D01*
G01X1784524D01*
G02Y490442I0J1512D01*
G37*
G36*
G01X1811975Y487218D02*
X1806975D01*
G02Y490242I0J1512D01*
G01X1811975D01*
G02X1813486Y488740I-1J-1512D01*
G01Y488645D01*
X1813477Y488561D01*
G02X1811975Y487218I-1502J169D01*
G37*
G36*
G01X1754300Y486344D02*
X1749299D01*
G02X1749300Y489366I1J1511D01*
G01X1754300D01*
G02X1755812Y487865I0J-1512D01*
G01Y487770D01*
X1755802Y487686D01*
G02X1754300Y486344I-1502J170D01*
G37*
G36*
G01X1741900Y486244D02*
X1736899D01*
G02X1736900Y489266I1J1511D01*
G01X1741900D01*
G02X1743412Y487765I0J-1512D01*
G01Y487670D01*
X1743402Y487586D01*
G02X1741900Y486244I-1502J170D01*
G37*
G36*
G01X1770325Y485844D02*
X1765324D01*
G02X1765325Y488866I1J1511D01*
G01X1770325D01*
G02X1771836Y487365I0J-1511D01*
G01Y487270D01*
X1771827Y487186D01*
G02X1770325Y485844I-1502J169D01*
G37*
G36*
G01X1450607Y488218D02*
G03X1451188Y488206I296J268D01*
G02X1451149Y486281I1000J-983D01*
G03X1450568Y486293I-296J-268D01*
G02X1450607Y488218I-1000J983D01*
G37*
G36*
G01X721807Y486893D02*
G03X721585Y486360I145J-373D01*
G02X719794Y487107I-1285J-560D01*
G03X720016Y487640I-145J373D01*
G02X721934Y489451I1285J560D01*
G03X722487Y489661I181J357D01*
G02X723159Y487897I1305J-513D01*
G03X722606Y487687I-181J-357D01*
G02X721807Y486893I-1304J514D01*
G37*
G36*
G01X676752Y484669D02*
G03X676148Y484662I-299J-266D01*
G02X676128Y486501I-1068J908D01*
G03X676732Y486508I299J266D01*
G02X678732Y486647I1068J-908D01*
G03X679287Y486669I266J299D01*
G02X679368Y484653I1013J-969D01*
G03X678813Y484631I-266J-299D01*
G02X676752Y484669I-1013J969D01*
G37*
G36*
G01X1841471Y486239D02*
G03Y485661I277J-289D01*
G02X1839529I-971J-1011D01*
G03Y486239I-277J289D01*
G02X1841471I971J1011D01*
G37*
G36*
G01X610478Y485035D02*
G03X611039Y485021I288J278D01*
G02X610992Y483025I961J-1021D01*
G03X610431Y483039I-288J-278D01*
G02X610478Y485035I-961J1021D01*
G37*
G36*
G01X709168Y482570D02*
G03X708585Y482538I-277J-289D01*
G02X708480Y484452I-1074J901D01*
G03X709063Y484484I277J289D01*
G02X709168Y482570I1074J-901D01*
G37*
G36*
G01X1652882Y483774D02*
G03X1652896Y483210I290J-275D01*
G02X1650911Y483164I-970J-1013D01*
G03X1650897Y483728I-290J275D01*
G02X1652882Y483774I970J1013D01*
G37*
G36*
G01X1616627Y480390D02*
G03X1616073I-277J-288D01*
G02Y482410I-973J1010D01*
G03X1616627I277J288D01*
G02Y480390I973J-1010D01*
G37*
G36*
G01X1672021Y482589D02*
G03Y482011I277J-289D01*
G02X1670079I-971J-1011D01*
G03Y482589I-277J289D01*
G02X1672021I971J1011D01*
G37*
G36*
G01X606268Y482376D02*
G03X606278Y481843I303J-261D01*
G02X604187Y481806I-1029J-952D01*
G03X604177Y482339I-303J261D01*
G02X606268Y482376I1029J952D01*
G37*
G36*
G01X1291510Y481727D02*
G03Y481173I288J-277D01*
G02X1289490I-1010J-973D01*
G03Y481727I-288J277D01*
G02X1291510I1010J973D01*
G37*
G36*
G01X1794975Y477788D02*
X1789974D01*
G02X1789975Y480812I1J1512D01*
G01X1794975D01*
G02X1796486Y479310I-1J-1512D01*
G01Y479215D01*
X1796477Y479131D01*
G02X1794975Y477788I-1502J168D01*
G37*
G36*
G01X658794Y478143D02*
G03X658229Y478136I-279J-287D01*
G02X658203Y480122I-1002J980D01*
G03X658768Y480129I279J287D01*
G02X660708Y480191I1002J-980D01*
G03X661243I267J297D01*
G02Y478107I938J-1042D01*
G03X660708I-268J-297D01*
G02X658794Y478143I-938J1042D01*
G37*
G36*
G01X1817375Y476808D02*
X1812375D01*
G02Y479832I0J1512D01*
G01X1817375D01*
G02X1818886Y478330I-1J-1512D01*
G01Y478235D01*
X1818877Y478151D01*
G02X1817375Y476808I-1502J169D01*
G37*
G36*
G01X1829967Y475416D02*
X1825297D01*
G02Y478438I0J1511D01*
G01X1829967D01*
G02X1831478Y476937I0J-1511D01*
G01Y476842D01*
X1831469Y476758D01*
G02X1829967Y475416I-1502J169D01*
G37*
G36*
G01X1766700Y474144D02*
X1761699D01*
G02X1761700Y477166I1J1511D01*
G01X1766700D01*
G02X1768212Y475665I0J-1512D01*
G01Y475570D01*
X1768202Y475486D01*
G02X1766700Y474144I-1502J170D01*
G37*
G36*
G01X15473Y476510D02*
G03X16027I277J288D01*
G02Y474490I973J-1010D01*
G03X15473I-277J-288D01*
G02X13549Y474470I-973J1010D01*
G03X12988Y474451I-271J-294D01*
G02X12923Y476447I-1016J966D01*
G03X13484Y476466I271J294D01*
G02X15473Y476510I1016J-966D01*
G37*
G36*
G01X1779300Y473544D02*
X1774299D01*
G02X1774300Y476566I1J1511D01*
G01X1779300D01*
G02X1780812Y475065I0J-1512D01*
G01Y474970D01*
X1780802Y474886D01*
G02X1779300Y473544I-1502J170D01*
G37*
G36*
G01X1806525Y472444D02*
X1801524D01*
G02X1801525Y475466I1J1511D01*
G01X1806525D01*
G02X1808036Y473965I0J-1511D01*
G01Y473870D01*
X1808027Y473786D01*
G02X1806525Y472444I-1502J169D01*
G37*
G36*
G01X-13140Y474769D02*
G03X-12540I300J265D01*
G02Y472911I1050J-929D01*
G03X-13140I-300J-265D01*
G02Y474769I-1050J929D01*
G37*
G36*
G01X1679576Y472270D02*
G03X1679022Y472244I-263J-301D01*
G02X1678925Y474260I-1021J961D01*
G03X1679479Y474286I263J301D01*
G02X1679576Y472270I1021J-961D01*
G37*
G36*
G01X1895789Y469229D02*
G03X1895211I-289J-277D01*
G02X1893117Y471090I-1011J971D01*
G03X1893095Y471623I-309J254D01*
G02X1895111Y473571I1005J977D01*
G03X1895689I289J277D01*
G02X1897634Y473646I1011J-971D01*
G03X1898166I266J298D01*
G02X1900111Y473571I934J-1046D01*
G03X1900689I289J277D01*
G02X1902632Y473647I1011J-971D01*
G03X1903187Y473669I266J299D01*
G02X1905283Y471810I1013J-969D01*
G03X1905305Y471277I309J-254D01*
G02X1903368Y469253I-1005J-977D01*
G03X1902813Y469231I-266J-299D01*
G02X1900789Y469229I-1013J969D01*
G03X1900211I-289J-277D01*
G02X1898266Y469154I-1011J971D01*
G03X1897734I-266J-298D01*
G02X1895789Y469229I-934J1046D01*
G37*
G36*
G01X1634422Y471660D02*
G03X1634365Y471124I265J-299D01*
G02X1632012Y471373I-1290J-950D01*
G03X1632069Y471909I-265J299D01*
G02X1634422Y471660I1290J950D01*
G37*
G36*
G01X1463389Y464529D02*
G03X1462811I-289J-277D01*
G02Y466471I-1011J971D01*
G03X1463389I289J277D01*
G02Y464529I1011J-971D01*
G37*
G36*
G01X1455589D02*
G03X1455011I-289J-277D01*
G02Y466471I-1011J971D01*
G03X1455589I289J277D01*
G02Y464529I1011J-971D01*
G37*
G36*
G01X1667496Y465448D02*
G03X1667236Y465939I-384J111D01*
G02X1666657Y466306I438J1332D01*
G03X1666074Y466303I-290J-276D01*
G02X1666064Y468222I-1027J954D01*
G03X1666647Y468225I290J276D01*
G02X1669021Y466883I1027J-954D01*
G03X1669281Y466392I384J-111D01*
G02X1667496Y465448I-438J-1332D01*
G37*
G36*
G01X1322493Y464943D02*
G03X1323080Y464737I377J134D01*
G02X1322494Y463074I735J-1194D01*
G03X1321907Y463280I-377J-134D01*
G02X1322493Y464943I-735J1194D01*
G37*
G36*
G01X1343133Y462606D02*
G03X1342564Y462583I-273J-292D01*
G02X1342485Y464552I-1036J945D01*
G03X1343054Y464575I273J292D01*
G02X1345126I1036J-945D01*
G03X1345714Y464571I296J269D01*
G02X1345703Y462670I1025J-956D01*
G03X1345115Y462674I-296J-269D01*
G02X1343133Y462606I-1025J956D01*
G37*
G36*
G01X1624247Y462902D02*
G03X1624014Y462389I142J-374D01*
G02X1622202Y463211I-1314J-489D01*
G03X1622435Y463724I-142J374D01*
G02X1624247Y462902I1314J489D01*
G37*
G36*
G01X1586502Y459200D02*
G03X1585948I-277J-288D01*
G02X1583863Y459356I-973J1010D01*
G03X1583247Y459378I-317J-244D01*
G02X1580798Y460293I-1047J932D01*
G03X1580392Y460688I-400J-5D01*
G02X1581772Y462107I-22J1402D01*
G03X1582178Y461712I400J5D01*
G02X1582413Y461696I23J-1402D01*
G03X1582857Y462206I61J395D01*
G02X1585455Y461984I1343J404D01*
G03X1585627Y461451I358J-179D01*
G02X1585948Y461220I-650J-1242D01*
G03X1586502I277J288D01*
G02Y459200I973J-1010D01*
G37*
G36*
G01X1463389Y458829D02*
G03X1462811I-289J-277D01*
G02Y460771I-1011J971D01*
G03X1463389I289J277D01*
G02Y458829I1011J-971D01*
G37*
G36*
G01X1455589D02*
G03X1455011I-289J-277D01*
G02Y460771I-1011J971D01*
G03X1455589I289J277D01*
G02Y458829I1011J-971D01*
G37*
G36*
G01X1640942Y458579D02*
G03X1640920Y457958I241J-319D01*
G02X1639158Y458021I-920J-1058D01*
G03X1639180Y458642I-241J319D01*
G02X1640942Y458579I920J1058D01*
G37*
G36*
G01X1685410Y458414D02*
G03Y457839I279J-288D01*
G02X1683460I-975J-1007D01*
G03Y458414I-279J287D01*
G02X1685410I975J1007D01*
G37*
G36*
G01X1676848Y457738D02*
G03X1676782Y457142I230J-327D01*
G02X1674937Y457346I-1038J-942D01*
G03X1675003Y457942I-230J327D01*
G02X1676848Y457738I1038J942D01*
G37*
G36*
G01X1529333Y455957D02*
G03X1529260Y455398I245J-316D01*
G02X1527289Y455655I-1113J-852D01*
G03X1527362Y456214I-245J316D01*
G02X1529333Y455957I1113J852D01*
G37*
G36*
G01X1463389Y453129D02*
G03X1462811I-289J-277D01*
G02Y455071I-1011J971D01*
G03X1463389I289J277D01*
G02Y453129I1011J-971D01*
G37*
G36*
G01X1455589D02*
G03X1455011I-289J-277D01*
G02Y455071I-1011J971D01*
G03X1455589I289J277D01*
G02Y453129I1011J-971D01*
G37*
G36*
G01X1411986Y457571D02*
Y453476D01*
X1411977Y453392D01*
G02X1408964Y453561I-1502J169D01*
G01Y457561D01*
G02X1411986Y457571I1511J0D01*
G37*
G36*
G01X1404286D02*
Y453476D01*
X1404277Y453392D01*
G02X1401264Y453561I-1502J169D01*
G01Y457561D01*
G02X1404286Y457571I1511J0D01*
G37*
G36*
G01X1396886D02*
Y453476D01*
X1396877Y453392D01*
G02X1393864Y453561I-1502J169D01*
G01Y457562D01*
G02X1396886Y457571I1511J-1D01*
G37*
G36*
G01X1589693Y453068D02*
G03X1590295Y453064I303J261D01*
G02X1590283Y451217I1049J-930D01*
G03X1589681Y451221I-303J-261D01*
G02X1587504Y451319I-1049J930D01*
G03X1586902Y451367I-322J-238D01*
G02X1584927Y451378I-982J1001D01*
G03X1584325Y451338I-284J-282D01*
G02X1584201Y453175I-1117J847D01*
G03X1584803Y453215I284J282D01*
G02X1587048Y453200I1117J-847D01*
G03X1587650Y453152I322J238D01*
G02X1589693Y453068I982J-1001D01*
G37*
G36*
G01X1620175Y453672D02*
G03X1620664Y453361I393J77D01*
G02X1619625Y451728I336J-1361D01*
G03X1619136Y452039I-393J-77D01*
G02X1620175Y453672I-336J1361D01*
G37*
G36*
G01X1662542Y452789D02*
G03X1662548Y452234I291J-274D01*
G02X1660529Y452213I-999J-983D01*
G03X1660523Y452768I-291J274D01*
G02X1660492Y454703I999J984D01*
G03X1660481Y455257I-294J271D01*
G02X1662500Y455299I989J994D01*
G03X1662511Y454745I294J-271D01*
G02X1662542Y452789I-989J-994D01*
G37*
G36*
G01X1867886Y451591D02*
G03X1867450Y451172I-36J-398D01*
G02X1866179Y452496I-1400J-72D01*
G03X1866615Y452915I36J398D01*
G02X1869093Y453883I1400J72D01*
G03X1869715Y453891I308J256D01*
G02X1869737Y452126I1100J-869D01*
G03X1869115Y452118I-308J-256D01*
G02X1867886Y451591I-1100J869D01*
G37*
G36*
G01X1836495Y449088D02*
X1831494D01*
G02X1831495Y452112I1J1512D01*
G01X1836495D01*
G02X1838006Y450610I-1J-1512D01*
G01Y450515D01*
X1837997Y450431D01*
G02X1836495Y449088I-1502J168D01*
G37*
G36*
G01X1818760Y451920D02*
X1823760D01*
G02X1825272Y450418I0J-1512D01*
G01Y450323D01*
X1825262Y450239D01*
G02X1823760Y448896I-1502J169D01*
G01X1818760D01*
G02Y451920I0J1512D01*
G37*
G36*
G01X1811161Y448896D02*
X1806161D01*
G02Y451920I0J1512D01*
G01X1811161D01*
G02X1812672Y450418I-1J-1512D01*
G01Y450323D01*
X1812663Y450239D01*
G02X1811161Y448896I-1502J169D01*
G37*
G36*
G01X1793562Y451920D02*
X1798563D01*
G02X1800074Y450418I-1J-1512D01*
G01Y450323D01*
X1800065Y450239D01*
G02X1798563Y448896I-1502J169D01*
G01X1793562D01*
G02Y451920I1J1512D01*
G37*
G36*
G01X1780963D02*
X1785964D01*
G02X1787476Y450418I0J-1512D01*
G01Y450323D01*
X1787466Y450239D01*
G02X1785964Y448896I-1502J168D01*
G01X1780963D01*
G02Y451920I0J1512D01*
G37*
G36*
G01X1768366D02*
X1773366D01*
G02X1774878Y450418I0J-1512D01*
G01Y450323D01*
X1774868Y450239D01*
G02X1773366Y448896I-1502J169D01*
G01X1768366D01*
G02Y451920I0J1512D01*
G37*
G36*
G01X1760767Y448896D02*
X1755767D01*
G02Y451920I0J1512D01*
G01X1760767D01*
G02X1762278Y450418I-1J-1512D01*
G01Y450323D01*
X1762269Y450239D01*
G02X1760767Y448896I-1502J169D01*
G37*
G36*
G01X1748169D02*
X1743169D01*
G02Y451920I0J1512D01*
G01X1748169D01*
G02X1749680Y450418I-1J-1512D01*
G01Y450323D01*
X1749671Y450239D01*
G02X1748169Y448896I-1502J169D01*
G37*
G36*
G01X1470989Y449026D02*
G03X1470411I-289J-277D01*
G02Y450968I-1011J971D01*
G03X1470989I289J277D01*
G02Y449026I1011J-971D01*
G37*
G36*
G01X1463189D02*
G03X1462611I-289J-277D01*
G02Y450968I-1011J971D01*
G03X1463189I289J277D01*
G02Y449026I1011J-971D01*
G37*
G36*
G01X1631268Y451086D02*
G03X1631263Y450513I277J-289D01*
G02X1629308Y450531I-987J-996D01*
G03X1629313Y451104I-277J289D01*
G02X1629282Y453064I987J996D01*
G03X1629260Y453635I-291J275D01*
G02X1629190Y455648I940J1040D01*
G03Y456202I-288J277D01*
G02X1631210I1010J973D01*
G03Y455648I288J-277D01*
G02X1631218Y453711I-1010J-973D01*
G03X1631240Y453140I291J-275D01*
G02X1631268Y451086I-940J-1040D01*
G37*
G36*
G01X1682201Y450789D02*
G03X1682187Y450234I281J-285D01*
G02X1680168Y450283I-1033J-948D01*
G03X1680182Y450838I-281J285D01*
G02X1682201Y450789I1033J948D01*
G37*
G36*
G01X1873831Y449539D02*
G03Y448961I277J-289D01*
G02X1871889I-971J-1011D01*
G03Y449539I-277J289D01*
G02X1873831I971J1011D01*
G37*
G36*
G01X1647500Y449140D02*
G03X1647513Y448585I294J-271D01*
G02X1645494Y448540I-988J-995D01*
G03X1645481Y449095I-294J271D01*
G02X1645452Y451055I988J995D01*
G03X1645448Y451610I-290J275D01*
G02X1647468Y451625I1003J980D01*
G03X1647472Y451070I290J-275D01*
G02X1647500Y449140I-1003J-980D01*
G37*
G36*
G01X1677288Y448795D02*
G03X1677284Y448229I281J-285D01*
G02X1675303Y448243I-998J-985D01*
G03X1675307Y448809I-281J285D01*
G02X1677288Y448795I998J985D01*
G37*
G36*
G01X1674076Y447548D02*
G03X1674075Y446993I288J-278D01*
G02X1672056Y446996I-1011J-971D01*
G03X1672057Y447551I-288J278D01*
G02X1674076Y447548I1011J971D01*
G37*
G36*
G01X-616Y454932D02*
G03X-328Y455438I-94J389D01*
G02X2535Y455410I1436J441D01*
G03X2794Y454904I380J-125D01*
G02X3435Y452446I-455J-1431D01*
G03Y451900I292J-273D01*
G02Y449846I-1096J-1027D01*
G03Y449300I292J-273D01*
G02Y447246I-1096J-1027D01*
G03Y446700I292J-273D01*
G02X1312Y444577I-1096J-1027D01*
G03X766I-273J-292D01*
G02X-1357Y446700I-1027J1096D01*
G03Y447246I-292J273D01*
G02Y449300I1096J1027D01*
G03Y449846I-292J273D01*
G02Y451900I1096J1027D01*
G03Y452446I-292J273D01*
G02X-616Y454932I1096J1027D01*
G37*
G36*
G01X6770Y447971D02*
G03X7316I273J292D01*
G02X9705Y447508I1027J-1096D01*
G03X10297Y447349I363J169D01*
G02X9857Y445552I803J-1149D01*
G03X9258Y445684I-355J-185D01*
G02X7316Y445779I-915J1191D01*
G03X6770I-273J-292D01*
G02X6712Y445728I-1020J1102D01*
G03Y445422I130J-153D01*
G02X4647Y445302I-969J-1147D01*
G03Y445848I-292J273D01*
G02X6770Y447971I1096J1027D01*
G37*
G36*
G01X1670826Y445480D02*
G03Y444926I288J-277D01*
G02X1668806I-1010J-973D01*
G03Y445480I-288J277D01*
G02Y447426I1010J973D01*
G03Y447980I-288J277D01*
G02X1670826I1010J973D01*
G03Y447426I288J-277D01*
G02Y445480I-1010J-973D01*
G37*
G36*
G01X1718140Y442709D02*
G03X1717978Y443287I-335J218D01*
G02X1717595Y443559I609J1263D01*
G03X1717029I-283J-282D01*
G02Y445541I-992J991D01*
G03X1717595I283J282D01*
G02X1719764Y443788I992J-991D01*
G03X1719926Y443210I335J-218D01*
G02X1718140Y442709I-609J-1263D01*
G37*
G36*
G01X10786Y443296D02*
X15787D01*
G02X17298Y441795I0J-1512D01*
G01Y441700D01*
X17288Y441616D01*
G02X15786Y440274I-1502J170D01*
G01X10786D01*
G02Y443296I0J1511D01*
G37*
G36*
G01X1413300Y442491D02*
G03X1413324Y441870I264J-301D01*
G02X1411559Y441802I-841J-1122D01*
G03X1411535Y442423I-264J301D01*
G02X1413300Y442491I841J1122D01*
G37*
G36*
G01X1589900Y441497D02*
G03X1590472Y441480I294J271D01*
G02X1590416Y439521I974J-1008D01*
G03X1589844Y439538I-294J-271D01*
G02X1589900Y441497I-974J1008D01*
G37*
G36*
G01X1613207Y441666D02*
G03X1613223Y441103I292J-273D01*
G02X1611232Y441045I-967J-1015D01*
G03X1611216Y441608I-292J273D01*
G02X1613207Y441666I967J1015D01*
G37*
G36*
G01X22936Y444354D02*
G02X25958Y444364I1511J0D01*
G01Y439354D01*
X25959D01*
X25958Y439269D01*
X25949Y439185D01*
G02X22936Y439354I-1502J169D01*
G01Y444354D01*
G37*
G36*
G01X750525Y439327D02*
G03X749900Y438975I-226J-330D01*
G02X747401Y439770I-1400J-75D01*
G03X747278Y440369I-314J248D01*
G02X748440Y442914I672J1231D01*
G03X748971Y443205I140J375D01*
G02X750525Y439327I3670J-780D01*
G37*
G36*
G01X1409123Y439924D02*
G03Y439309I257J-307D01*
G02X1407327I-898J-1076D01*
G03Y439924I-257J307D01*
G02X1409123I898J1076D01*
G37*
G36*
G01X1506427Y436187D02*
G03X1506443Y435632I296J-269D01*
G02X1504427Y435576I-981J-1002D01*
G03X1504411Y436131I-296J269D01*
G02X1506427Y436187I981J1002D01*
G37*
G36*
G01X1640510Y434727D02*
G03Y434173I288J-277D01*
G02X1638490I-1010J-973D01*
G03Y434727I-288J277D01*
G02X1640510I1010J973D01*
G37*
G36*
G01X1461099Y431902D02*
G03X1460510I-294J-271D01*
G02Y433800I-1032J949D01*
G03X1461099I295J271D01*
G02Y431902I1032J-949D01*
G37*
G36*
G01X1468386Y433869D02*
G03X1468958Y433852I294J271D01*
G02X1468900Y431892I973J-1010D01*
G03X1468328Y431909I-294J-271D01*
G02X1468386Y433869I-973J1010D01*
G37*
G36*
G01X1588351Y433445D02*
G03X1588973Y433428I318J243D01*
G02X1588924Y431663I1064J-913D01*
G03X1588302Y431680I-318J-243D01*
G02X1588351Y433445I-1064J913D01*
G37*
G36*
G01X1410812Y434785D02*
Y429690D01*
X1410802Y429606D01*
G02X1407788Y429775I-1502J169D01*
G01Y434776D01*
G02X1410812Y434785I1512J-1D01*
G37*
G36*
G01X1402910D02*
Y429690D01*
X1402900Y429606D01*
G02X1399886Y429775I-1502J169D01*
G01Y434776D01*
G02X1402910Y434785I1512J-1D01*
G37*
G36*
G01X1468885Y427046D02*
G03X1468305I-290J-276D01*
G02Y428980I-1015J967D01*
G03X1468885I290J276D01*
G02Y427046I1015J-967D01*
G37*
G36*
G01X1548776Y429391D02*
G03Y428844I292J-274D01*
G02X1546732I-1022J-960D01*
G03Y429391I-292J274D01*
G02X1548097Y431710I1022J960D01*
G03X1548579Y431986I98J388D01*
G02X1549582Y430235I1346J-392D01*
G03X1549100Y429959I-98J-388D01*
G02X1548776Y429391I-1346J392D01*
G37*
G36*
G01X1583820Y426607D02*
G03X1583311Y426307I-118J-382D01*
G02X1582352Y427934I-1372J287D01*
G03X1582861Y428234I118J382D01*
G02X1583820Y426607I1372J-287D01*
G37*
G36*
G01X17025Y423338D02*
X12024D01*
G02X12025Y426362I1J1512D01*
G01X17025D01*
G02X18536Y424860I-1J-1512D01*
G01Y424765D01*
X18527Y424681D01*
G02X17025Y423338I-1502J168D01*
G37*
G36*
G01X7025D02*
X2024D01*
G02X2025Y426362I1J1512D01*
G01X7025D01*
G02X8536Y424860I-1J-1512D01*
G01Y424765D01*
X8527Y424681D01*
G02X7025Y423338I-1502J168D01*
G37*
G36*
G01X62516Y424220D02*
X62507Y424136D01*
G02X59494Y424305I-1502J169D01*
G01Y429306D01*
G02X62516Y429315I1511J-1D01*
G01Y424220D01*
G37*
G36*
G01X1589368Y424272D02*
G03X1588961Y423864I-7J-400D01*
G02X1587587Y425237I-1402J-29D01*
G03X1587994Y425645I7J400D01*
G02X1589368Y424272I1402J29D01*
G37*
G36*
G01X1559675Y420042D02*
X1555775D01*
G02Y422866I0J1412D01*
G01X1559676D01*
G02X1561086Y421464I-1J-1412D01*
G01Y421370D01*
X1561076Y421286D01*
G02X1559675Y420042I-1401J167D01*
G37*
G36*
G01X1548790Y422624D02*
G03Y422084I295J-270D01*
G02X1546720I-1035J-946D01*
G03Y422624I-295J270D01*
G02X1548139Y424918I1035J946D01*
G03X1548629Y425181I109J385D01*
G02X1549580Y423405I1335J-428D01*
G03X1549090Y423142I-109J-385D01*
G02X1548790Y422624I-1335J427D01*
G37*
G36*
G01X1504996Y419784D02*
G03X1504478Y419514I-133J-377D01*
G02X1501738Y419711I-1350J378D01*
G03X1501304Y420058I-397J-51D01*
G02X1502565Y421635I-129J1396D01*
G03X1502999Y421288I397J51D01*
G02X1503591Y421215I128J-1396D01*
G03X1504109Y421485I133J377D01*
G02X1504508Y422137I1350J-378D01*
G03X1504541Y422692I-271J295D01*
G02X1506556Y422574I1064J912D01*
G03X1506523Y422019I271J-295D01*
G02X1504996Y419784I-1065J-912D01*
G37*
G36*
G01X50776Y424005D02*
Y418910D01*
X50767Y418826D01*
G02X47754Y418995I-1502J169D01*
G01Y423996D01*
G02X50776Y424005I1511J-1D01*
G37*
G36*
G01X1557725Y416662D02*
X1553824D01*
G02X1553825Y419486I1J1412D01*
G01X1554448D01*
G02X1554998Y418963I0J-551D01*
G03X1555016Y418813I777J17D01*
G02X1555159Y418507I-1189J-742D01*
G03X1556391I616J472D01*
G02X1556534Y418813I1332J-436D01*
G03X1556550Y419022I-759J163D01*
G02X1557050Y419486I500J-37D01*
G01X1557725D01*
G02X1559136Y418084I0J-1411D01*
G01Y417990D01*
X1559126Y417906D01*
G02X1557725Y416662I-1401J167D01*
G37*
G36*
G01X1413476Y416907D02*
X1413461Y417081D01*
X1413626Y421997D01*
X1413634Y422005D01*
X1413640Y422078D01*
G02X1416647Y422124I1506J-131D01*
G01X1416668Y421948D01*
X1416504Y417042D01*
X1416505D01*
X1416502Y416988D01*
X1416477Y416817D01*
G02X1413476Y416907I-1495J222D01*
G37*
G36*
G01X1405646Y421576D02*
G02X1408670Y421585I1512J-1D01*
G01Y416490D01*
X1408660Y416406D01*
G02X1405646Y416572I-1502J167D01*
G01Y421576D01*
G37*
G36*
G01X1567475Y413282D02*
X1563574D01*
G02X1563575Y416106I1J1412D01*
G01X1564198D01*
G02X1564748Y415583I0J-551D01*
G03X1564766Y415433I777J17D01*
G02X1564909Y415127I-1189J-742D01*
G03X1566141I616J472D01*
G02X1566284Y415433I1332J-436D01*
G03X1566300Y415642I-759J163D01*
G02X1566800Y416106I500J-37D01*
G01X1567475D01*
G02X1568886Y414704I0J-1411D01*
G01Y414610D01*
X1568876Y414526D01*
G02X1567475Y413282I-1401J167D01*
G37*
G36*
G01X767237Y416062D02*
G03X767281Y415483I296J-269D01*
G02X765357Y415340I-887J-1086D01*
G03X765313Y415919I-296J269D01*
G02X766261Y418406I887J1086D01*
G03X766678Y418800I17J399D01*
G02X768019Y417379I1402J-20D01*
G03X767602Y416985I-17J-399D01*
G02X767237Y416062I-1402J21D01*
G37*
G36*
G01X47006Y415201D02*
G03Y414590I258J-306D01*
G02X45194I-906J-1070D01*
G03Y415201I-258J305D01*
G02X47006I906J1070D01*
G37*
G36*
G01X1471147Y413091D02*
G03X1471720Y413069I297J268D01*
G02X1471647Y411116I968J-1014D01*
G03X1471074Y411138I-297J-268D01*
G02X1471147Y413091I-968J1014D01*
G37*
G36*
G01X1588551Y411003D02*
G03X1587996Y410990I-271J-295D01*
G02X1587949Y413008I-996J986D01*
G03X1588504Y413021I271J295D01*
G02X1588551Y411003I996J-986D01*
G37*
G36*
G01X120018Y413220D02*
G03X120037Y412643I286J-279D01*
G02X118098Y412581I-937J-1043D01*
G03X118079Y413158I-286J279D01*
G02X120018Y413220I937J1043D01*
G37*
G36*
G01X20473Y414391D02*
G03X21740Y414794I-2J2199D01*
G02X21756Y410156I1488J-2314D01*
G03X20502Y410569I-1283J-1786D01*
G01X20471D01*
G03X19204Y410166I2J-2199D01*
G02X19188Y414804I-1488J2314D01*
G03X20442Y414391I1283J1786D01*
G01X20473D01*
G37*
G36*
G01X3938D02*
G03X5205Y414794I-2J2199D01*
G02X5221Y410156I1488J-2314D01*
G03X3967Y410569I-1283J-1786D01*
G01X3936D01*
G03X2669Y410166I2J-2199D01*
G02X2653Y414804I-1488J2314D01*
G03X3907Y414391I1283J1786D01*
G01X3938D01*
G37*
G36*
G01X-12598D02*
G03X-11331Y414794I-2J2199D01*
G02X-11315Y410156I1488J-2314D01*
G03X-12569Y410569I-1283J-1786D01*
G01X-12599D01*
G03X-13866Y410166I2J-2199D01*
G02X-13882Y414804I-1488J2314D01*
G03X-12628Y414391I1283J1786D01*
G01X-12598D01*
G37*
G36*
G01X749612Y408828D02*
G03X749058I-277J-288D01*
G02X747075Y410811I-973J1010D01*
G03Y411365I-288J277D01*
G02X749058Y413348I1010J973D01*
G03X749612I277J288D01*
G02X751558I973J-1010D01*
G03X752112I277J288D01*
G02X753991Y413408I973J-1010D01*
G03X754524Y413422I259J305D01*
G02X755905Y413741I963J-1019D01*
G03X756424Y414133I119J382D01*
G02X758799Y415177I1402J34D01*
G03X759353I277J288D01*
G02X761303Y415172I972J-1010D01*
G03X761912Y415233I279J287D01*
G02X763960Y413358I1157J-793D01*
G03X763942Y412756I254J-309D01*
G02X761975Y410760I-953J-1028D01*
G03X761384Y410747I-290J-276D01*
G02X759353Y410657I-1058J920D01*
G03X758799I-277J-288D01*
G02X757408Y410329I-972J1010D01*
G03X756889Y409937I-119J-382D01*
G02X754581Y408833I-1402J-34D01*
G03X754048Y408819I-259J-305D01*
G02X752112Y408828I-963J1019D01*
G03X751558I-277J-288D01*
G02X749612I-973J1010D01*
G37*
G36*
G01X1403912Y408281D02*
Y413282D01*
G02X1406934Y413291I1511J-1D01*
G01Y408281D01*
X1406935D01*
X1406934Y408196D01*
X1406925Y408112D01*
G02X1403912Y408281I-1502J169D01*
G37*
G36*
G01X1571375Y406522D02*
X1567474D01*
G02X1567475Y409346I1J1412D01*
G01X1568098D01*
G02X1568648Y408823I0J-551D01*
G03X1568666Y408673I777J17D01*
G02X1568809Y408367I-1189J-742D01*
G03X1570041I616J472D01*
G02X1570184Y408673I1332J-436D01*
G03X1570200Y408882I-759J163D01*
G02X1570700Y409346I500J-37D01*
G01X1571375D01*
G02X1572786Y407944I0J-1411D01*
G01Y407850D01*
X1572776Y407766D01*
G02X1571375Y406522I-1401J167D01*
G37*
G36*
G01X1444049Y407876D02*
G03X1443955Y407308I227J-329D01*
G02X1442033Y407625I-1125J-836D01*
G03X1442127Y408193I-227J329D01*
G02X1444049Y407876I1125J836D01*
G37*
G36*
G01X120709Y404984D02*
G03X120136Y405156I-363J-168D01*
G02X120670Y406937I-738J1192D01*
G03X121243Y406765I363J168D01*
G02X120709Y404984I738J-1192D01*
G37*
G36*
G01X53088Y406598D02*
X55227Y409137D01*
G02X57894Y408173I1156J-974D01*
G01Y408078D01*
X57885Y407994D01*
G02X57539Y407189I-1503J169D01*
G01X56228Y405632D01*
X56227D01*
X55422Y404678D01*
X55421Y404676D01*
G02X53088Y406598I-1177J948D01*
G37*
G36*
G01X1589833Y402984D02*
G03X1589253Y402806I-214J-338D01*
G02X1588716Y404554I-1285J562D01*
G03X1589296Y404732I214J338D01*
G02X1589833Y402984I1285J-562D01*
G37*
G36*
G01X25591Y406517D02*
G03X26858Y406920I-2J2199D01*
G02X26874Y402282I1488J-2314D01*
G03X25620Y402695I-1283J-1786D01*
G01X25590D01*
G03X24323Y402292I2J-2199D01*
G02X24307Y406930I-1488J2314D01*
G03X25561Y406517I1283J1786D01*
G01X25591D01*
G37*
G36*
G01X9056D02*
G03X10323Y406920I-2J2199D01*
G02X10339Y402282I1488J-2314D01*
G03X9085Y402695I-1283J-1786D01*
G01X9054D01*
G03X7787Y402292I2J-2199D01*
G02X7771Y406930I-1488J2314D01*
G03X9025Y406517I1283J1786D01*
G01X9056D01*
G37*
G36*
G01X-7480D02*
G03X-6213Y406920I-2J2199D01*
G02X-6197Y402282I1488J-2314D01*
G03X-7451Y402695I-1283J-1786D01*
G01X-7481D01*
G03X-8748Y402292I2J-2199D01*
G02X-8764Y406930I-1488J2314D01*
G03X-7510Y406517I1283J1786D01*
G01X-7480D01*
G37*
G36*
G01X66896Y403268D02*
Y403173D01*
X66886Y403089D01*
G02X64311Y402193I-1502J169D01*
G01X61973Y404550D01*
X61972Y404551D01*
G02X64097Y406701I1052J1085D01*
G01X65153Y405638D01*
X66457Y404323D01*
G02X66896Y403268I-1073J-1065D01*
G37*
G36*
G01X1383327Y397890D02*
G03X1382773I-277J-288D01*
G02X1380751Y399830I-973J1010D01*
G03X1380740Y400372I-299J265D01*
G02X1380658Y400466I1015J968D01*
G03X1380346I-156J-125D01*
G02X1378023Y400669I-1094J877D01*
G03X1377479Y400826I-350J-193D01*
G02X1375827Y401043I-679J1227D01*
G03X1375273I-277J-288D01*
G02Y403063I-973J1010D01*
G03X1375827I277J288D01*
G02X1378029Y402727I973J-1010D01*
G03X1378573Y402570I350J193D01*
G02X1380225Y402353I679J-1227D01*
G03X1380779I277J288D01*
G02X1382725I973J-1010D01*
G03X1383279I277J288D01*
G02X1385225I973J-1010D01*
G03X1385779I277J288D01*
G02X1387801Y400413I973J-1010D01*
G03X1387812Y399871I299J-265D01*
G02X1385827Y397890I-1012J-971D01*
G03X1385273I-277J-288D01*
G02X1383327I-973J1010D01*
G37*
G36*
G01X1586703Y396411D02*
G03X1586141Y396408I-279J-286D01*
G02X1586130Y398403I-991J992D01*
G03X1586692Y398406I279J286D01*
G02X1586703Y396411I991J-992D01*
G37*
G36*
G01X102066Y400958D02*
G03X102634I284J282D01*
G02X104766I1066J-1058D01*
G03X105334I284J282D01*
G02X107466I1066J-1058D01*
G03X108034I284J282D01*
G02X110499Y400446I1066J-1058D01*
G03X111017Y400219I373J146D01*
G02X111112Y397386I544J-1400D01*
G03X110594Y397045I-120J-382D01*
G02X108034Y396142I-1494J155D01*
G03X107466I-284J-282D01*
G02X105334I-1066J1058D01*
G03X104766I-284J-282D01*
G02X102634I-1066J1058D01*
G03X102066I-284J-282D01*
G02X99942Y398266I-1066J1058D01*
G03Y398834I-282J284D01*
G02X102066Y400958I1058J1066D01*
G37*
G36*
G01X1370996Y395697D02*
G03X1370418I-289J-277D01*
G02Y397639I-1011J971D01*
G03X1370996I289J277D01*
G02Y395697I1011J-971D01*
G37*
G36*
G01X1655811Y398206D02*
G03X1655831Y397649I297J-268D01*
G02X1653820Y397576I-970J-1012D01*
G03X1653800Y398133I-297J268D01*
G02X1653776Y400133I970J1012D01*
G03X1653784Y400688I-284J282D01*
G02X1655803Y400657I1024J957D01*
G03X1655795Y400102I284J-282D01*
G02X1655811Y398206I-1025J-957D01*
G37*
G36*
G01X3938Y398643D02*
G03X5205Y399046I-2J2199D01*
G02X5221Y394408I1488J-2314D01*
G03X3967Y394821I-1283J-1786D01*
G01X3936D01*
G03X2669Y394418I2J-2199D01*
G02X2653Y399056I-1488J2314D01*
G03X3907Y398643I1283J1786D01*
G01X3938D01*
G37*
G36*
G01X-12598D02*
G03X-11331Y399046I-2J2199D01*
G02X-11315Y394408I1488J-2314D01*
G03X-12569Y394821I-1283J-1786D01*
G01X-12599D01*
G03X-13866Y394418I2J-2199D01*
G02X-13882Y399056I-1488J2314D01*
G03X-12628Y398643I1283J1786D01*
G01X-12598D01*
G37*
G36*
G01X66236Y391560D02*
X66227Y391476D01*
G02X63214Y391645I-1502J169D01*
G01Y396645D01*
G02X66236Y396655I1511J0D01*
G01Y391560D01*
G37*
G36*
G01X1662125Y389274D02*
G03X1662056Y388723I251J-311D01*
G02X1660052Y388973I-1122J-840D01*
G03X1660121Y389524I-251J311D01*
G02X1660264Y391367I1122J840D01*
G03Y391940I-280J286D01*
G02X1662222I979J1003D01*
G03Y391367I280J-286D01*
G02X1662125Y389274I-979J-1003D01*
G37*
G36*
G01X25591Y390769D02*
G03X26858Y391172I-2J2199D01*
G02X26874Y386534I1488J-2314D01*
G03X25620Y386947I-1283J-1786D01*
G01X25590D01*
G03X24323Y386544I2J-2199D01*
G02X24307Y391182I-1488J2314D01*
G03X25561Y390769I1283J1786D01*
G01X25591D01*
G37*
G36*
G01X175673Y385123D02*
G03Y384493I246J-315D01*
G02X173827I-923J-1185D01*
G03Y385123I-246J315D01*
G02Y387493I923J1185D01*
G03Y388123I-246J315D01*
G02X175673I923J1185D01*
G03Y387493I246J-315D01*
G02Y385123I-923J-1185D01*
G37*
G36*
G01X822033Y382027D02*
G03X821403I-315J-246D01*
G02X819295Y384135I-1185J923D01*
G03Y384765I-246J315D01*
G02X821403Y386873I923J1185D01*
G03X822033I315J246D01*
G02X824364Y386921I1185J-923D01*
G03X824969Y386915I305J259D01*
G02X827152Y384854I1128J-992D01*
G03X827177Y384262I281J-285D01*
G02X825081Y382125I-961J-1154D01*
G03X824450Y382091I-302J-262D01*
G02X822033Y382027I-1232J859D01*
G37*
G36*
G01X1465365Y384296D02*
G03X1465373Y383729I286J-280D01*
G02X1463396Y383699I-973J-1009D01*
G03X1463388Y384266I-286J280D01*
G02X1465365Y384296I973J1009D01*
G37*
G36*
G01X172081Y384583D02*
G03Y383953I246J-315D01*
G02X170235I-923J-1185D01*
G03Y384583I-246J315D01*
G02Y386953I923J1185D01*
G03Y387583I-246J315D01*
G02X172081I923J1185D01*
G03Y386953I246J-315D01*
G02Y384583I-923J-1185D01*
G37*
G36*
G01X1571657Y384060D02*
G03X1571944Y383585I390J-89D01*
G02X1570217Y382538I-359J-1355D01*
G03X1569930Y383013I-390J89D01*
G02X1571657Y384060I359J1355D01*
G37*
G36*
G01X3938Y382895D02*
G03X5205Y383298I-2J2199D01*
G02X5221Y378660I1488J-2314D01*
G03X3967Y379073I-1283J-1786D01*
G01X3936D01*
G03X2669Y378670I2J-2199D01*
G02X2653Y383308I-1488J2314D01*
G03X3907Y382895I1283J1786D01*
G01X3938D01*
G37*
G36*
G01X-12598D02*
G03X-11331Y383298I-2J2199D01*
G02X-11315Y378660I1488J-2314D01*
G03X-12569Y379073I-1283J-1786D01*
G01X-12599D01*
G03X-13866Y378670I2J-2199D01*
G02X-13882Y383308I-1488J2314D01*
G03X-12628Y382895I1283J1786D01*
G01X-12598D01*
G37*
G36*
G01X1665868Y378253D02*
G03X1665885Y377698I296J-269D01*
G02X1663866Y377636I-980J-1003D01*
G03X1663849Y378191I-296J269D01*
G02X1665868Y378253I980J1003D01*
G37*
G36*
G01X1600490Y380354D02*
Y376261D01*
X1600480Y376176D01*
G02X1597266Y376346I-1603J170D01*
G01Y380344D01*
G02X1600490Y380354I1612J0D01*
G37*
G36*
G01X1609758Y380332D02*
Y376086D01*
X1609748Y376001D01*
G02X1606534Y376171I-1603J170D01*
G01Y380322D01*
G02X1609758Y380332I1612J0D01*
G37*
G36*
G01X852304Y377641D02*
G03Y377095I292J-273D01*
G02X852361Y375106I-1096J-1027D01*
G03X852470Y374502I307J-256D01*
G02X850602Y372202I-743J-1305D01*
G03X850014Y372215I-300J-265D01*
G02X847807Y374252I-1082J1042D01*
G03X847739Y374843I-300J265D01*
G02X847581Y374972I869J1225D01*
G03X847035I-273J-292D01*
G02X844912Y377095I-1027J1096D01*
G03Y377641I-292J273D01*
G02X847035Y379764I1096J1027D01*
G03X847581I273J292D01*
G02X849635I1027J-1096D01*
G03X850181I273J292D01*
G02X852304Y377641I1027J-1096D01*
G37*
G36*
G01X778810Y371129D02*
G03X778193Y371122I-306J-258D01*
G02X778172Y372904I-1093J878D01*
G03X778789Y372911I306J258D01*
G02X778810Y371129I1093J-878D01*
G37*
G36*
G01X25591Y375021D02*
G03X26858Y375424I-2J2199D01*
G02X26874Y370786I1488J-2314D01*
G03X25620Y371199I-1283J-1786D01*
G01X25590D01*
G03X24323Y370796I2J-2199D01*
G02X24307Y375434I-1488J2314D01*
G03X25561Y375021I1283J1786D01*
G01X25591D01*
G37*
G36*
G01X9056D02*
G03X10323Y375424I-2J2199D01*
G02X10339Y370786I1488J-2314D01*
G03X9085Y371199I-1283J-1786D01*
G01X9054D01*
G03X7787Y370796I2J-2199D01*
G02X7771Y375434I-1488J2314D01*
G03X9025Y375021I1283J1786D01*
G01X9056D01*
G37*
G36*
G01X197824Y376256D02*
G03X198316Y376525I109J385D01*
G02X200871Y375085I1438J-436D01*
G03X200901Y374520I297J-268D01*
G02X200823Y372215I-1001J-1120D01*
G03Y371585I246J-315D01*
G02X198977I-923J-1185D01*
G03Y372215I-246J315D01*
G02X198429Y373097I923J1185D01*
G03X197906Y373394I-392J-81D01*
G02X197824Y376256I-495J1418D01*
G37*
G36*
G01X102761Y370050D02*
G03X102792Y369428I266J-298D01*
G02X101032Y369342I-827J-1132D01*
G03X101001Y369964I-266J298D01*
G02X102761Y370050I827J1132D01*
G37*
G36*
G01X1598821Y368943D02*
G03X1598810Y368350I263J-301D01*
G02X1596929Y368386I-960J-1021D01*
G03X1596940Y368979I-263J301D01*
G02X1598821Y368943I960J1021D01*
G37*
G36*
G01X835863Y367760D02*
G03X836181Y367756I161J119D01*
G02X836282Y365787I1182J-926D01*
G03X835713Y365794I-288J-278D01*
G02X833631Y365767I-1055J1069D01*
G03X833085I-273J-292D01*
G02X831031I-1027J1096D01*
G03X830485I-273J-292D01*
G02X828431I-1027J1096D01*
G03X827885I-273J-292D01*
G02X825831I-1027J1096D01*
G03X825285I-273J-292D01*
G02X823231I-1027J1096D01*
G03X822685I-273J-292D01*
G02X820562Y367890I-1027J1096D01*
G03Y368436I-292J273D01*
G02X822685Y370559I1096J1027D01*
G03X823231I273J292D01*
G02X825285I1027J-1096D01*
G03X825831I273J292D01*
G02X827885I1027J-1096D01*
G03X828431I273J292D01*
G02X830485I1027J-1096D01*
G03X831031I273J292D01*
G02X833085I1027J-1096D01*
G03X833631I273J292D01*
G02X835754Y368436I1027J-1096D01*
G03Y367890I292J-273D01*
G02X835863Y367760I-1095J-1029D01*
G37*
G36*
G01X175215Y365864D02*
G03X174585I-315J-246D01*
G02X172477Y367972I-1185J923D01*
G03Y368602I-246J315D01*
G02X174585Y370710I923J1185D01*
G03X175215I315J246D01*
G02X177585I1185J-923D01*
G03X178215I315J246D01*
G02X180585I1185J-923D01*
G03X181215I315J246D01*
G02X183585I1185J-923D01*
G03X184215I315J246D01*
G02X186585I1185J-923D01*
G03X187215I315J246D01*
G02X189323Y368602I1185J-923D01*
G03Y367972I246J-315D01*
G02X187215Y365864I-923J-1185D01*
G03X186585I-315J-246D01*
G02X184215I-1185J923D01*
G03X183585I-315J-246D01*
G02X181215I-1185J923D01*
G03X180585I-315J-246D01*
G02X178215I-1185J923D01*
G03X177585I-315J-246D01*
G02X175215I-1185J923D01*
G37*
G36*
G01X746646Y362913D02*
G03X746100I-273J-292D01*
G02X744063Y365121I-1027J1096D01*
G03X744042Y365730I-269J296D01*
G02X746000Y368005I932J1178D01*
G03X746546I273J292D01*
G02X748600I1027J-1096D01*
G03X749146I273J292D01*
G02X751183Y365797I1027J-1096D01*
G03X751204Y365188I269J-296D01*
G02X749246Y362913I-932J-1178D01*
G03X748700I-273J-292D01*
G02X746646I-1027J1096D01*
G37*
G36*
G01X20473Y367147D02*
G03X21740Y367550I-2J2199D01*
G02X21756Y362912I1488J-2314D01*
G03X20502Y363325I-1283J-1786D01*
G01X20471D01*
G03X19204Y362922I2J-2199D01*
G02X19188Y367560I-1488J2314D01*
G03X20442Y367147I1283J1786D01*
G01X20473D01*
G37*
G36*
G01X3938D02*
G03X5205Y367550I-2J2199D01*
G02X5221Y362912I1488J-2314D01*
G03X3967Y363325I-1283J-1786D01*
G01X3936D01*
G03X2669Y362922I2J-2199D01*
G02X2653Y367560I-1488J2314D01*
G03X3907Y367147I1283J1786D01*
G01X3938D01*
G37*
G36*
G01X-12598D02*
G03X-11331Y367550I-2J2199D01*
G02X-11315Y362912I1488J-2314D01*
G03X-12569Y363325I-1283J-1786D01*
G01X-12599D01*
G03X-13866Y362922I2J-2199D01*
G02X-13882Y367560I-1488J2314D01*
G03X-12628Y367147I1283J1786D01*
G01X-12598D01*
G37*
G36*
G01X175286Y362358D02*
G03X174656I-315J-246D01*
G02Y364204I-1185J923D01*
G03X175286I315J246D01*
G02X177656I1185J-923D01*
G03X178286I315J246D01*
G02X180656I1185J-923D01*
G03X181286I315J246D01*
G02X183656I1185J-923D01*
G03X184286I315J246D01*
G02X186656I1185J-923D01*
G03X187286I315J246D01*
G02Y362358I1185J-923D01*
G03X186656I-315J-246D01*
G02X184286I-1185J923D01*
G03X183656I-315J-246D01*
G02X181286I-1185J923D01*
G03X180656I-315J-246D01*
G02X178286I-1185J923D01*
G03X177656I-315J-246D01*
G02X175286I-1185J923D01*
G37*
G36*
G01X1544310Y362427D02*
G03Y361873I288J-277D01*
G02X1542290I-1010J-973D01*
G03Y362427I-288J277D01*
G02X1544310I1010J973D01*
G37*
G36*
G01X1653798Y365610D02*
Y360515D01*
X1653788Y360430D01*
G02X1650574Y360600I-1603J170D01*
G01Y365601D01*
G02X1653798Y365610I1612J-1D01*
G37*
G36*
G01X1641878Y365510D02*
Y360415D01*
X1641868Y360330D01*
G02X1638654Y360500I-1603J170D01*
G01Y365501D01*
G02X1641878Y365510I1612J-1D01*
G37*
G36*
G01X1534756Y361839D02*
G03X1534771Y361284I295J-270D01*
G02X1532753Y361227I-982J-1001D01*
G03X1532738Y361782I-295J270D01*
G02X1534756Y361839I982J1001D01*
G37*
G36*
G01X823923Y358895D02*
G03X823292Y358882I-310J-252D01*
G02X821166Y360967I-1202J900D01*
G03Y361597I-246J315D01*
G02X823274Y363705I923J1185D01*
G03X823904I315J246D01*
G02X826274I1185J-923D01*
G03X826904I315J246D01*
G02X829274I1185J-923D01*
G03X829904I315J246D01*
G02X832274I1185J-923D01*
G03X832904I315J246D01*
G02X835042Y361621I1185J-923D01*
G03Y361002I253J-310D01*
G02X832904Y358918I-953J-1161D01*
G03X832274I-315J-246D01*
G02X829904I-1185J923D01*
G03X829274I-315J-246D01*
G02X826904I-1185J923D01*
G03X826274I-315J-246D01*
G02X823923Y358895I-1185J923D01*
G37*
G36*
G01X175239Y358698D02*
G03X174609I-315J-246D01*
G02Y360544I-1185J923D01*
G03X175239I315J246D01*
G02X177609I1185J-923D01*
G03X178239I315J246D01*
G02X180609I1185J-923D01*
G03X181239I315J246D01*
G02X183609I1185J-923D01*
G03X184239I315J246D01*
G02X186609I1185J-923D01*
G03X187239I315J246D01*
G02Y358698I1185J-923D01*
G03X186609I-315J-246D01*
G02X184239I-1185J923D01*
G03X183609I-315J-246D01*
G02X181239I-1185J923D01*
G03X180609I-315J-246D01*
G02X178239I-1185J923D01*
G03X177609I-315J-246D01*
G02X175239I-1185J923D01*
G37*
G36*
G01X49402Y358381D02*
G03X48839Y358449I-315J-246D01*
G02X49078Y360409I-869J1101D01*
G03X49641Y360341I315J246D01*
G02X49402Y358381I869J-1101D01*
G37*
G36*
G01X1479586Y360661D02*
G03X1479585Y360087I278J-287D01*
G02X1477633Y360091I-978J-1005D01*
G03X1477634Y360665I-278J287D01*
G02X1479586Y360661I978J1005D01*
G37*
G36*
G01X1588089Y357429D02*
G03X1587511I-289J-277D01*
G02Y359371I-1011J971D01*
G03X1588089I289J277D01*
G02Y357429I1011J-971D01*
G37*
G36*
G01X1489450Y359356D02*
G03Y358778I277J-289D01*
G02X1487508I-971J-1011D01*
G03Y359356I-277J289D01*
G02Y361378I971J1011D01*
G03Y361956I-277J289D01*
G02X1489450I971J1011D01*
G03Y361378I277J-289D01*
G02Y359356I-971J-1011D01*
G37*
G36*
G01X1484671Y358502D02*
G03X1484699Y357881I266J-299D01*
G02X1482936Y357801I-832J-1128D01*
G03X1482908Y358422I-266J299D01*
G02X1484671Y358502I832J1128D01*
G37*
G36*
G01X25591Y359273D02*
G03X26858Y359676I-2J2199D01*
G02X26874Y355038I1488J-2314D01*
G03X25620Y355451I-1283J-1786D01*
G01X25590D01*
G03X24323Y355048I2J-2199D01*
G02X24307Y359686I-1488J2314D01*
G03X25561Y359273I1283J1786D01*
G01X25591D01*
G37*
G36*
G01X9056D02*
G03X10323Y359676I-2J2199D01*
G02X10339Y355038I1488J-2314D01*
G03X9085Y355451I-1283J-1786D01*
G01X9054D01*
G03X7787Y355048I2J-2199D01*
G02X7771Y359686I-1488J2314D01*
G03X9025Y359273I1283J1786D01*
G01X9056D01*
G37*
G36*
G01X-7480D02*
G03X-6213Y359676I-2J2199D01*
G02X-6197Y355038I1488J-2314D01*
G03X-7451Y355451I-1283J-1786D01*
G01X-7481D01*
G03X-8748Y355048I2J-2199D01*
G02X-8764Y359686I-1488J2314D01*
G03X-7510Y359273I1283J1786D01*
G01X-7480D01*
G37*
G36*
G01X1631382Y356595D02*
G03X1631410Y355995I278J-288D01*
G02X1629560Y355908I-876J-1095D01*
G03X1629532Y356508I-278J288D01*
G02X1629425Y358603I876J1095D01*
G03X1629440Y359158I-280J285D01*
G02X1629414Y361018I1036J945D01*
G03X1629383Y361573I-303J261D01*
G02X1629291Y363533I954J1027D01*
G03X1629269Y364088I-299J266D01*
G02X1629267Y366108I971J1011D01*
G03X1629258Y366692I-278J288D01*
G02X1631173Y366721I942J1038D01*
G03X1631182Y366137I278J-288D01*
G02X1631286Y364166I-942J-1038D01*
G03X1631308Y363611I299J-266D01*
G02X1631399Y361685I-971J-1011D01*
G03X1631430Y361130I303J-261D01*
G02X1631459Y359103I-954J-1027D01*
G03X1631444Y358548I280J-285D01*
G02X1631382Y356595I-1036J-945D01*
G37*
G36*
G01X696625Y356247D02*
G03X696613Y355657I264J-300D01*
G02X694719Y355697I-969J-1013D01*
G03X694731Y356287I-264J300D01*
G02X696625Y356247I969J1013D01*
G37*
G36*
G01X1521289Y356063D02*
G03X1521315Y355466I279J-287D01*
G02X1519453Y355385I-885J-1087D01*
G03X1519427Y355982I-279J287D01*
G02X1521289Y356063I885J1087D01*
G37*
G36*
G01X1525756Y355744D02*
G03Y355190I288J-277D01*
G02X1523736I-1010J-973D01*
G03Y355744I-288J277D01*
G02Y357690I1010J973D01*
G03Y358244I-288J277D01*
G02X1525756I1010J973D01*
G03Y357690I288J-277D01*
G02Y355744I-1010J-973D01*
G37*
G36*
G01X1499217Y353894D02*
G03Y353316I277J-289D01*
G02X1497275I-971J-1011D01*
G03Y353894I-277J289D01*
G02Y355916I971J1011D01*
G03Y356494I-277J289D01*
G02X1497261Y358503I971J1011D01*
G03X1497275Y359058I-281J285D01*
G02X1497356Y361034I1034J947D01*
G03X1497342Y361633I-272J293D01*
G02X1497293Y363734I904J1072D01*
G03X1497279Y364333I-272J293D01*
G02X1499136Y364376I904J1072D01*
G03X1499150Y363777I272J-293D01*
G02X1499199Y361676I-904J-1072D01*
G03X1499213Y361077I272J-293D01*
G02X1499294Y359007I-904J-1072D01*
G03X1499280Y358452I281J-285D01*
G02X1499217Y356494I-1034J-947D01*
G03Y355916I277J-289D01*
G02Y353894I-971J-1011D01*
G37*
G36*
G01X1653157Y353689D02*
G03Y353111I277J-289D01*
G02X1651215I-971J-1011D01*
G03Y353689I-277J289D01*
G02X1653157I971J1011D01*
G37*
G36*
G01X767955Y352504D02*
G03X768121Y351953I349J-195D01*
G02X766254Y351393I-644J-1245D01*
G03X766088Y351944I-349J195D01*
G02X767955Y352504I644J1245D01*
G37*
G36*
G01X1539449Y352283D02*
G03Y351705I277J-289D01*
G02X1537507I-971J-1011D01*
G03Y352283I-277J289D01*
G02Y354305I971J1011D01*
G03Y354883I-277J289D01*
G02X1539449I971J1011D01*
G03Y354305I277J-289D01*
G02Y352283I-971J-1011D01*
G37*
G36*
G01X1416430Y352151D02*
G03X1416419Y351563I266J-299D01*
G02X1414520Y351599I-969J-1013D01*
G03X1414531Y352187I-266J299D01*
G02X1416430Y352151I969J1013D01*
G37*
G36*
G01X1447394Y350654D02*
G03X1446911Y350277I-83J-391D01*
G02X1445801Y351698I-1401J50D01*
G03X1446284Y352075I83J391D01*
G02X1447394Y350654I1401J-50D01*
G37*
G36*
G01X1490844Y351587D02*
G03X1490827Y351004I265J-299D01*
G02X1488909Y351061I-989J-993D01*
G03X1488926Y351644I-265J299D01*
G02X1490844Y351587I989J993D01*
G37*
G36*
G01X1544538Y351473D02*
G03Y350919I288J-277D01*
G02X1542518I-1010J-973D01*
G03Y351473I-288J277D01*
G02X1544538I1010J973D01*
G37*
G36*
G01X1331153Y351026D02*
G03X1331708Y350981I301J264D01*
G02X1331547Y348974I892J-1082D01*
G03X1330992Y349019I-301J-264D01*
G02X1331153Y351026I-892J1082D01*
G37*
G36*
G01X115528Y351963D02*
G03X115764Y352490I-135J377D01*
G02X117535Y351696I1299J526D01*
G03X117299Y351169I135J-377D01*
G02X117398Y350750I-1299J-528D01*
G03X117844Y350383I399J30D01*
G02X116610Y348884I164J-1392D01*
G03X116164Y349251I-399J-30D01*
G02X115528Y351963I-163J1392D01*
G37*
G36*
G01X746392Y343816D02*
G03X745804I-294J-270D01*
G02X743775Y346018I-1105J1018D01*
G03Y346648I-246J315D01*
G02X745804Y348850I924J1184D01*
G03X746392I294J270D01*
G02X748604I1106J-1017D01*
G03X749192I294J270D01*
G02X751221Y346648I1105J-1018D01*
G03Y346018I246J-315D01*
G02X749192Y343816I-924J-1184D01*
G03X748604I-294J-270D01*
G02X746392I-1106J1017D01*
G37*
G36*
G01X189515Y344231D02*
G03X190146Y344210I324J235D01*
G02X190085Y342365I1154J-962D01*
G03X189454Y342386I-324J-235D01*
G02X187115Y342425I-1154J962D01*
G03X186485I-315J-246D01*
G02X184085Y342465I-1185J923D01*
G03X183454Y342486I-324J-235D01*
G02X181115Y342525I-1154J962D01*
G03X180485I-315J-246D01*
G02X178115I-1185J923D01*
G03X177485I-315J-246D01*
G02X175115I-1185J923D01*
G03X174485I-315J-246D01*
G02Y344371I-1185J923D01*
G03X175115I315J246D01*
G02X177485I1185J-923D01*
G03X178115I315J246D01*
G02X180485I1185J-923D01*
G03X181115I315J246D01*
G02X183515Y344331I1185J-923D01*
G03X184146Y344310I324J235D01*
G02X186485Y344271I1154J-962D01*
G03X187115I315J246D01*
G02X189515Y344231I1185J-923D01*
G37*
G36*
G01X1643534Y343999D02*
G03X1643594Y343437I312J-251D01*
G02X1641621Y343227I-882J-1090D01*
G03X1641561Y343789I-312J251D01*
G02X1643534Y343999I882J1090D01*
G37*
G36*
G01X1556480Y340194D02*
G03X1555870I-305J-259D01*
G02Y342006I-1070J906D01*
G03X1556480I305J259D01*
G02Y340194I1070J-906D01*
G37*
G36*
G01X778862Y339127D02*
G03X778252I-305J-259D01*
G02Y340939I-1070J906D01*
G03X778862I305J259D01*
G02Y339127I1070J-906D01*
G37*
G36*
G01X700168Y337953D02*
G03X699613Y337931I-266J-299D01*
G02X699532Y339947I-1013J969D01*
G03X700087Y339969I266J299D01*
G02X700168Y337953I1013J-969D01*
G37*
G36*
G01X1582841Y337739D02*
G03X1582273Y337715I-272J-293D01*
G02X1579704Y339598I-1183J1080D01*
G03X1579581Y340130I-346J200D01*
G02X1581408Y342230I785J1162D01*
G03X1581962Y342189I298J267D01*
G02X1584152Y340570I897J-1077D01*
G03X1584360Y340050I369J-154D01*
G02X1582841Y337739I-566J-1283D01*
G37*
G36*
G01X1070007Y337750D02*
G03X1069377I-315J-246D01*
G02Y339596I-1185J923D01*
G03X1070007I315J246D01*
G02Y337750I1185J-923D01*
G37*
G36*
G01X1062807D02*
G03X1062177I-315J-246D01*
G02Y339596I-1185J923D01*
G03X1062807I315J246D01*
G02Y337750I1185J-923D01*
G37*
G36*
G01X824297Y336104D02*
G03X823667I-315J-246D01*
G02X821465Y338133I-1184J924D01*
G03Y338721I-270J294D01*
G02X821559Y341012I1017J1106D01*
G03Y341642I-246J315D01*
G02X823667Y343750I923J1185D01*
G03X824297I315J246D01*
G02X826667I1185J-923D01*
G03X827297I315J246D01*
G02X829667I1185J-923D01*
G03X830297I315J246D01*
G02X832667I1185J-923D01*
G03X833297I315J246D01*
G02X835610Y343818I1185J-923D01*
G03X836220Y343829I300J264D01*
G02X838474Y343909I1162J-952D01*
G03X839079Y343937I290J275D01*
G02X841293Y341919I1183J-926D01*
G03X841298Y341334I275J-290D01*
G02X841337Y339158I-1016J-1107D01*
G03X841358Y338569I281J-285D01*
G02X839303Y336382I-977J-1141D01*
G03X838672Y336308I-287J-278D01*
G02X836254Y336086I-1290J769D01*
G03X835644Y336075I-300J-264D01*
G02X833297Y336104I-1162J952D01*
G03X832667I-315J-246D01*
G02X830297I-1185J923D01*
G03X829667I-315J-246D01*
G02X827297I-1185J923D01*
G03X826667I-315J-246D01*
G02X824297I-1185J923D01*
G37*
G36*
G01X1620907Y337663D02*
G03Y337109I288J-277D01*
G02X1618887I-1010J-973D01*
G03Y337663I-288J277D01*
G02Y339609I1010J973D01*
G03Y340163I-288J277D01*
G02X1620907I1010J973D01*
G03Y339609I288J-277D01*
G02Y337663I-1010J-973D01*
G37*
G36*
G01X746392Y334499D02*
G03X745804I-294J-270D01*
G02X743681Y336622I-1106J1017D01*
G03Y337210I-270J294D01*
G02X745804Y339333I1017J1106D01*
G03X746392I294J270D01*
G02X748604I1106J-1017D01*
G03X749192I294J270D01*
G02X751315Y337210I1106J-1017D01*
G03Y336622I270J-294D01*
G02X749192Y334499I-1017J-1106D01*
G03X748604I-294J-270D01*
G02X746392I-1106J1017D01*
G37*
G36*
G01X852890Y334482D02*
G03X852260I-315J-246D01*
G02X850078Y336528I-1185J923D01*
G03X850058Y337143I-266J299D01*
G02X849797Y337404I924J1185D01*
G03X849167I-315J-246D01*
G02X847059Y339512I-1185J923D01*
G03Y340142I-246J315D01*
G02Y342512I923J1185D01*
G03Y343142I-246J315D01*
G02X849167Y345250I923J1185D01*
G03X849797I315J246D01*
G02X852167I1185J-923D01*
G03X852797I315J246D01*
G02X855167I1185J-923D01*
G03X855797I315J246D01*
G02X857905Y343142I1185J-923D01*
G03Y342512I246J-315D01*
G02Y340142I-923J-1185D01*
G03Y339512I246J-315D01*
G02X857979Y337204I-923J-1185D01*
G03X857999Y336589I266J-299D01*
G02X855890Y334482I-924J-1184D01*
G03X855260I-315J-246D01*
G02X852890I-1185J923D01*
G37*
G36*
G01X81379Y334629D02*
G03X80813Y334496I-220J-334D01*
G02X80371Y336371I-1213J704D01*
G03X80937Y336504I220J334D01*
G02X81379Y334629I1213J-704D01*
G37*
G36*
G01X102187Y334221D02*
G03X101599Y334210I-289J-277D01*
G02X101563Y336109I-1049J930D01*
G03X102151Y336120I289J277D01*
G02X102187Y334221I1049J-930D01*
G37*
G36*
G01X1497795Y336516D02*
G03X1498283Y336166I398J40D01*
G02X1497205Y334660I317J-1366D01*
G03X1496717Y335010I-398J-40D01*
G02X1495105Y336914I-317J1366D01*
G03X1494893Y337435I-369J153D01*
G02X1494589Y339834I552J1289D01*
G03X1494670Y340384I-244J317D01*
G02X1496666Y340090I1140J816D01*
G03X1496585Y339540I244J-317D01*
G02X1496620Y339488I-1145J-808D01*
G03X1496939Y339466I168J109D01*
G02X1498126Y337150I1058J-920D01*
G03X1497771Y336668I36J-398D01*
G02X1497795Y336516I-1371J-294D01*
G37*
G36*
G01X1473398Y336467D02*
G03X1473409Y335868I270J-295D01*
G02X1471552Y335833I-909J-1068D01*
G03X1471541Y336432I-270J295D01*
G02X1473398Y336467I909J1068D01*
G37*
G36*
G01X1416971Y334489D02*
G03Y333911I277J-289D01*
G02X1415029I-971J-1011D01*
G03Y334489I-277J289D01*
G02Y336511I971J1011D01*
G03Y337089I-277J289D01*
G02X1416971I971J1011D01*
G03Y336511I277J-289D01*
G02Y334489I-971J-1011D01*
G37*
G36*
G01X1570182Y333131D02*
G03Y332553I277J-289D01*
G02X1568240I-971J-1011D01*
G03Y333131I-277J289D01*
G02X1570182I971J1011D01*
G37*
G36*
G01X1548600Y333102D02*
G03X1548734Y332556I343J-205D01*
G02X1546798Y332082I-733J-1195D01*
G03X1546664Y332628I-343J205D01*
G02X1548600Y333102I733J1195D01*
G37*
G36*
G01X773426Y331585D02*
G03X773170Y331092I128J-379D01*
G02X770343Y331241I-1440J-427D01*
G03X770038Y331789I-369J153D01*
G02X771437Y334227I240J1483D01*
G03X771999Y334172I309J255D01*
G02X774055Y334025I950J-1163D01*
G03X774640Y334021I294J271D01*
G02X776466Y331678I1091J-1033D01*
G03X776330Y331104I195J-349D01*
G02X774427Y331504I-1159J-788D01*
G03X774533Y332084I-213J339D01*
G02X774498Y332133I1204J897D01*
G03X774171Y332135I-164J-114D01*
G02X773426Y331585I-1221J875D01*
G37*
G36*
G01X1526765Y328878D02*
G03X1526213Y328768I-220J-334D01*
G02X1525823Y330723I-1162J785D01*
G03X1526375Y330833I220J334D01*
G02X1526765Y328878I1162J-785D01*
G37*
G36*
G01X1560995Y330789D02*
G03Y330211I277J-289D01*
G02X1559053I-971J-1011D01*
G03Y330789I-277J289D01*
G02X1560995I971J1011D01*
G37*
G36*
G01X1654016Y328102D02*
G03X1654038Y327534I292J-273D01*
G02X1652066Y327457I-947J-1034D01*
G03X1652044Y328025I-292J273D01*
G02X1654016Y328102I947J1034D01*
G37*
G36*
G01X645706Y326977D02*
G03X645589Y327576I-312J250D01*
G02X647366Y327923I683J1224D01*
G03X647483Y327324I312J-250D01*
G02X645706Y326977I-683J-1224D01*
G37*
G36*
G01X1493775Y327586D02*
G03X1493930Y327048I352J-190D01*
G02X1492005Y326492I-690J-1220D01*
G03X1491850Y327030I-352J190D01*
G02X1493775Y327586I690J1220D01*
G37*
G36*
G01X376986Y330493D02*
G03X377603Y330507I303J261D01*
G02X379341Y328185I1182J-927D01*
G03X379154Y327595I148J-372D01*
G02X376831Y325716I-1260J-818D01*
G03X376269Y325720I-283J-283D01*
G02X374123Y325775I-1046J1078D01*
G03X373528Y325764I-293J-272D01*
G02X371284Y325731I-1137J982D01*
G03X370728Y325764I-295J-270D01*
G02X368647Y325881I-980J1138D01*
G03X368094Y325913I-293J-272D01*
G02X368087Y325906I-1062J1055D01*
G03X368024Y325360I257J-306D01*
G02X365856Y325610I-1202J-901D01*
G03X365919Y326156I-257J306D01*
G02X368222Y328078I1202J900D01*
G03X368775Y328046I293J272D01*
G02X370855Y327917I973J-1144D01*
G03X371411Y327884I295J270D01*
G02X373491Y327769I980J-1138D01*
G03X374086Y327780I293J272D01*
G02X374473Y328099I1135J-983D01*
G03X374604Y328670I-200J346D01*
G02X376986Y330493I1244J842D01*
G37*
G36*
G01X1017937Y325288D02*
G03X1017717Y324783I156J-368D01*
G02X1015855Y325596I-1318J-479D01*
G03X1016075Y326101I-156J368D01*
G02X1018366Y327590I1318J480D01*
G03X1018920I277J288D01*
G02X1020866I973J-1010D01*
G03X1021420I277J288D01*
G02X1023366I973J-1010D01*
G03X1023920I277J288D01*
G02X1024287Y327844I971J-1011D01*
G03X1024479Y328371I-172J361D01*
G02X1026567Y330094I1276J580D01*
G03X1027153Y330233I232J326D01*
G02X1028642Y328200I1240J-653D01*
G03X1028420Y327534I71J-394D01*
G02X1026420Y325570I-1027J-955D01*
G03X1025866I-277J-288D01*
G02X1023920I-973J1010D01*
G03X1023366I-277J-288D01*
G02X1021420I-973J1010D01*
G03X1020866I-277J-288D01*
G02X1018920I-973J1010D01*
G03X1018366I-277J-288D01*
G02X1017937Y325288I-972J1011D01*
G37*
G36*
G01X1543591Y324428D02*
G03X1543924Y323984I397J-49D01*
G02X1542309Y322772I-224J-1384D01*
G03X1541976Y323216I-397J49D01*
G02X1543591Y324428I224J1384D01*
G37*
G36*
G01X1590800Y323413D02*
G03X1591385Y323202I378J131D01*
G02X1590786Y321542I725J-1200D01*
G03X1590201Y321753I-378J-131D01*
G02X1590800Y323413I-725J1200D01*
G37*
G36*
G01X688320Y318775D02*
G03X688262Y318235I263J-301D01*
G02X686218Y318455I-1124J-838D01*
G03X686276Y318995I-263J301D01*
G02X688320Y318775I1124J838D01*
G37*
G36*
G01X647783Y319011D02*
G03Y318389I252J-311D01*
G02X646017I-883J-1089D01*
G03Y319011I-252J311D01*
G02X647783I883J1089D01*
G37*
G36*
G01X115528Y319963D02*
G03X115764Y320490I-135J377D01*
G02X117535Y319696I1299J526D01*
G03X117299Y319169I135J-377D01*
G02X117398Y318750I-1299J-528D01*
G03X117844Y318383I399J30D01*
G02X116610Y316884I164J-1392D01*
G03X116164Y317251I-399J-30D01*
G02X115528Y319963I-163J1392D01*
G37*
G36*
G01X1549195Y318450D02*
G03X1549443Y317930I374J-141D01*
G02X1547687Y317092I-443J-1330D01*
G03X1547439Y317612I-374J141D01*
G02X1549195Y318450I443J1330D01*
G37*
G36*
G01X82378Y317044D02*
G03X82972Y317036I301J264D01*
G02X82946Y315158I1028J-953D01*
G03X82352Y315166I-301J-264D01*
G02X82378Y317044I-1028J953D01*
G37*
G36*
G01X64971Y315489D02*
G03Y314911I277J-289D01*
G02X63029I-971J-1011D01*
G03Y315489I-277J289D01*
G02X64971I971J1011D01*
G37*
G36*
G01X1568271Y314778D02*
G03X1568629Y314283I388J-96D01*
G02X1567163Y313224I-105J-1398D01*
G03X1566805Y313719I-388J96D01*
G02X1565900Y314144I104J1398D01*
G03X1565346Y314165I-288J-277D01*
G02X1565421Y316183I-935J1045D01*
G03X1565975Y316162I288J277D01*
G02X1568271Y314778I935J-1045D01*
G37*
G36*
G01X1517245Y312208D02*
G03X1517209Y311654I269J-296D01*
G02X1515194Y311785I-1071J-905D01*
G03X1515230Y312339I-269J296D01*
G02X1517245Y312208I1071J905D01*
G37*
G36*
G01X1640423Y311762D02*
G03Y311208I288J-277D01*
G02X1638403I-1010J-973D01*
G03Y311762I-288J277D01*
G02X1640423I1010J973D01*
G37*
G36*
G01X1047773Y310863D02*
G03X1048390Y310862I309J254D01*
G02X1048386Y308951I1157J-958D01*
G03X1047769Y308952I-309J-254D01*
G02X1047773Y310863I-1157J958D01*
G37*
G36*
G01X1040555Y310849D02*
G03X1041179Y310848I312J250D01*
G02X1041175Y308965I1168J-944D01*
G03X1040551Y308966I-312J-250D01*
G02X1040555Y310849I-1168J944D01*
G37*
G36*
G01X405294Y310843D02*
G03X405920Y310841I314J248D01*
G02X405917Y308971I1174J-937D01*
G03X405291Y308973I-314J-248D01*
G02X405294Y310843I-1174J937D01*
G37*
G36*
G01X383682Y310833D02*
G03X384312Y310831I316J245D01*
G02X384309Y308981I1182J-927D01*
G03X383679Y308983I-316J-245D01*
G02X383682Y310833I-1182J927D01*
G37*
G36*
G01X1565345Y310023D02*
G03X1565339Y309424I262J-302D01*
G02X1563482Y309443I-939J-1041D01*
G03X1563488Y310042I-262J302D01*
G02X1565345Y310023I939J1041D01*
G37*
G36*
G01X714980Y309887D02*
G03Y309333I288J-277D01*
G02X712960I-1010J-973D01*
G03Y309887I-288J277D01*
G02X714980I1010J973D01*
G37*
G36*
G01X455158Y309368D02*
G03Y308814I288J-277D01*
G02X452981Y307064I-1010J-972D01*
G03X452426Y307175I-333J-222D01*
G02X450266Y308104I-778J1166D01*
G03X449789Y308428I-394J-67D01*
G02X448527Y308790I-289J1372D01*
G03X447973I-277J-288D01*
G02Y310810I-973J1010D01*
G03X448527I277J288D01*
G02X450882Y310037I973J-1010D01*
G03X451359Y309713I394J67D01*
G02X452218Y309622I289J-1372D01*
G03X452773Y310066I163J365D01*
G02X455158Y309368I1375J275D01*
G37*
G36*
G01X1561087Y309435D02*
G03X1561176Y308850I311J-252D01*
G02X1559310Y308565I-776J-1167D01*
G03X1559221Y309150I-311J252D01*
G02X1561087Y309435I776J1167D01*
G37*
G36*
G01X849497Y305804D02*
G03X848867I-315J-246D01*
G02X846586Y307754I-1185J923D01*
G03Y308300I-292J273D01*
G02X846624Y310393I1096J1027D01*
G03Y310961I-282J284D01*
G02X846586Y313054I1058J1066D01*
G03Y313600I-292J273D01*
G02X848867Y315550I1096J1027D01*
G03X849497I315J246D01*
G02X851867I1185J-923D01*
G03X852497I315J246D01*
G02X854867I1185J-923D01*
G03X855497I315J246D01*
G02X857778Y313600I1185J-923D01*
G03Y313054I292J-273D01*
G02X857740Y310961I-1096J-1027D01*
G03Y310393I282J-284D01*
G02X857778Y308300I-1058J-1066D01*
G03Y307754I292J-273D01*
G02X855497Y305804I-1096J-1027D01*
G03X854867I-315J-246D01*
G02X852497I-1185J923D01*
G03X851867I-315J-246D01*
G02X849497I-1185J923D01*
G37*
G36*
G01X1306859Y308248D02*
G03X1306876Y307664I281J-284D01*
G02X1304964Y307608I-926J-1053D01*
G03X1304947Y308192I-281J284D01*
G02X1304824Y308315I928J1051D01*
G03X1304271Y308358I-299J-266D01*
G02X1304429Y310371I-891J1083D01*
G03X1304982Y310328I299J266D01*
G02X1306859Y308248I891J-1083D01*
G37*
G36*
G01X198962Y305776D02*
G03X198423Y305919I-343J-205D01*
G02X196657Y308323I-739J1308D01*
G03X196667Y308898I-273J292D01*
G02X198757Y308863I1063J1061D01*
G03X198747Y308288I273J-292D01*
G02X198973Y307999I-1061J-1063D01*
G03X199512Y307856I343J205D01*
G02X198962Y305776I739J-1308D01*
G37*
G36*
G01X1537386Y305392D02*
G03X1537870Y305102I388J98D01*
G02X1536847Y303397I336J-1361D01*
G03X1536363Y303687I-388J-98D01*
G02X1537386Y305392I-336J1361D01*
G37*
G36*
G01X1637893Y304142D02*
G03X1637906Y303586I294J-271D01*
G02X1635890Y303537I-984J-998D01*
G03X1635877Y304093I-294J271D01*
G02X1637893Y304142I984J998D01*
G37*
G36*
G01X1564358Y302020D02*
G03X1564356Y302642I-253J310D01*
G02X1566121Y302648I879J1092D01*
G03X1566123Y302026I253J-310D01*
G02X1564358Y302020I-879J-1092D01*
G37*
G36*
G01X1584487Y302124D02*
G03Y301556I281J-284D01*
G02X1582513I-987J-996D01*
G03Y302124I-281J284D01*
G02X1584487I987J996D01*
G37*
G36*
G01X1300631Y300220D02*
G03X1300624Y299612I256J-307D01*
G02X1298804Y299635I-923J-1055D01*
G03X1298811Y300243I-256J307D01*
G02X1300631Y300220I923J1055D01*
G37*
G36*
G01X657627Y294985D02*
G03X657426Y295549I-350J193D01*
G02X659176Y296170I524J1301D01*
G03X659377Y295606I350J-193D01*
G02X657627Y294985I-524J-1301D01*
G37*
G36*
G01X1026147Y293881D02*
G03X1026758Y293878I307J256D01*
G02X1026749Y291941I1144J-974D01*
G03X1026138Y291944I-307J-256D01*
G02X1026147Y293881I-1144J974D01*
G37*
G36*
G01X405427Y293983D02*
G03X406022Y293956I310J253D01*
G02X405933Y291951I1072J-1052D01*
G03X405338Y291978I-310J-253D01*
G02X405427Y293983I-1072J1052D01*
G37*
G36*
G01X398128Y293919D02*
G03X398758Y293887I327J229D01*
G02X398663Y292043I1136J-983D01*
G03X398033Y292075I-327J-229D01*
G02X398128Y293919I-1136J983D01*
G37*
G36*
G01X383861Y294061D02*
G03X384464Y293997I329J227D01*
G02X384258Y292050I1030J-1093D01*
G03X383655Y292114I-329J-227D01*
G02X383861Y294061I-1030J1093D01*
G37*
G36*
G01X372760Y291927D02*
G03X372204Y291892I-260J-304D01*
G02X369861Y292046I-1110J1012D01*
G03X369235Y292085I-328J-228D01*
G02X369349Y293945I-1119J1002D01*
G03X369975Y293906I328J228D01*
G02X372070Y294045I1119J-1002D01*
G03X372626Y294080I260J304D01*
G02X372760Y291927I1110J-1012D01*
G37*
G36*
G01X1637832Y293973D02*
G03Y293419I288J-277D01*
G02X1635812I-1010J-973D01*
G03Y293973I-288J277D01*
G02X1635853Y295959I1010J973D01*
G03X1635876Y296514I-276J289D01*
G02X1637894Y296431I1049J930D01*
G03X1637871Y295876I276J-289D01*
G02X1637832Y293973I-1049J-930D01*
G37*
G36*
G01X1305637Y292913D02*
G03X1305262Y292476I23J-399D01*
G02X1303787Y293745I-1396J-131D01*
G03X1304162Y294182I-23J399D01*
G02X1305637Y292913I1396J131D01*
G37*
G36*
G01X1335501Y292918D02*
G03X1336123Y292909I315J247D01*
G02X1336099Y291144I1077J-897D01*
G03X1335477Y291153I-315J-247D01*
G02X1335501Y292918I-1077J897D01*
G37*
G36*
G01X49683Y291311D02*
G03Y290689I252J-311D01*
G02X47917I-883J-1089D01*
G03Y291311I-252J311D01*
G02X49683I883J1089D01*
G37*
G36*
G01X1534824Y287709D02*
G03X1534841Y287125I281J-284D01*
G02X1532928Y287070I-927J-1052D01*
G03X1532911Y287654I-281J284D01*
G02X1534824Y287709I927J1052D01*
G37*
G36*
G01X1548006Y287663D02*
G03X1548358Y287223I398J-43D01*
G02X1546805Y285979I-159J-1393D01*
G03X1546453Y286419I-398J43D01*
G02X1548006Y287663I159J1393D01*
G37*
G36*
G01X637881Y287185D02*
G03X637839Y286610I255J-308D01*
G02X636064Y286864I-1040J-940D01*
G03X636087Y287187I-105J170D01*
G02X635967Y287300I900J1076D01*
G03X635645Y287257I-146J-137D01*
G02X635280Y289012I-1238J658D01*
G03X635852Y289090I249J313D01*
G02X637881Y287185I1133J-827D01*
G37*
G36*
G01X115528Y287963D02*
G03X115764Y288490I-135J377D01*
G02X117535Y287696I1299J526D01*
G03X117299Y287169I135J-377D01*
G02X117398Y286750I-1299J-528D01*
G03X117844Y286383I399J30D01*
G02X116610Y284884I164J-1392D01*
G03X116164Y285251I-399J-30D01*
G02X115528Y287963I-163J1392D01*
G37*
G36*
G01X663911Y283917D02*
G03X663289I-311J-252D01*
G02X660957Y285448I-1089J883D01*
G03X660742Y286007I-355J184D01*
G02X662475Y286673I490J1314D01*
G03X662690Y286114I355J-184D01*
G02X663289Y285683I-491J-1314D01*
G03X663911I311J252D01*
G02Y283917I1089J-883D01*
G37*
G36*
G01X1580115Y283805D02*
G03X1579560Y283799I-274J-291D01*
G02X1579539Y285819I-983J1000D01*
G03X1580094Y285825I274J291D01*
G02X1580115Y283805I983J-1000D01*
G37*
G36*
G01X1570790Y286064D02*
G03X1571021Y286576I-144J373D01*
G02X1573704Y286758I1315J487D01*
G03X1574027Y286277I391J-87D01*
G02X1572875Y283833I-237J-1382D01*
G03X1572321Y283802I-261J-303D01*
G02X1570790Y286064I-1028J953D01*
G37*
G36*
G01X560979Y284997D02*
G03X560608Y284565I28J-399D01*
G02X559116Y285846I-1397J-118D01*
G03X559487Y286278I-28J399D01*
G02X560979Y284997I1397J118D01*
G37*
G36*
G01X1315646Y285315D02*
G03X1315579Y284745I243J-318D01*
G02X1313636Y284974I-1089J-883D01*
G03X1313703Y285544I-243J318D01*
G02X1315646Y285315I1089J883D01*
G37*
G36*
G01X69311Y282571D02*
G03X69889I289J277D01*
G02Y280629I1011J-971D01*
G03X69311I-289J-277D01*
G02Y282571I-1011J971D01*
G37*
G36*
G01X1399552Y283306D02*
G03X1399680Y282764I343J-205D01*
G02X1397721Y282299I-754J-1182D01*
G03X1397593Y282841I-343J205D01*
G02X1399552Y283306I754J1182D01*
G37*
G36*
G01X1097703Y279975D02*
G03X1098242I269J295D01*
G02X1098239Y277904I944J-1037D01*
G03X1097700I-269J-295D01*
G02X1097703Y279975I-944J1037D01*
G37*
G36*
G01X448798Y277912D02*
G03X448198I-300J-265D01*
G02Y279770I-1050J929D01*
G03X448798I300J265D01*
G02Y277912I1050J-929D01*
G37*
G36*
G01X1434372Y279771D02*
G03Y279217I288J-277D01*
G02X1432352I-1010J-973D01*
G03Y279771I-288J277D01*
G02X1434372I1010J973D01*
G37*
G36*
G01X662303Y279878D02*
G03X662721Y279485I400J6D01*
G02X661384Y278062I65J-1401D01*
G03X660966Y278455I-400J-6D01*
G02X662303Y279878I-65J1401D01*
G37*
G36*
G01X60473Y279010D02*
G03X61027I277J288D01*
G02Y276990I973J-1010D01*
G03X60473I-277J-288D01*
G02Y279010I-973J1010D01*
G37*
G36*
G01X648422Y279263D02*
G03X648418Y278671I267J-298D01*
G02X646534Y278684I-949J-1032D01*
G03X646538Y279276I-267J298D01*
G02X648422Y279263I949J1032D01*
G37*
G36*
G01X1333680Y274524D02*
X1330171D01*
G02Y277546I0J1511D01*
G01X1333681D01*
G02X1335192Y276045I0J-1512D01*
G01Y275950D01*
X1335182Y275866D01*
G02X1333680Y274524I-1502J169D01*
G37*
G36*
G01X452389Y274629D02*
G03X451811I-289J-277D01*
G02Y276571I-1011J971D01*
G03X452389I289J277D01*
G02Y274629I1011J-971D01*
G37*
G36*
G01X778572Y275068D02*
G03X777973Y274913I-236J-323D01*
G02X777528Y276632I-1273J588D01*
G03X778127Y276787I236J323D01*
G02X778572Y275068I1273J-588D01*
G37*
G36*
G01X1637694Y276342D02*
G03Y275788I288J-277D01*
G02X1635674I-1010J-973D01*
G03Y276342I-288J277D01*
G02Y278288I1010J973D01*
G03Y278842I-288J277D01*
G02X1637694I1010J973D01*
G03Y278288I288J-277D01*
G02Y276342I-1010J-973D01*
G37*
G36*
G01X824279Y273987D02*
G03X823649I-315J-246D01*
G02X821368Y275937I-1185J923D01*
G03Y276483I-292J273D01*
G02Y278537I1096J1027D01*
G03Y279083I-292J273D01*
G02X823649Y281033I1096J1027D01*
G03X824279I315J246D01*
G02X826649I1185J-923D01*
G03X827279I315J246D01*
G02X829649I1185J-923D01*
G03X830279I315J246D01*
G02X832649I1185J-923D01*
G03X833279I315J246D01*
G02X835570Y281127I1185J-923D01*
G03X836158I294J270D01*
G02X838370I1106J-1017D01*
G03X838958I294J270D01*
G02X841160Y279083I1106J-1017D01*
G03Y278537I292J-273D01*
G02X838958Y276493I-1096J-1027D01*
G03X838370I-294J-270D01*
G02X838360Y276483I-1067J1056D01*
G03Y275937I292J-273D01*
G02X836158Y273893I-1096J-1027D01*
G03X835570I-294J-270D01*
G02X833279Y273987I-1106J1017D01*
G03X832649I-315J-246D01*
G02X830279I-1185J923D01*
G03X829649I-315J-246D01*
G02X827279I-1185J923D01*
G03X826649I-315J-246D01*
G02X824279I-1185J923D01*
G37*
G36*
G01X850197Y273504D02*
G03X849567I-315J-246D01*
G02X847286Y275454I-1185J923D01*
G03Y276000I-292J273D01*
G02X847324Y278093I1096J1027D01*
G03Y278661I-282J284D01*
G02X847286Y280754I1058J1066D01*
G03Y281300I-292J273D01*
G02X849567Y283250I1096J1027D01*
G03X850197I315J246D01*
G02X852567I1185J-923D01*
G03X853197I315J246D01*
G02X855567I1185J-923D01*
G03X856197I315J246D01*
G02X858478Y281300I1185J-923D01*
G03Y280754I292J-273D01*
G02X858440Y278661I-1096J-1027D01*
G03Y278093I282J-284D01*
G02X858478Y276000I-1058J-1066D01*
G03Y275454I292J-273D01*
G02X856197Y273504I-1096J-1027D01*
G03X855567I-315J-246D01*
G02X853197I-1185J923D01*
G03X852567I-315J-246D01*
G02X850197I-1185J923D01*
G37*
G36*
G01X1340248Y270244D02*
X1336448D01*
G02Y273266I0J1511D01*
G01X1340249D01*
G02X1341760Y271765I0J-1512D01*
G01Y271670D01*
X1341750Y271586D01*
G02X1340248Y270244I-1502J169D01*
G37*
G36*
G01X1412345Y270158D02*
G03X1412700Y269670I390J-90D01*
G02X1411213Y268588I-121J-1397D01*
G03X1410858Y269076I-390J90D01*
G02X1412345Y270158I121J1397D01*
G37*
G36*
G01X1010655Y269874D02*
G03X1011064Y269502I399J28D01*
G02X1009701Y268003I36J-1402D01*
G03X1009292Y268375I-399J-28D01*
G02X1007949Y269270I-36J1402D01*
G03X1007382Y269475I-373J-145D01*
G02X1005785Y271762I-682J1225D01*
G03X1005777Y272375I-261J303D01*
G02X1007580Y272398I888J1085D01*
G03X1007588Y271785I261J-303D01*
G02X1008007Y271207I-888J-1085D01*
G03X1008574Y271002I373J145D01*
G02X1010655Y269874I682J-1225D01*
G37*
G36*
G01X361047D02*
G03X361456Y269502I399J28D01*
G02X360093Y268003I36J-1402D01*
G03X359684Y268375I-399J-28D01*
G02X358341Y269270I-36J1402D01*
G03X357774Y269475I-373J-145D01*
G02X356177Y271762I-682J1225D01*
G03X356169Y272375I-261J303D01*
G02X357972Y272398I888J1085D01*
G03X357980Y271785I261J-303D01*
G02X358399Y271207I-888J-1085D01*
G03X358966Y271002I373J145D01*
G02X361047Y269874I682J-1225D01*
G37*
G36*
G01X1347468Y266584D02*
X1343668D01*
G02Y269606I0J1511D01*
G01X1347469D01*
G02X1348980Y268105I0J-1512D01*
G01Y268010D01*
X1348970Y267926D01*
G02X1347468Y266584I-1502J169D01*
G37*
G36*
G01X748148Y268571D02*
G03X748170Y269192I-241J319D01*
G02X749932Y269129I920J1058D01*
G03X749910Y268508I241J-319D01*
G02X748148Y268571I-920J-1058D01*
G37*
G36*
G01X773888Y267630D02*
G03X774434Y267508I335J218D01*
G02X774041Y265487I737J-1192D01*
G03X773489Y265578I-323J-237D01*
G02X771498Y265822I-859J1232D01*
G03X770869Y265788I-301J-263D01*
G02X769071Y268038I-1232J859D01*
G03X769249Y268636I-151J370D01*
G02X771051Y268098I1236J853D01*
G03X770873Y267500I151J-370D01*
G02X770919Y267430I-1232J-860D01*
G03X771271Y267449I171J104D01*
G02X773888Y267630I1359J-639D01*
G37*
G36*
G01X1452990Y267710D02*
G03X1453522Y267465I380J125D01*
G02X1452703Y265803I534J-1296D01*
G03X1452184Y266075I-386J-105D01*
G02X1452990Y267710I-431J1229D01*
G37*
G36*
G01X1356268Y264184D02*
X1352468D01*
G02Y267206I0J1511D01*
G01X1356269D01*
G02X1357780Y265705I0J-1512D01*
G01Y265610D01*
X1357770Y265526D01*
G02X1356268Y264184I-1502J170D01*
G37*
G36*
G01X1217244Y267082D02*
G03Y266528I288J-277D01*
G02X1215224I-1010J-973D01*
G03Y267082I-288J277D01*
G02X1217244I1010J973D01*
G37*
G36*
G01X567936D02*
G03Y266528I288J-277D01*
G02X565916I-1010J-973D01*
G03Y267082I-288J277D01*
G02X567936I1010J973D01*
G37*
G36*
G01X1381031Y264088D02*
X1377522D01*
G02Y267112I0J1512D01*
G01X1381032D01*
G02X1382542Y265610I-1J-1512D01*
G01Y265515D01*
X1382533Y265431D01*
G02X1381031Y264088I-1502J168D01*
G37*
G36*
G01X1362803Y267036D02*
X1366313D01*
G02X1367824Y265535I0J-1512D01*
G01Y265440D01*
X1367814Y265356D01*
G02X1366312Y264014I-1502J169D01*
G01X1362803D01*
G02Y267036I1J1511D01*
G37*
G36*
G01X406409Y263976D02*
G03X405779I-315J-246D01*
G02Y265822I-1185J923D01*
G03X406409I315J246D01*
G02Y263976I1185J-923D01*
G37*
G36*
G01X1074342Y265966D02*
G03X1074903Y265919I304J260D01*
G02X1074723Y263791I962J-1153D01*
G03X1074162Y263838I-304J-260D01*
G02X1072085Y263984I-963J1153D01*
G03X1071476Y263965I-296J-268D01*
G02X1071415Y265907I-1176J935D01*
G03X1072024Y265926I296J268D01*
G02X1074342Y265966I1175J-935D01*
G37*
G36*
G01X424803Y263696D02*
G03X424210Y263694I-296J-269D01*
G02X421878Y263812I-1118J1003D01*
G03X421268Y263855I-323J-235D01*
G02X419004Y263975I-1080J1044D01*
G03X418374I-315J-247D01*
G02X416005Y263977I-1184J924D01*
G03X415373I-316J-246D01*
G02X413003Y263976I-1185J922D01*
G03X412373I-315J-246D01*
G02Y265822I-1185J923D01*
G03X413003I315J246D01*
G02X415373Y265821I1185J-923D01*
G03X416005I316J246D01*
G02X418374Y265823I1185J-922D01*
G03X419004I315J247D01*
G02X421402Y265784I1184J-924D01*
G03X422012Y265741I323J235D01*
G02X424200Y265711I1080J-1044D01*
G03X424793Y265713I296J269D01*
G02X424803Y263696I1118J-1003D01*
G37*
G36*
G01X437497Y263882D02*
G03X437537Y263336I311J-252D01*
G02X435351Y263176I-1018J-1104D01*
G03X435311Y263722I-311J252D01*
G02X437497Y263882I1018J1104D01*
G37*
G36*
G01X1628763Y261318D02*
G03X1628481Y260782I90J-390D01*
G02X1626286Y261349I-1304J-515D01*
G03X1626299Y261955I-255J309D01*
G02X1628763Y261318I1843J2044D01*
G37*
G36*
G01X1160308Y261401D02*
G03X1160313Y260793I262J-302D01*
G02X1158492Y260779I-902J-1073D01*
G03X1158487Y261387I-262J302D01*
G02X1160308Y261401I902J1073D01*
G37*
G36*
G01X1455205Y261089D02*
G03X1455127Y260534I244J-317D01*
G02X1453298Y260914I-1127J-834D01*
G03X1453342Y261226I-100J173D01*
G02X1453256Y261323I1005J978D01*
G03X1452944I-156J-125D01*
G02X1452823Y263210I-1094J877D01*
G03X1453377I277J288D01*
G02X1455205Y261089I972J-1010D01*
G37*
G36*
G01X1226918Y260827D02*
G03Y260273I288J-277D01*
G02X1224898I-1010J-973D01*
G03Y260827I-288J277D01*
G02X1226918I1010J973D01*
G37*
G36*
G01X576610D02*
G03Y260273I288J-277D01*
G02X574590I-1010J-973D01*
G03Y260827I-288J277D01*
G02X576610I1010J973D01*
G37*
G36*
G01X510478Y259111D02*
G03X510102Y258672I22J-399D01*
G02X508630Y259932I-1395J-140D01*
G03X509006Y260371I-22J399D01*
G02X510478Y259111I1395J140D01*
G37*
G36*
G01X1494858Y254727D02*
G03X1494307Y254648I-235J-324D01*
G02X1494023Y256641I-1108J859D01*
G03X1494574Y256720I235J324D01*
G02X1494678Y256839I1106J-861D01*
G03X1494681Y257394I-287J279D01*
G02X1496700Y257383I1015J967D01*
G03X1496697Y256828I287J-279D01*
G02X1494858Y254727I-1015J-967D01*
G37*
G36*
G01X1465810Y255243D02*
G03X1465890Y254676I316J-244D01*
G02X1463781Y252976I-827J-1132D01*
G03X1463257Y253182I-366J-161D01*
G02X1462861Y255863I-553J1288D01*
G03X1463304Y256225I44J398D01*
G02X1465810Y255243I1396J-125D01*
G37*
G36*
G01X621974Y254930D02*
G03X621904Y254340I231J-327D01*
G02X620041Y254561I-1054J-924D01*
G03X620111Y255151I-231J327D01*
G02X621974Y254930I1054J924D01*
G37*
G36*
G01X1275468Y254991D02*
G03X1275795Y254508I390J-88D01*
G02X1274209Y253432I-218J-1385D01*
G03X1273882Y253915I-390J88D01*
G02X1275468Y254991I218J1385D01*
G37*
G36*
G01X116610Y252884D02*
G03X116164Y253251I-399J-30D01*
G02X115528Y255963I-163J1392D01*
G03X115764Y256490I-135J377D01*
G02X117535Y255696I1299J526D01*
G03X117299Y255169I135J-377D01*
G02X117398Y254750I-1299J-528D01*
G03X117844Y254383I399J30D01*
G02X116610Y252884I164J-1392D01*
G37*
G36*
G01X1469444Y253888D02*
G03X1469999Y253876I284J282D01*
G02X1469956Y251858I951J-1030D01*
G03X1469401Y251870I-284J-282D01*
G02X1469444Y253888I-951J1030D01*
G37*
G36*
G01X766693Y253259D02*
G03X766354Y252751I45J-397D01*
G02X764846Y253756I-1347J-388D01*
G03X765185Y254264I-45J397D01*
G02X765602Y255701I1347J388D01*
G03X765624Y256278I-266J299D01*
G02X767562Y256203I1008J974D01*
G03X767540Y255626I266J-299D01*
G02X766693Y253259I-1008J-974D01*
G37*
G36*
G01X1479777Y253333D02*
G03X1479666Y252778I222J-333D01*
G02X1477723Y253167I-1166J-778D01*
G03X1477834Y253722I-222J333D01*
G02X1477627Y254782I1166J778D01*
G03X1477271Y255261I-392J80D01*
G02X1478770Y256375I126J1396D01*
G03X1479126Y255896I392J-80D01*
G02X1479777Y253333I-126J-1396D01*
G37*
G36*
G01X1434852Y253400D02*
G03X1434985Y252823I328J-228D01*
G02X1433148Y252400I-686J-1223D01*
G03X1433015Y252977I-328J228D01*
G02X1434852Y253400I686J1223D01*
G37*
G36*
G01X1817282Y248886D02*
X1812281D01*
G02X1812282Y252110I1J1612D01*
G01X1817282D01*
G02X1818894Y250508I0J-1612D01*
G01Y250413D01*
X1818884Y250328D01*
G02X1817282Y248886I-1602J169D01*
G37*
G36*
G01X1798384D02*
X1793384D01*
G02Y252110I0J1612D01*
G01X1798385D01*
G02X1799996Y250508I-1J-1612D01*
G01Y250413D01*
X1799986Y250328D01*
G02X1798384Y248886I-1602J169D01*
G37*
G36*
G01X1825702Y251794D02*
G03X1826143Y251395I400J-1D01*
G02X1824885Y250006I144J-1395D01*
G03X1824444Y250405I-400J1D01*
G02X1825702Y251794I-144J1395D01*
G37*
G36*
G01X1736815Y249077D02*
G03X1736185I-315J-246D01*
G02Y250923I-1185J923D01*
G03X1736815I315J246D01*
G02X1739185I1185J-923D01*
G03X1739815I315J246D01*
G02Y249077I1185J-923D01*
G03X1739185I-315J-246D01*
G02X1736815I-1185J923D01*
G37*
G36*
G01X1690282Y249679D02*
G03X1689813Y249382I-80J-392D01*
G02X1687183Y249118I-1362J334D01*
G03X1686664Y249315I-362J-171D01*
G02X1685186Y249552I-551J1289D01*
G03X1684632Y249528I-265J-300D01*
G02X1684542Y251545I-1017J965D01*
G03X1685096Y251569I265J300D01*
G02X1687381Y251202I1017J-965D01*
G03X1687900Y251005I362J171D01*
G02X1688734Y251089I551J-1289D01*
G03X1689203Y251386I80J392D01*
G02X1690282Y249679I1362J-334D01*
G37*
G36*
G01X1597653Y247276D02*
G03X1598245Y247267I300J264D01*
G02X1598217Y245384I1025J-957D01*
G03X1597625Y245393I-300J-264D01*
G02X1597653Y247276I-1025J957D01*
G37*
G36*
G01X1468298Y245076D02*
G03X1467721Y244868I-201J-345D01*
G02X1467110Y246561I-1317J482D01*
G03X1467687Y246769I201J345D01*
G02X1470015Y247258I1317J-482D01*
G03X1470593I289J277D01*
G02Y245316I1011J-971D01*
G03X1470015I-289J-277D01*
G02X1468298Y245076I-1011J971D01*
G37*
G36*
G01X1510804Y246222D02*
G03X1510800Y245658I282J-284D01*
G02X1508810Y245669I-1000J-982D01*
G03X1508814Y246233I-282J284D01*
G02X1510804Y246222I1000J982D01*
G37*
G36*
G01X89773Y243304D02*
G03X89227I-273J-292D01*
G02X87277Y245585I-1027J1096D01*
G03Y246215I-246J315D01*
G02Y248585I923J1185D01*
G03Y249215I-246J315D01*
G02Y251585I923J1185D01*
G03Y252215I-246J315D01*
G02X87228Y254545I923J1185D01*
G03Y255155I-259J305D01*
G02X87104Y257327I972J1145D01*
G03Y257873I-292J273D01*
G02X89227Y259996I1096J1027D01*
G03X89773I273J292D01*
G02X91827I1027J-1096D01*
G03X92373I273J292D01*
G02X94427I1027J-1096D01*
G03X94973I273J292D01*
G02X97027I1027J-1096D01*
G03X97573I273J292D01*
G02X99696Y257873I1027J-1096D01*
G03Y257327I292J-273D01*
G02X99572Y255155I-1096J-1027D01*
G03Y254545I259J-305D01*
G02X99523Y252215I-972J-1145D01*
G03Y251585I246J-315D01*
G02Y249215I-923J-1185D01*
G03Y248585I246J-315D01*
G02Y246215I-923J-1185D01*
G03Y245585I246J-315D01*
G02X97573Y243304I-923J-1185D01*
G03X97027I-273J-292D01*
G02X94973I-1027J1096D01*
G03X94427I-273J-292D01*
G02X92373I-1027J1096D01*
G03X91827I-273J-292D01*
G02X89773I-1027J1096D01*
G37*
G36*
G01X1662588Y245377D02*
G03X1662981Y244984I400J7D01*
G02X1661554Y243557I-25J-1402D01*
G03X1661161Y243950I-400J-7D01*
G02X1662588Y245377I25J1402D01*
G37*
G36*
G01X1215804Y244399D02*
G03X1216413Y244396I306J258D01*
G02X1216404Y242579I1063J-914D01*
G03X1215795Y242582I-306J-258D01*
G02X1215804Y244399I-1063J914D01*
G37*
G36*
G01X569422Y242495D02*
G03X568860Y242491I-279J-286D01*
G02X566796Y242579I-992J991D01*
G03X566187Y242582I-306J-258D01*
G02X566196Y244399I-1063J914D01*
G03X566805Y244396I306J258D01*
G02X568846Y244487I1063J-914D01*
G03X569408Y244491I279J286D01*
G02X569422Y242495I992J-991D01*
G37*
G36*
G01X1548542Y245073D02*
G03X1548652Y244519I333J-222D01*
G02X1546702Y244133I-783J-1163D01*
G03X1546592Y244687I-333J222D01*
G02X1548542Y245073I783J1163D01*
G37*
G36*
G01X1515446Y244968D02*
G03X1515447Y244410I287J-278D01*
G02X1513296Y244409I-1075J-1049D01*
G03X1513295Y244967I-287J278D01*
G02X1513274Y247043I1075J1049D01*
G03X1513275Y247590I-291J274D01*
G02X1515468Y247589I1097J1026D01*
G03X1515467Y247042I291J-274D01*
G02X1515446Y244968I-1097J-1026D01*
G37*
G36*
G01X1626025Y242615D02*
G03X1626599Y242478I350J194D01*
G02X1625390Y240152I1543J-2279D01*
G03X1624948Y240543I-400J-7D01*
G02X1626025Y242615I-150J1394D01*
G37*
G36*
G01X1779451Y236100D02*
X1774450D01*
G02X1774451Y239324I1J1612D01*
G01X1779451D01*
G02X1781062Y237722I0J-1611D01*
G01Y237627D01*
X1781053Y237542D01*
G02X1779451Y236100I-1602J169D01*
G37*
G36*
G01X1760554D02*
X1755554D01*
G02Y239324I0J1612D01*
G01X1760555D01*
G02X1762166Y237722I-1J-1612D01*
G01Y237627D01*
X1762156Y237542D01*
G02X1760554Y236100I-1602J169D01*
G37*
G36*
G01X642637Y237601D02*
G03Y237055I292J-273D01*
G02X640445I-1096J-1027D01*
G03Y237601I-292J273D01*
G02Y239655I1096J1027D01*
G03Y240201I-292J273D01*
G02Y242255I1096J1027D01*
G03Y242801I-292J273D01*
G02X642637I1096J1027D01*
G03Y242255I292J-273D01*
G02Y240201I-1096J-1027D01*
G03Y239655I292J-273D01*
G02Y237601I-1096J-1027D01*
G37*
G36*
G01X1572141Y234659D02*
G03X1571596Y234427I-167J-363D01*
G02X1570861Y236161I-1324J462D01*
G03X1571406Y236393I167J363D01*
G02X1572753Y237333I1324J-462D01*
G03X1573159Y237717I6J400D01*
G02X1573165Y237800I1401J-60D01*
G03X1572933Y238017I-199J20D01*
G02X1572213Y238085I-233J1383D01*
G03X1571684Y237800I-139J-375D01*
G02X1570805Y239431I-1366J316D01*
G03X1571334Y239716I139J375D01*
G02X1573024Y240764I1366J-316D01*
G03X1573512Y241097I92J389D01*
G02X1574377Y239599I1388J-197D01*
G03X1574102Y239412I-75J-185D01*
G02X1574095Y239260I-1402J-12D01*
G03X1574327Y239043I199J-20D01*
G02X1574537Y236258I232J-1383D01*
G03X1574131Y235874I-6J-400D01*
G02X1572141Y234659I-1401J57D01*
G37*
G36*
G01X771881Y236329D02*
G03X771811Y235764I244J-317D01*
G02X769716Y236023I-1179J-931D01*
G03X769786Y236588I-244J317D01*
G02X769698Y236712I1179J930D01*
G03X769395Y236752I-168J-108D01*
G02X769546Y238811I-1013J1109D01*
G03X770089Y238739I310J253D01*
G02X772021Y238587I876J-1220D01*
G03X772617Y238625I281J285D01*
G02X772744Y236632I1183J-925D01*
G03X772148Y236594I-281J-285D01*
G02X771881Y236329I-1183J925D01*
G37*
G36*
G01X1844293Y237781D02*
G03X1844175Y237187I197J-348D01*
G02X1839851Y237383I-2246J-1757D01*
G03X1839724Y238022I-291J274D01*
G02X1841617Y238819I576J1278D01*
G03X1841985Y238281I376J-138D01*
G02X1842075Y238278I-50J-2851D01*
G03X1842275Y238543I11J200D01*
G02X1844293Y237781I1325J457D01*
G37*
G36*
G01X1682700Y234573D02*
G03X1683292Y234554I305J259D01*
G02X1683232Y232671I1008J-975D01*
G03X1682640Y232690I-305J-259D01*
G02X1682700Y234573I-1008J975D01*
G37*
G36*
G01X1767985Y232438D02*
G03X1767403Y232224I-204J-344D01*
G02X1766792Y233887I-1326J457D01*
G03X1767374Y234101I204J344D01*
G02X1767985Y232438I1326J-457D01*
G37*
G36*
G01X1804379Y233482D02*
G03X1805001Y233476I313J248D01*
G02X1804984Y231713I1082J-892D01*
G03X1804362Y231719I-313J-248D01*
G02X1804379Y233482I-1082J892D01*
G37*
G36*
G01X1794608Y234126D02*
G03X1794630Y233549I288J-278D01*
G02X1792692Y233474I-930J-1049D01*
G03X1792670Y234051I-288J278D01*
G02X1794608Y234126I930J1049D01*
G37*
G36*
G01X1883239Y233459D02*
G03X1883271Y232890I296J-269D01*
G02X1881306Y232778I-926J-1053D01*
G03X1881274Y233347I-296J269D01*
G02X1882924Y235600I926J1052D01*
G03X1883468Y235728I206J343D01*
G02X1883927Y233775I1183J-752D01*
G03X1883383Y233647I-206J-343D01*
G02X1883239Y233459I-1181J755D01*
G37*
G36*
G01X824285Y230658D02*
G03X823732Y230653I-274J-292D01*
G02X821586Y232754I-1050J1074D01*
G03Y233300I-292J273D01*
G02X821624Y235393I1096J1027D01*
G03Y235961I-282J284D01*
G02X821586Y238054I1058J1066D01*
G03Y238600I-292J273D01*
G02X823867Y240550I1096J1027D01*
G03X824497I315J246D01*
G02X826867I1185J-923D01*
G03X827497I315J246D01*
G02X829867I1185J-923D01*
G03X830497I315J246D01*
G02X832867I1185J-923D01*
G03X833497I315J246D01*
G02X835840Y240583I1185J-923D01*
G03X836433Y240557I308J255D01*
G02X838495Y238375I1068J-1056D01*
G03Y237775I265J-300D01*
G02X838596Y235623I-995J-1125D01*
G03Y235077I292J-273D01*
G02X838603Y235070I-1058J-1065D01*
G03X838915Y235092I147J135D01*
G02X839185Y233098I1240J-847D01*
G03X838627Y233057I-258J-305D01*
G02X836340Y233096I-1127J993D01*
G03X835751Y233127I-309J-254D01*
G02X833470Y233338I-1051J1073D01*
G03X832835Y233365I-328J-229D01*
G02X830497Y233404I-1153J962D01*
G03X829867I-315J-246D01*
G02X829550Y233101I-1185J923D01*
G03X829444Y232559I231J-327D01*
G02X827046Y230763I-1264J-811D01*
G03X826443Y230764I-302J-262D01*
G02X824285Y230658I-1130J989D01*
G37*
G36*
G01X175339Y230666D02*
G03X174685Y230622I-312J-251D01*
G02X172428Y232545I-1285J778D01*
G03Y233155I-259J305D01*
G02X172342Y235366I972J1145D01*
G03Y235934I-282J284D01*
G02X172428Y238145I1058J1066D01*
G03Y238755I-259J305D01*
G02X174585Y240823I972J1145D01*
G03X175215I315J246D01*
G02X177585I1185J-923D01*
G03X178215I315J246D01*
G02X180585I1185J-923D01*
G03X181215I315J246D01*
G02X183543Y240875I1185J-923D01*
G03X184142Y240864I304J259D01*
G02X186393Y240825I1108J-1014D01*
G03X186992Y240814I304J259D01*
G02X189062Y238646I1108J-1015D01*
G03X189083Y238015I256J-307D01*
G02X189255Y235731I-883J-1215D01*
G03X189276Y235142I281J-285D01*
G02X187023Y233210I-976J-1142D01*
G03X186381Y233262I-340J-211D01*
G02X184107Y233275I-1131J988D01*
G03X183508Y233286I-304J-259D01*
G02X181215Y233377I-1108J1014D01*
G03X180585I-315J-246D01*
G02X178215I-1185J923D01*
G03X177585I-315J-246D01*
G02X177503Y233280I-1187J920D01*
G03X177525Y232714I293J-272D01*
G02X175339Y230666I-1017J-1106D01*
G37*
G36*
G01X1926924Y232852D02*
G03X1926983Y232289I311J-252D01*
G02X1925011Y232083I-883J-1089D01*
G03X1924952Y232646I-311J252D01*
G02X1926924Y232852I883J1089D01*
G37*
G36*
G01X1499741Y233065D02*
G03X1499981Y232510I360J-174D01*
G02X1498296Y231783I-422J-1337D01*
G03X1498056Y232338I-360J174D01*
G02X1499741Y233065I422J1337D01*
G37*
G36*
G01X578805Y232720D02*
G03X578809Y232141I278J-288D01*
G02X576876Y232128I-960J-1022D01*
G03X576872Y232707I-278J288D01*
G02X578805Y232720I960J1022D01*
G37*
G36*
G01X1387761Y232456D02*
G03X1388231Y232161I388J96D01*
G02X1387157Y230451I287J-1372D01*
G03X1386687Y230746I-388J-96D01*
G02X1387761Y232456I-287J1372D01*
G37*
G36*
G01X571477Y230511D02*
G03X571449Y229950I270J-295D01*
G02X569455Y230047I-1045J-935D01*
G03X569483Y230608I-270J295D01*
G02X571477Y230511I1045J935D01*
G37*
G36*
G01X1939213Y229053D02*
G03X1939785Y229046I289J276D01*
G02X1939761Y226947I1062J-1062D01*
G03X1939189Y226954I-289J-276D01*
G02X1939213Y229053I-1062J1062D01*
G37*
G36*
G01X90173Y226354D02*
G03X89627I-273J-292D01*
G02X87677Y228635I-1027J1096D01*
G03Y229265I-246J315D01*
G02Y231635I923J1185D01*
G03Y232265I-246J315D01*
G02Y234635I923J1185D01*
G03Y235265I-246J315D01*
G02X89627Y237546I923J1185D01*
G03X90173I273J292D01*
G02X92227I1027J-1096D01*
G03X92773I273J292D01*
G02X94827I1027J-1096D01*
G03X95373I273J292D01*
G02X97427I1027J-1096D01*
G03X97973I273J292D01*
G02X99923Y235265I1027J-1096D01*
G03Y234635I246J-315D01*
G02Y232265I-923J-1185D01*
G03Y231635I246J-315D01*
G02Y229265I-923J-1185D01*
G03Y228635I246J-315D01*
G02X97973Y226354I-923J-1185D01*
G03X97427I-273J-292D01*
G02X95373I-1027J1096D01*
G03X94827I-273J-292D01*
G02X92773I-1027J1096D01*
G03X92227I-273J-292D01*
G02X90173I-1027J1096D01*
G37*
G36*
G01X703380Y225694D02*
G03X702770I-305J-259D01*
G02Y227506I-1070J906D01*
G03X703380I305J259D01*
G02Y225694I1070J-906D01*
G37*
G36*
G01X1253531Y228169D02*
G03X1253880Y227627I374J-143D01*
G02X1252796Y225241I-89J-1399D01*
G03X1252264Y225273I-284J-282D01*
G02X1250295Y225504I-869J1100D01*
G03X1249691Y225531I-314J-248D01*
G02X1249772Y227363I-1019J963D01*
G03X1250376Y227336I314J248D01*
G02X1250745Y227615I1018J-963D01*
G03X1250929Y228125I-185J355D01*
G02X1253531Y228169I1292J543D01*
G37*
G36*
G01X1945635Y227689D02*
G03X1945738Y227143I334J-220D01*
G02X1943753Y226770I-813J-1142D01*
G03X1943650Y227316I-334J220D01*
G02X1945635Y227689I813J1142D01*
G37*
G36*
G01X1627679Y224282D02*
G03X1627124Y224267I-270J-295D01*
G02X1627069Y226286I-1000J983D01*
G03X1627624Y226301I270J295D01*
G02X1627679Y224282I1000J-983D01*
G37*
G36*
G01X1883427Y223090D02*
G03X1882873I-277J-288D01*
G02Y225110I-973J1010D01*
G03X1883427I277J288D01*
G02Y223090I973J-1010D01*
G37*
G36*
G01X1401311Y222717D02*
G03X1400689I-311J-252D01*
G02Y224483I-1089J883D01*
G03X1401311I311J252D01*
G02Y222717I1089J-883D01*
G37*
G36*
G01X1622167Y224930D02*
G03Y224372I286J-279D01*
G02X1620161I-1003J-980D01*
G03Y224930I-286J279D01*
G02X1622167I1003J980D01*
G37*
G36*
G01X1245144Y223407D02*
G03X1244700Y223029I-44J-398D01*
G02X1243456Y224493I-1400J71D01*
G03X1243900Y224871I44J398D01*
G02X1245144Y223407I1400J-71D01*
G37*
G36*
G01X767662Y224140D02*
G03X767640Y223563I266J-299D01*
G02X765702Y223638I-1008J-974D01*
G03X765724Y224215I-266J299D01*
G02X767662Y224140I1008J974D01*
G37*
G36*
G01X638097Y223710D02*
G03Y223164I292J-273D01*
G02X635905I-1096J-1027D01*
G03Y223710I-292J273D01*
G02Y225764I1096J1027D01*
G03Y226310I-292J273D01*
G02Y228364I1096J1027D01*
G03Y228910I-292J273D01*
G02X638097I1096J1027D01*
G03Y228364I292J-273D01*
G02Y226310I-1096J-1027D01*
G03Y225764I292J-273D01*
G02Y223710I-1096J-1027D01*
G37*
G36*
G01X714708Y223170D02*
G03X714730Y222593I288J-278D01*
G02X712792Y222518I-930J-1049D01*
G03X712770Y223095I-288J278D01*
G02X714708Y223170I930J1049D01*
G37*
G36*
G01X115652Y224178D02*
G03X115823Y224709I-187J353D01*
G02X117738Y224092I1257J621D01*
G03X117567Y223561I187J-353D01*
G02X117707Y222824I-1257J-621D01*
G03X118084Y222391I399J-34D01*
G02X116611Y221107I-76J-1400D01*
G03X116234Y221540I-399J34D01*
G02X115652Y224178I76J1400D01*
G37*
G36*
G01X1911301Y222317D02*
G03X1911312Y221751I288J-278D01*
G02X1909279Y221657I-972J-1010D01*
G03X1909237Y222221I-303J261D01*
G02X1909148Y224412I982J1137D01*
G03X1909135Y224986I-285J281D01*
G02X1911224Y225036I1019J1104D01*
G03X1911237Y224462I285J-281D01*
G02X1911301Y222317I-1018J-1104D01*
G37*
G36*
G01X1627988Y218701D02*
G03X1628578Y218690I300J264D01*
G02X1628542Y216799I1017J-965D01*
G03X1627952Y216810I-300J-264D01*
G02X1627988Y218701I-1017J965D01*
G37*
G36*
G01X94077Y218891D02*
G03X94053Y219509I-266J299D01*
G02X93755Y219794I1088J1436D01*
G03X93150Y219805I-307J-256D01*
G02X90389Y219899I-1341J1204D01*
G03X89779Y219922I-315J-247D01*
G02X87038Y220013I-1332J1214D01*
G03X86446Y220050I-313J-249D01*
G02X86597Y222464I-1258J1290D01*
G03X87189Y222427I313J249D01*
G02X89867Y222246I1258J-1291D01*
G03X90477Y222223I315J247D01*
G02X93194Y222161I1332J-1214D01*
G03X93799Y222150I307J256D01*
G02X96338Y219600I1341J-1204D01*
G03X96362Y218982I266J-299D01*
G02X94077Y218891I-1087J-1437D01*
G37*
G36*
G01X1592264Y213948D02*
G03X1591703Y213814I-216J-337D01*
G02X1589500Y215513I-1208J711D01*
G03X1589507Y216069I-284J282D01*
G02X1590941Y218372I1018J964D01*
G03X1591421Y218583I118J382D01*
G02X1593973Y216738I1449J-683D01*
G03X1593975Y216155I275J-291D01*
G02X1592264Y213948I-955J-1026D01*
G37*
G36*
G01X1898421Y215540D02*
G03Y214962I277J-289D01*
G02X1896479I-971J-1011D01*
G03Y215540I-277J289D01*
G02X1898421I971J1011D01*
G37*
G36*
G01X1612670Y215183D02*
G03Y214574I260J-305D01*
G02X1610852I-909J-1067D01*
G03Y215183I-260J304D01*
G02X1612670I909J1067D01*
G37*
G36*
G01X715613Y215122D02*
G03X715771Y214575I349J-196D01*
G02X713878Y214031I-671J-1231D01*
G03X713720Y214578I-349J196D01*
G02X714134Y217187I671J1231D01*
G03X714431Y217733I-73J393D01*
G02X715984Y216889I1296J534D01*
G03X715687Y216343I73J-393D01*
G02X715613Y215122I-1296J-534D01*
G37*
G36*
G01X591383Y214711D02*
G03Y214089I252J-311D01*
G02X589617I-883J-1089D01*
G03Y214711I-252J311D01*
G02X591383I883J1089D01*
G37*
G36*
G01X824103Y213363D02*
G03X823732Y212838I9J-400D01*
G02X821128Y212989I-1332J-438D01*
G03X820912Y213529I-363J168D01*
G02X820541Y216108I554J1396D01*
G03X820606Y216674I-247J315D01*
G02X822886Y218628I1169J943D01*
G03X823448Y218598I296J269D01*
G02X825597Y218441I998J-1122D01*
G03X826202Y218431I307J257D01*
G02X828681Y216791I1120J-1001D01*
G03X829103Y216225I362J-170D01*
G02X830487Y215694I224J-1485D01*
G03X831107Y215697I309J254D01*
G02X831116Y213800I1169J-943D01*
G03X830496Y213797I-309J-254D01*
G02X828264Y213679I-1169J943D01*
G03X827712Y213692I-283J-283D01*
G02X825636Y213742I-1012J1110D01*
G03X825084Y213755I-283J-283D01*
G02X824103Y213363I-1012J1110D01*
G37*
G36*
G01X1814125Y210720D02*
X1809125D01*
G02Y213742I0J1511D01*
G01X1814126D01*
G02X1815636Y212241I-1J-1511D01*
G01Y212146D01*
X1815627Y212062D01*
G02X1814125Y210720I-1502J169D01*
G37*
G36*
G01X1801526D02*
X1796526D01*
G02Y213742I0J1511D01*
G01X1801527D01*
G02X1803038Y212241I0J-1512D01*
G01Y212146D01*
X1803028Y212062D01*
G02X1801526Y210720I-1502J169D01*
G37*
G36*
G01X1826685Y210650D02*
X1821685D01*
G02Y213672I0J1511D01*
G01X1826686D01*
G02X1828196Y212171I-1J-1511D01*
G01Y212076D01*
X1828187Y211992D01*
G02X1826685Y210650I-1502J169D01*
G37*
G36*
G01X778862Y211127D02*
G03X778252I-305J-259D01*
G02Y212939I-1070J906D01*
G03X778862I305J259D01*
G02Y211127I1070J-906D01*
G37*
G36*
G01X129393Y210985D02*
G03X128822Y210945I-266J-299D01*
G02X128685Y212901I-1068J908D01*
G03X129256Y212941I266J299D01*
G02X129393Y210985I1068J-908D01*
G37*
G36*
G01X1788925Y210120D02*
X1783925D01*
G02Y213142I0J1511D01*
G01X1788926D01*
G02X1790436Y211641I-1J-1511D01*
G01Y211546D01*
X1790427Y211462D01*
G02X1788925Y210120I-1502J169D01*
G37*
G36*
G01X1776325D02*
X1771325D01*
G02Y213142I0J1511D01*
G01X1776326D01*
G02X1777836Y211641I-1J-1511D01*
G01Y211546D01*
X1777827Y211462D01*
G02X1776325Y210120I-1502J169D01*
G37*
G36*
G01X1763725D02*
X1758725D01*
G02Y213142I0J1511D01*
G01X1763726D01*
G02X1765236Y211641I-1J-1511D01*
G01Y211546D01*
X1765227Y211462D01*
G02X1763725Y210120I-1502J169D01*
G37*
G36*
G01X1751125D02*
X1746125D01*
G02Y213142I0J1511D01*
G01X1751126D01*
G02X1752636Y211641I-1J-1511D01*
G01Y211546D01*
X1752627Y211462D01*
G02X1751125Y210120I-1502J169D01*
G37*
G36*
G01X1738484D02*
X1733484D01*
G02Y213142I0J1511D01*
G01X1738485D01*
G02X1739996Y211641I0J-1512D01*
G01Y211546D01*
X1739986Y211462D01*
G02X1738484Y210120I-1502J169D01*
G37*
G36*
G01X1863263Y210799D02*
G03X1862670Y210713I-259J-305D01*
G02X1860096Y211423I-1173J768D01*
G03X1859676Y211806I-400J-16D01*
G02X1861005Y213264I-72J1400D01*
G03X1861425Y212881I400J16D01*
G02X1862404Y212551I73J-1400D01*
G03X1862997Y212637I259J305D01*
G02X1863263Y210799I1173J-769D01*
G37*
G36*
G01X1726494Y210283D02*
G03X1725906I-294J-270D01*
G02Y212317I-1106J1017D01*
G03X1726494I294J270D01*
G02Y210283I1106J-1017D01*
G37*
G36*
G01X89628Y210958D02*
G03X89293Y210468I54J-396D01*
G02X85796Y210488I-1751J-425D01*
G03X85362Y210984I-388J99D01*
G02X83439Y213322I-206J1790D01*
G03X83114Y213840I-381J122D01*
G02X85083Y215076I252J1784D01*
G03X85408Y214558I381J-122D01*
G02X85527Y214537I-253J-1784D01*
G03X85753Y214810I41J196D01*
G02X89158Y215043I1663J694D01*
G03X89516Y214541I387J-103D01*
G02X89697Y214519I-127J-1797D01*
G03X89921Y214781I35J197D01*
G02X91562Y213563I1705J583D01*
G03X91155Y213087I-14J-400D01*
G02X89628Y210958I-1769J-343D01*
G37*
G36*
G01X1358537Y208181D02*
G03X1357965Y208159I-275J-290D01*
G02X1357889Y210119I-1039J941D01*
G03X1358461Y210141I275J290D01*
G02X1360432Y210247I1039J-941D01*
G03X1360987Y210269I266J299D01*
G02X1361068Y208253I1013J-969D01*
G03X1360513Y208231I-266J-299D01*
G02X1358537Y208181I-1013J969D01*
G37*
G36*
G01X1227826Y209464D02*
G03X1227844Y208909I297J-268D01*
G02X1225826Y208843I-977J-1005D01*
G03X1225808Y209398I-297J268D01*
G02X1225814Y211414I977J1005D01*
G03Y211992I-277J289D01*
G02X1225978Y214149I971J1011D01*
G03X1226070Y214713I-230J327D01*
G02X1228007Y214397I1130J830D01*
G03X1227915Y213833I230J-327D01*
G02X1227756Y211992I-1130J-830D01*
G03Y211414I277J-289D01*
G02X1227826Y209464I-971J-1011D01*
G37*
G36*
G01X1475934Y208720D02*
G03X1475721Y208189I153J-369D01*
G02X1473906Y208918I-1282J-568D01*
G03X1474119Y209449I-153J369D01*
G02X1475934Y208720I1282J568D01*
G37*
G36*
G01X1479760Y208891D02*
G03X1479846Y208343I328J-229D01*
G02X1477851Y208029I-846J-1118D01*
G03X1477765Y208577I-328J229D01*
G02X1479760Y208891I846J1118D01*
G37*
G36*
G01X617675Y205984D02*
G03X617121I-277J-288D01*
G02Y208004I-973J1010D01*
G03X617675I277J288D01*
G02X617771Y208088I970J-1012D01*
G03Y208400I-125J156D01*
G02X619658Y208521I877J1094D01*
G03Y207967I288J-277D01*
G02X619742Y207871I-1012J-970D01*
G03X620054I156J125D01*
G02X622121Y208004I1094J-877D01*
G03X622675I277J288D01*
G02X622771Y208088I970J-1012D01*
G03Y208400I-125J156D01*
G02X622638Y210467I877J1094D01*
G03Y211021I-288J277D01*
G02X622554Y211117I1012J970D01*
G03X622242I-156J-125D01*
G02X622121Y213004I-1094J877D01*
G03X622675I277J288D01*
G02X622771Y213088I970J-1012D01*
G03Y213400I-125J156D01*
G02X622638Y215467I877J1094D01*
G03Y216021I-288J277D01*
G02X622554Y216117I1012J970D01*
G03X622242I-156J-125D01*
G02X622121Y218004I-1094J877D01*
G03X622675I277J288D01*
G02X622771Y218088I970J-1012D01*
G03Y218400I-125J156D01*
G02X622638Y220467I877J1094D01*
G03Y221021I-288J277D01*
G02X622554Y221117I1012J970D01*
G03X622242I-156J-125D01*
G02X622121Y223004I-1094J877D01*
G03X622675I277J288D01*
G02X622771Y223088I970J-1012D01*
G03Y223400I-125J156D01*
G02X622638Y225467I877J1094D01*
G03Y226021I-288J277D01*
G02X622554Y226117I1012J970D01*
G03X622242I-156J-125D01*
G02X620175Y225984I-1094J877D01*
G03X619621I-277J-288D01*
G02X619525Y225900I-970J1012D01*
G03Y225588I125J-156D01*
G02X617638Y225467I-877J-1094D01*
G03Y226021I-288J277D01*
G02X617554Y226117I1012J970D01*
G03X617242I-156J-125D01*
G02X615175Y225984I-1094J877D01*
G03X614621I-277J-288D01*
G02X614525Y225900I-970J1012D01*
G03Y225588I125J-156D01*
G02X614658Y223521I-877J-1094D01*
G03Y222967I288J-277D01*
G02X614742Y222871I-1012J-970D01*
G03X615054I156J125D01*
G02X615175Y220984I1094J-877D01*
G03X614621I-277J-288D01*
G02X614525Y220900I-970J1012D01*
G03Y220588I125J-156D01*
G02X614658Y218521I-877J-1094D01*
G03Y217967I288J-277D01*
G02X614742Y217871I-1012J-970D01*
G03X615054I156J125D01*
G02X615175Y215984I1094J-877D01*
G03X614621I-277J-288D01*
G02X614525Y215900I-970J1012D01*
G03Y215588I125J-156D01*
G02X614658Y213521I-877J-1094D01*
G03Y212967I288J-277D01*
G02X614742Y212871I-1012J-970D01*
G03X615054I156J125D01*
G02X615175Y210984I1094J-877D01*
G03X614621I-277J-288D01*
G02X614525Y210900I-970J1012D01*
G03Y210588I125J-156D01*
G02X612638Y210467I-877J-1094D01*
G03Y211021I-288J277D01*
G02Y212967I1010J973D01*
G03Y213521I-288J277D01*
G02Y215467I1010J973D01*
G03Y216021I-288J277D01*
G02Y217967I1010J973D01*
G03Y218521I-288J277D01*
G02Y220467I1010J973D01*
G03Y221021I-288J277D01*
G02X612554Y221117I1012J970D01*
G03X612242I-156J-125D01*
G02X610138Y222967I-1094J877D01*
G03Y223521I-288J277D01*
G02X610054Y223617I1012J970D01*
G03X609742I-156J-125D01*
G02X607638Y225467I-1094J877D01*
G03Y226021I-288J277D01*
G02X609658I1010J973D01*
G03Y225467I288J-277D01*
G02X609742Y225371I-1012J-970D01*
G03X610054I156J125D01*
G02X612121Y225504I1094J-877D01*
G03X612675I277J288D01*
G02X612771Y225588I970J-1012D01*
G03Y225900I-125J156D01*
G02X612638Y227967I877J1094D01*
G03Y228521I-288J277D01*
G02X612554Y228617I1012J970D01*
G03X612242I-156J-125D01*
G02X612121Y230504I-1094J877D01*
G03X612675I277J288D01*
G02X614658Y228521I973J-1010D01*
G03Y227967I288J-277D01*
G02X614742Y227871I-1012J-970D01*
G03X615054I156J125D01*
G02X617121Y228004I1094J-877D01*
G03X617675I277J288D01*
G02X617771Y228088I970J-1012D01*
G03Y228400I-125J156D01*
G02X619621Y230504I877J1094D01*
G03X620175I277J288D01*
G02X622158Y228521I973J-1010D01*
G03Y227967I288J-277D01*
G02X622242Y227871I-1012J-970D01*
G03X622554I156J125D01*
G02X624658Y226021I1094J-877D01*
G03Y225467I288J-277D01*
G02Y223521I-1010J-973D01*
G03Y222967I288J-277D01*
G02Y221021I-1010J-973D01*
G03Y220467I288J-277D01*
G02Y218521I-1010J-973D01*
G03Y217967I288J-277D01*
G02Y216021I-1010J-973D01*
G03Y215467I288J-277D01*
G02Y213521I-1010J-973D01*
G03Y212967I288J-277D01*
G02Y211021I-1010J-973D01*
G03Y210467I288J-277D01*
G02Y208521I-1010J-973D01*
G03Y207967I288J-277D01*
G02X622675Y205984I-1010J-973D01*
G03X622121I-277J-288D01*
G02X620175I-973J1010D01*
G03X619621I-277J-288D01*
G02X617675I-973J1010D01*
G37*
G36*
G01X1856789Y207274D02*
G03X1857411Y207253I319J241D01*
G02X1857351Y205491I1059J-918D01*
G03X1856729Y205512I-319J-241D01*
G02X1856789Y207274I-1059J918D01*
G37*
G36*
G01X1222271Y206989D02*
G03Y206411I277J-289D01*
G02X1220329I-971J-1011D01*
G03Y206989I-277J289D01*
G02X1222271I971J1011D01*
G37*
G36*
G01X1517619Y204557D02*
G03X1517615Y204002I286J-280D01*
G02X1515595Y204017I-1017J-965D01*
G03X1515599Y204572I-286J280D01*
G02X1517619Y204557I1017J965D01*
G37*
G36*
G01X708189Y200329D02*
G03X707611I-289J-277D01*
G02X705762Y202424I-1011J971D01*
G03X705753Y203071I-240J320D01*
G02X707678Y205064I808J1146D01*
G03X708260Y205004I319J241D01*
G02X710479Y204479I922J-1056D01*
G03X711061Y204291I370J152D01*
G02X711171Y201847I739J-1191D01*
G03X710594Y201447I-179J-358D01*
G02X708189Y200329I-1394J-147D01*
G37*
G36*
G01X1884247Y201333D02*
G03X1884271Y201009I128J-153D01*
G02X1882499Y200753I-732J-1196D01*
G03X1882457Y201329I-297J268D01*
G02X1884491Y203224I893J1081D01*
G03X1885100Y203174I326J232D01*
G02X1884952Y201370I993J-990D01*
G03X1884343Y201420I-326J-232D01*
G02X1884247Y201333I-988J994D01*
G37*
G36*
G01X1227471Y201389D02*
G03Y200811I277J-289D01*
G02X1225529I-971J-1011D01*
G03Y201389I-277J289D01*
G02X1227471I971J1011D01*
G37*
G36*
G01X1546924Y199009D02*
G03X1546944Y198437I289J-276D01*
G02X1544986Y198368I-944J-1037D01*
G03X1544966Y198940I-289J276D01*
G02X1546924Y199009I944J1037D01*
G37*
G36*
G01X1763668Y195332D02*
X1758668D01*
G02Y198354I0J1511D01*
G01X1763669D01*
G02X1765180Y196853I0J-1512D01*
G01Y196758D01*
X1765170Y196674D01*
G02X1763668Y195332I-1502J169D01*
G37*
G36*
G01X1751082D02*
X1746082D01*
G02Y198354I0J1511D01*
G01X1751083D01*
G02X1752594Y196853I0J-1512D01*
G01Y196758D01*
X1752584Y196674D01*
G02X1751082Y195332I-1502J169D01*
G37*
G36*
G01X1826682Y195330D02*
X1821682D01*
G02Y198352I0J1511D01*
G01X1826683D01*
G02X1828194Y196851I0J-1512D01*
G01Y196756D01*
X1828184Y196672D01*
G02X1826682Y195330I-1502J169D01*
G37*
G36*
G01X1814041D02*
X1809041D01*
G02Y198352I0J1511D01*
G01X1814042D01*
G02X1815552Y196851I-1J-1511D01*
G01Y196756D01*
X1815543Y196672D01*
G02X1814041Y195330I-1502J169D01*
G37*
G36*
G01X1801441D02*
X1796441D01*
G02Y198352I0J1511D01*
G01X1801442D01*
G02X1802952Y196851I-1J-1511D01*
G01Y196756D01*
X1802943Y196672D01*
G02X1801441Y195330I-1502J169D01*
G37*
G36*
G01X1788841D02*
X1783841D01*
G02Y198352I0J1511D01*
G01X1788842D01*
G02X1790352Y196851I-1J-1511D01*
G01Y196756D01*
X1790343Y196672D01*
G02X1788841Y195330I-1502J169D01*
G37*
G36*
G01X1776241D02*
X1771241D01*
G02Y198352I0J1511D01*
G01X1776242D01*
G02X1777752Y196851I-1J-1511D01*
G01Y196756D01*
X1777743Y196672D01*
G02X1776241Y195330I-1502J169D01*
G37*
G36*
G01X720641Y196447D02*
G03X721181Y196442I273J293D01*
G02X721162Y194373I936J-1043D01*
G03X720622Y194378I-273J-293D01*
G02X720641Y196447I-936J1043D01*
G37*
G36*
G01X1638880Y196604D02*
G03Y196050I288J-277D01*
G02X1636860I-1010J-973D01*
G03Y196604I-288J277D01*
G02X1638880I1010J973D01*
G37*
G36*
G01X44942Y266908D02*
X44832Y266853D01*
Y197440D01*
X39339Y191947D01*
X11125D01*
X7085Y195987D01*
Y230630D01*
X1977Y235738D01*
Y264753D01*
X8820Y271596D01*
Y338949D01*
X8825Y338954D01*
Y339015D01*
X14147Y344337D01*
X40874D01*
X44832Y340379D01*
Y269467D01*
X44942Y269412D01*
G02Y266908I-632J-1252D01*
G37*
G36*
G01X1708794Y193293D02*
G02X1712894Y191735I3218J2294D01*
G02X1708794Y193293I-882J3852D01*
G37*
G36*
G01X1210925Y194189D02*
G03X1210909Y193567I243J-317D01*
G02X1209145Y193611I-909J-1067D01*
G03X1209161Y194233I-243J317D01*
G02X1210925Y194189I909J1067D01*
G37*
G36*
G01X1621217Y184110D02*
G03X1620607Y184084I-294J-271D01*
G02X1620531Y185894I-1107J860D01*
G03X1621141Y185920I294J271D01*
G02X1621217Y184110I1107J-860D01*
G37*
G36*
G01X1609625Y183827D02*
G03X1609071Y183803I-265J-300D01*
G02X1608985Y185821I-1015J968D01*
G03X1609539Y185845I265J300D01*
G02X1611497Y185914I1014J-968D01*
G03X1612052Y185930I269J296D01*
G02X1614042Y185943I1001J-981D01*
G03X1614597Y185934I282J283D01*
G02X1614564Y183914I956J-1026D01*
G03X1614009Y183923I-282J-283D01*
G02X1612110Y183912I-955J1026D01*
G03X1611555Y183896I-269J-296D01*
G02X1609625Y183827I-1001J981D01*
G37*
G36*
G01X1682294Y182678D02*
G03X1681795Y182531I-164J-365D01*
G02X1679261Y184475I-1345J870D01*
G03X1679252Y184752I-148J134D01*
G02X1681967Y186024I1118J1148D01*
G03X1682483Y185672I399J31D01*
G02X1682294Y182678I467J-1532D01*
G37*
G36*
G01X1656005Y183496D02*
G03X1656044Y182887I277J-288D01*
G02X1654235Y182770I-835J-1126D01*
G03X1654196Y183379I-277J288D01*
G02X1656005Y183496I835J1126D01*
G37*
G36*
G01X1493491Y178427D02*
G03X1493498Y177872I291J-274D01*
G02X1491478Y177847I-998J-985D01*
G03X1491471Y178402I-291J274D01*
G02X1493491Y178427I998J985D01*
G37*
G36*
G01X1615377Y178062D02*
G03X1615891Y177756I393J75D01*
G02X1615021Y176207I395J-1241D01*
G03X1614492Y176487I-389J-94D01*
G02X1615377Y178062I-492J1313D01*
G37*
G36*
G01X1820382Y175014D02*
X1815382D01*
G02Y178036I0J1511D01*
G01X1820383D01*
G02X1821894Y176535I0J-1512D01*
G01Y176440D01*
X1821884Y176356D01*
G02X1820382Y175014I-1502J169D01*
G37*
G36*
G01X1807784D02*
X1802784D01*
G02Y178036I0J1511D01*
G01X1807785D01*
G02X1809296Y176535I0J-1512D01*
G01Y176440D01*
X1809286Y176356D01*
G02X1807784Y175014I-1502J169D01*
G37*
G36*
G01X1795185D02*
X1790185D01*
G02Y178036I0J1511D01*
G01X1795185D01*
G02X1796696Y176535I0J-1511D01*
G01Y176440D01*
X1796687Y176356D01*
G02X1795185Y175014I-1502J169D01*
G37*
G36*
G01X1782587D02*
X1777587D01*
G02Y178036I0J1511D01*
G01X1782588D01*
G02X1784098Y176535I-1J-1511D01*
G01Y176440D01*
X1784089Y176356D01*
G02X1782587Y175014I-1502J169D01*
G37*
G36*
G01X1764988Y178036D02*
X1769989D01*
G02X1771500Y176535I0J-1512D01*
G01Y176440D01*
X1771490Y176356D01*
G02X1769988Y175014I-1502J169D01*
G01X1764987D01*
G02X1764988Y178036I1J1511D01*
G37*
G36*
G01X1739792D02*
X1744793D01*
G02X1746304Y176535I0J-1512D01*
G01Y176440D01*
X1746294Y176356D01*
G02X1744792Y175014I-1502J169D01*
G01X1739792D01*
G02Y178036I1J1511D01*
G37*
G36*
G01X1732193Y175014D02*
X1727193D01*
G02Y178036I1J1511D01*
G01X1732193D01*
G02X1733704Y176535I0J-1511D01*
G01Y176440D01*
X1733695Y176356D01*
G02X1732193Y175014I-1502J169D01*
G37*
G36*
G01X1254266Y174954D02*
G03X1253734I-266J-298D01*
G02Y177046I-934J1046D01*
G03X1254266I266J298D01*
G02Y174954I934J-1046D01*
G37*
G36*
G01X1856427Y174890D02*
G03X1855873I-277J-288D01*
G02Y176910I-973J1010D01*
G03X1856427I277J288D01*
G02Y174890I973J-1010D01*
G37*
G36*
G01X1876467Y175734D02*
G03X1876859Y175321I400J-13D01*
G02X1875431Y173967I-27J-1402D01*
G03X1875039Y174380I-400J13D01*
G02X1876467Y175734I27J1402D01*
G37*
G36*
G01X1472924Y172703D02*
G03X1472369Y172698I-275J-290D01*
G02X1472352Y174718I-981J1002D01*
G03X1472907Y174723I275J290D01*
G02X1472924Y172703I981J-1002D01*
G37*
G36*
G01X1245937Y172140D02*
G03X1245383I-277J-288D01*
G02X1243022Y173350I-973J1010D01*
G03X1242665Y173805I-396J57D01*
G02X1244188Y175000I135J1395D01*
G03X1244545Y174545I396J-57D01*
G02X1245383Y174160I-134J-1396D01*
G03X1245937I277J288D01*
G02Y172140I973J-1010D01*
G37*
G36*
G01X1614863Y174222D02*
G03X1615392Y173999I373J145D01*
G02X1614687Y172328I508J-1199D01*
G03X1614158Y172551I-373J-145D01*
G02X1613179Y172536I-508J1199D01*
G03X1612674Y172336I-144J-373D01*
G02X1610429Y172159I-1174J564D01*
G03X1609894Y172274I-329J-228D01*
G02X1610293Y174130I-672J1115D01*
G03X1610828Y174015I329J228D01*
G02X1611971Y174114I672J-1115D01*
G03X1612476Y174314I144J373D01*
G02X1614863Y174222I1174J-564D01*
G37*
G36*
G01X1596648Y171344D02*
G03X1596036I-306J-258D01*
G02Y173024I-994J840D01*
G03X1596648I306J258D01*
G02Y171344I994J-840D01*
G37*
G36*
G01X1887371Y171589D02*
G03Y171011I277J-289D01*
G02X1885429I-971J-1011D01*
G03Y171589I-277J289D01*
G02X1887371I971J1011D01*
G37*
G36*
G01X1701968Y162401D02*
G03X1702523Y162390I283J283D01*
G02X1702478Y160081I1087J-1176D01*
G03X1701923Y160092I-283J-283D01*
G02X1701968Y162401I-1087J1176D01*
G37*
G36*
G01X1840909Y158413D02*
G03X1840924Y157858I295J-270D01*
G02X1838905Y157803I-983J-1000D01*
G03X1838890Y158358I-295J270D01*
G02X1840909Y158413I983J1000D01*
G37*
G36*
G01X1531912Y157489D02*
G03X1532143Y156930I358J-179D01*
G02X1530362Y155182I-443J-1330D01*
G03X1529807Y155424I-382J-119D01*
G02X1531912Y157489I-1963J4107D01*
G37*
G36*
G01X20473Y158250D02*
G03X21740Y158653I-2J2199D01*
G02X21756Y154015I1488J-2314D01*
G03X20502Y154428I-1283J-1786D01*
G01X20471D01*
G03X19204Y154025I2J-2199D01*
G02X19188Y158663I-1488J2314D01*
G03X20442Y158250I1283J1786D01*
G01X20473D01*
G37*
G36*
G01X3938D02*
G03X5205Y158653I-2J2199D01*
G02X5221Y154015I1488J-2314D01*
G03X3967Y154428I-1283J-1786D01*
G01X3936D01*
G03X2669Y154025I2J-2199D01*
G02X2653Y158663I-1488J2314D01*
G03X3907Y158250I1283J1786D01*
G01X3938D01*
G37*
G36*
G01X-12598D02*
G03X-11331Y158653I-2J2199D01*
G02X-11315Y154015I1488J-2314D01*
G03X-12569Y154428I-1283J-1786D01*
G01X-12599D01*
G03X-13866Y154025I2J-2199D01*
G02X-13882Y158663I-1488J2314D01*
G03X-12628Y158250I1283J1786D01*
G01X-12598D01*
G37*
G36*
G01X51309Y152844D02*
X47309D01*
G02Y155868I0J1512D01*
G01X51310D01*
G02X52820Y154366I-1J-1512D01*
G01Y154271D01*
X52811Y154187D01*
G02X51309Y152844I-1502J168D01*
G37*
G36*
G01X1788818Y155649D02*
G03X1789375Y155428I376J136D01*
G02X1788550Y153595I725J-1428D01*
G03X1788016Y153866I-387J-101D01*
G02X1788818Y155649I-516J1304D01*
G37*
G36*
G01X1700076Y154255D02*
G03X1700357Y154249I144J140D01*
G02X1700306Y151967I1098J-1166D01*
G03X1700025Y151973I-144J-140D01*
G02X1700076Y154255I-1098J1166D01*
G37*
G36*
G01X1876493Y153833D02*
G03X1877086Y153815I305J259D01*
G02X1877028Y151935I1010J-972D01*
G03X1876435Y151953I-305J-259D01*
G02X1876493Y153833I-1010J972D01*
G37*
G36*
G01X1913160Y153727D02*
G03X1913765Y153634I342J208D01*
G02X1913491Y151853I925J-1054D01*
G03X1912886Y151946I-342J-208D01*
G02X1913160Y153727I-925J1054D01*
G37*
G36*
G01X1514888Y153600D02*
G03X1515300Y153144I396J-57D01*
G02X1513970Y151943I58J-1401D01*
G03X1513558Y152399I-396J57D01*
G02X1514888Y153600I-58J1401D01*
G37*
G36*
G01X1885299Y154911D02*
G03X1885233Y155526I-285J280D01*
G02X1887000Y155717I767J1174D01*
G03X1887066Y155102I285J-280D01*
G02X1887203Y152857I-767J-1173D01*
G03X1887148Y152303I258J-305D01*
G02X1885146Y152502I-1098J-872D01*
G03X1885201Y153056I-258J305D01*
G02X1885299Y154911I1098J872D01*
G37*
G36*
G01X68098Y149962D02*
X63098D01*
G02Y152984I0J1511D01*
G01X68099D01*
G02X69610Y151483I0J-1512D01*
G01Y151388D01*
X69600Y151304D01*
G02X68098Y149962I-1502J169D01*
G37*
G36*
G01X1265136Y151576D02*
G03X1265691Y151567I282J284D01*
G02X1265656Y149548I955J-1026D01*
G03X1265101Y149557I-282J-284D01*
G02X1263135Y149613I-955J1027D01*
G03X1262557I-289J-277D01*
G02Y151555I-1011J971D01*
G03X1263135I289J277D01*
G02X1265136Y151576I1011J-971D01*
G37*
G36*
G01X1574971Y151089D02*
G03Y150511I277J-289D01*
G02X1573029I-971J-1011D01*
G03Y151089I-277J289D01*
G02X1574971I971J1011D01*
G37*
G36*
G01X1945607Y150725D02*
G03X1945609Y150166I287J-278D01*
G02X1943602Y150159I-1000J-982D01*
G03X1943600Y150718I-287J278D01*
G02X1945607Y150725I1000J982D01*
G37*
G36*
G01X1295155Y148431D02*
G03X1294732Y148064I-24J-400D01*
G02X1291935Y148249I-1397J113D01*
G03X1291580Y148668I-400J21D01*
G02X1291742Y151463I156J1393D01*
G03X1292143Y151839I2J400D01*
G02X1292145Y151862I1398J-110D01*
G03X1291752Y152292I-399J30D01*
G02X1293170Y153588I20J1402D01*
G03X1293563Y153158I399J-30D01*
G02X1293594Y153157I-30J-1402D01*
G03X1293797Y153396I7J200D01*
G02X1295303Y152274I1375J274D01*
G03X1294942Y151849I38J-398D01*
G02Y151657I-1399J-96D01*
G03X1295318Y151230I399J-28D01*
G02X1295155Y148431I-78J-1400D01*
G37*
G36*
G01X1496967Y149755D02*
G03X1497034Y149203I319J-241D01*
G02X1495031Y148960I-884J-1088D01*
G03X1494964Y149512I-319J241D01*
G02X1496967Y149755I884J1088D01*
G37*
G36*
G01X1964194Y149150D02*
G03X1964545Y148710I398J-43D01*
G02X1962988Y147468I-163J-1392D01*
G03X1962637Y147908I-398J43D01*
G02X1964194Y149150I163J1392D01*
G37*
G36*
G01X25591Y150376D02*
G03X26858Y150779I-2J2199D01*
G02X26874Y146141I1488J-2314D01*
G03X25620Y146554I-1283J-1786D01*
G01X25590D01*
G03X24323Y146151I2J-2199D01*
G02X24307Y150789I-1488J2314D01*
G03X25561Y150376I1283J1786D01*
G01X25591D01*
G37*
G36*
G01X9056D02*
G03X10323Y150779I-2J2199D01*
G02X10339Y146141I1488J-2314D01*
G03X9085Y146554I-1283J-1786D01*
G01X9054D01*
G03X7787Y146151I2J-2199D01*
G02X7771Y150789I-1488J2314D01*
G03X9025Y150376I1283J1786D01*
G01X9056D01*
G37*
G36*
G01X-7480D02*
G03X-6213Y150779I-2J2199D01*
G02X-6197Y146141I1488J-2314D01*
G03X-7451Y146554I-1283J-1786D01*
G01X-7481D01*
G03X-8748Y146151I2J-2199D01*
G02X-8764Y150789I-1488J2314D01*
G03X-7510Y150376I1283J1786D01*
G01X-7480D01*
G37*
G36*
G01X1278933Y147438D02*
G03X1278927Y146832I258J-306D01*
G02X1277097Y146852I-927J-1052D01*
G03X1277103Y147458I-258J306D01*
G02X1278933Y147438I927J1052D01*
G37*
G36*
G01X1490661Y145218D02*
G03X1490195Y144863I-68J-394D01*
G02X1489039Y146382I-1395J138D01*
G03X1489505Y146737I68J394D01*
G02X1490661Y145218I1395J-138D01*
G37*
G36*
G01X1533237Y146370D02*
G03X1533446Y145819I358J-180D01*
G02X1531671Y145148I-523J-1301D01*
G03X1531462Y145699I-358J180D01*
G02X1533237Y146370I523J1301D01*
G37*
G36*
G01X1849616Y143180D02*
G03X1849627Y142581I270J-295D01*
G02X1847506Y142540I-1037J-1221D01*
G03X1847495Y143139I-270J295D01*
G02X1849616Y143180I1037J1221D01*
G37*
G36*
G01X1267743Y140626D02*
G03X1267208Y140322I-141J-375D01*
G02X1266321Y141880I-1380J246D01*
G03X1266856Y142184I141J375D01*
G02X1267743Y140626I1380J-246D01*
G37*
G36*
G01X62342Y144760D02*
Y139665D01*
X62333Y139581D01*
G02X59320Y139750I-1502J169D01*
G01Y144750D01*
G02X62342Y144760I1511J0D01*
G37*
G36*
G01X48412D02*
Y139665D01*
X48402Y139581D01*
G02X45388Y139750I-1502J169D01*
G01Y144750D01*
G02X48412Y144760I1512J0D01*
G37*
G36*
G01X3938Y142502D02*
G03X5205Y142905I-2J2199D01*
G02X5221Y138267I1488J-2314D01*
G03X3967Y138680I-1283J-1786D01*
G01X3936D01*
G03X2669Y138277I2J-2199D01*
G02X2653Y142915I-1488J2314D01*
G03X3907Y142502I1283J1786D01*
G01X3938D01*
G37*
G36*
G01X-12598D02*
G03X-11331Y142905I-2J2199D01*
G02X-11315Y138267I1488J-2314D01*
G03X-12569Y138680I-1283J-1786D01*
G01X-12599D01*
G03X-13866Y138277I2J-2199D01*
G02X-13882Y142915I-1488J2314D01*
G03X-12628Y142502I1283J1786D01*
G01X-12598D01*
G37*
G36*
G01X1452354Y140426D02*
G03X1452435Y139869I322J-238D01*
G02X1450464Y139585I-845J-1119D01*
G03X1450383Y140142I-322J238D01*
G02X1450207Y142221I845J1118D01*
G03X1450200Y142776I-292J274D01*
G02X1450259Y144802I998J985D01*
G03X1450267Y145389I-268J297D01*
G02X1452172Y145364I966J1016D01*
G03X1452164Y144777I268J-297D01*
G02X1452219Y142801I-966J-1016D01*
G03X1452226Y142246I292J-274D01*
G02X1452354Y140426I-998J-985D01*
G37*
G36*
G01X1856050Y137539D02*
G03X1855450I-300J-265D01*
G02Y139661I-1200J1061D01*
G03X1856050I300J265D01*
G02Y137539I1200J-1061D01*
G37*
G36*
G01X1846743Y136086D02*
G03X1847327Y135919I364J167D01*
G02X1846826Y134164I773J-1170D01*
G03X1846242Y134331I-364J-167D01*
G02X1846743Y136086I-773J1170D01*
G37*
G36*
G01X67198Y137760D02*
Y132665D01*
X67189Y132581D01*
G02X64176Y132750I-1502J169D01*
G01Y137750D01*
G02X67198Y137760I1511J0D01*
G37*
G36*
G01X53080D02*
Y132665D01*
X53071Y132581D01*
G02X50058Y132750I-1502J169D01*
G01Y137751D01*
G02X53080Y137760I1511J-1D01*
G37*
G36*
G01X1920235Y133456D02*
G03X1920306Y132858I297J-268D01*
G02X1918474Y132641I-792J-1157D01*
G03X1918403Y133239I-297J268D01*
G02X1920235Y133456I792J1157D01*
G37*
G36*
G01X25591Y134628D02*
G03X26858Y135031I-2J2199D01*
G02X26874Y130393I1488J-2314D01*
G03X25620Y130806I-1283J-1786D01*
G01X25590D01*
G03X24323Y130403I2J-2199D01*
G02X24307Y135041I-1488J2314D01*
G03X25561Y134628I1283J1786D01*
G01X25591D01*
G37*
G36*
G01X1855539Y132335D02*
G03X1855351Y131782I165J-364D01*
G02X1853538Y132399I-1236J-661D01*
G03X1853726Y132952I-165J364D01*
G02X1855539Y132335I1236J661D01*
G37*
G36*
G01X1580308Y130140D02*
G03X1580312Y129585I290J-275D01*
G02X1578292Y129568I-1002J-981D01*
G03X1578288Y130123I-290J275D01*
G02X1580308Y130140I1002J981D01*
G37*
G36*
G01X1469569Y130197D02*
G03X1469606Y129592I279J-287D01*
G02X1467776Y129481I-851J-1114D01*
G03X1467739Y130086I-279J287D01*
G02X1469569Y130197I851J1114D01*
G37*
G36*
G01X1920681Y127497D02*
G03Y126924I279J-287D01*
G02X1918723I-979J-1004D01*
G03Y127497I-279J286D01*
G02X1920681I979J1004D01*
G37*
G36*
G01X62342Y130760D02*
Y125665D01*
X62333Y125581D01*
G02X59320Y125750I-1502J169D01*
G01Y130750D01*
G02X62342Y130760I1511J0D01*
G37*
G36*
G01X48412D02*
Y125665D01*
X48402Y125581D01*
G02X45388Y125750I-1502J169D01*
G01Y130750D01*
G02X48412Y130760I1512J0D01*
G37*
G36*
G01X-12598Y126754D02*
G03X-11331Y127157I-2J2199D01*
G02X-11315Y122519I1488J-2314D01*
G03X-12569Y122932I-1283J-1786D01*
G01X-12599D01*
G03X-13866Y122529I2J-2199D01*
G02X-13882Y127167I-1488J2314D01*
G03X-12628Y126754I1283J1786D01*
G01X-12598D01*
G37*
G36*
G01X1270489Y121529D02*
G03X1269911I-289J-277D01*
G02Y123471I-1011J971D01*
G03X1270489I289J277D01*
G02Y121529I1011J-971D01*
G37*
G36*
G01X1543504Y120435D02*
G03X1543326Y119880I172J-361D01*
G02X1541496Y120465I-1226J-680D01*
G03X1541674Y121020I-172J361D01*
G02X1543504Y120435I1226J680D01*
G37*
G36*
G01X1760020Y118137D02*
G03X1759380I-320J-240D01*
G02Y120063I-1280J963D01*
G03X1760020I320J240D01*
G02Y118137I1280J-963D01*
G37*
G36*
G01X53080Y123760D02*
Y118665D01*
X53071Y118581D01*
G02X50058Y118750I-1502J169D01*
G01Y123751D01*
G02X53080Y123760I1511J-1D01*
G37*
G36*
G01X63894Y123731D02*
G02X66916Y123740I1511J-1D01*
G01Y118730D01*
X66917D01*
X66916Y118645D01*
X66907Y118561D01*
G02X63894Y118730I-1502J169D01*
G01Y123731D01*
G37*
G36*
G01X1474064Y119985D02*
G03X1474087Y119386I276J-289D01*
G02X1472232Y119314I-887J-1086D01*
G03X1472209Y119913I-276J289D01*
G02X1471986Y121856I887J1086D01*
G03X1471854Y122456I-316J245D01*
G02X1473610Y122843I646J1244D01*
G03X1473742Y122243I316J-245D01*
G02X1474064Y119985I-646J-1244D01*
G37*
G36*
G01X1528024Y120779D02*
Y115684D01*
X1528015Y115600D01*
G02X1525002Y115769I-1502J169D01*
G01Y120769D01*
G02X1528024Y120779I1511J0D01*
G37*
G36*
G01X25591Y118880D02*
G03X26858Y119283I-2J2199D01*
G02X26874Y114645I1488J-2314D01*
G03X25620Y115058I-1283J-1786D01*
G01X25590D01*
G03X24323Y114655I2J-2199D01*
G02X24307Y119293I-1488J2314D01*
G03X25561Y118880I1283J1786D01*
G01X25591D01*
G37*
G36*
G01X9054Y115058D02*
G03X7787Y114655I2J-2199D01*
G02X7771Y119293I-1488J2314D01*
G03X9025Y118880I1283J1786D01*
G01X9056D01*
G03X10323Y119283I-2J2199D01*
G02X10339Y114645I1488J-2314D01*
G03X9085Y115058I-1283J-1786D01*
G01X9054D01*
G37*
G36*
G01X1907363Y116972D02*
G03X1907375Y116373I271J-294D01*
G02X1905518Y116337I-908J-1068D01*
G03X1905506Y116936I-271J294D01*
G02X1907363Y116972I908J1068D01*
G37*
G36*
G01X1303475Y113289D02*
G03Y112711I277J-289D01*
G02X1301533I-971J-1011D01*
G03Y113289I-277J289D01*
G02X1301458Y115234I971J1011D01*
G03Y115766I-298J266D01*
G02X1301467Y117644I1046J934D01*
G03X1301472Y118177I-295J269D01*
G02X1303563Y118158I1054J925D01*
G03X1303558Y117625I295J-269D01*
G02X1303550Y115766I-1054J-925D01*
G03Y115234I298J-266D01*
G02X1303475Y113289I-1046J-934D01*
G37*
G36*
G01X62212Y116760D02*
Y111665D01*
X62202Y111581D01*
G02X59188Y111750I-1502J169D01*
G01Y116750D01*
G02X62212Y116760I1512J0D01*
G37*
G36*
G01X48412D02*
Y111665D01*
X48402Y111581D01*
G02X45388Y111750I-1502J169D01*
G01Y116750D01*
G02X48412Y116760I1512J0D01*
G37*
G36*
G01X1599633Y109786D02*
G03X1599093Y109773I-263J-301D01*
G02X1599047Y111691I-903J938D01*
G03X1599587Y111704I263J301D01*
G02X1599633Y109786I903J-938D01*
G37*
G36*
G01X1188924Y109493D02*
G03X1188929Y108905I274J-292D01*
G02X1187028Y108886I-940J-1040D01*
G03X1187023Y109474I-274J292D01*
G02X1188924Y109493I940J1040D01*
G37*
G36*
G01X1152113D02*
G03X1152118Y108905I274J-292D01*
G02X1150217Y108886I-940J-1040D01*
G03X1150212Y109474I-274J292D01*
G02X1152113Y109493I940J1040D01*
G37*
G36*
G01X934593D02*
G03X934598Y108905I274J-292D01*
G02X932697Y108886I-940J-1040D01*
G03X932692Y109474I-274J292D01*
G02X934593Y109493I940J1040D01*
G37*
G36*
G01X897782D02*
G03X897787Y108905I274J-292D01*
G02X895886Y108886I-940J-1040D01*
G03X895881Y109474I-274J292D01*
G02X897782Y109493I940J1040D01*
G37*
G36*
G01X539316D02*
G03X539321Y108905I274J-292D01*
G02X537420Y108886I-940J-1040D01*
G03X537415Y109474I-274J292D01*
G02X539316Y109493I940J1040D01*
G37*
G36*
G01X502505D02*
G03X502510Y108905I274J-292D01*
G02X500609Y108886I-940J-1040D01*
G03X500604Y109474I-274J292D01*
G02X502505Y109493I940J1040D01*
G37*
G36*
G01X284985D02*
G03X284990Y108905I274J-292D01*
G02X283089Y108886I-940J-1040D01*
G03X283084Y109474I-274J292D01*
G02X284985Y109493I940J1040D01*
G37*
G36*
G01X248174D02*
G03X248179Y108905I274J-292D01*
G02X246278Y108886I-940J-1040D01*
G03X246273Y109474I-274J292D01*
G02X248174Y109493I940J1040D01*
G37*
G36*
G01X20473Y111006D02*
G03X21740Y111409I-2J2199D01*
G02X21756Y106771I1488J-2314D01*
G03X20502Y107184I-1283J-1786D01*
G01X20471D01*
G03X19204Y106781I2J-2199D01*
G02X19188Y111419I-1488J2314D01*
G03X20442Y111006I1283J1786D01*
G01X20473D01*
G37*
G36*
G01X3936Y107184D02*
G03X2669Y106781I2J-2199D01*
G02X2653Y111419I-1488J2314D01*
G03X3907Y111006I1283J1786D01*
G01X3938D01*
G03X5205Y111409I-2J2199D01*
G02X5221Y106771I1488J-2314D01*
G03X3967Y107184I-1283J-1786D01*
G01X3936D01*
G37*
G36*
G01X-12598Y111006D02*
G03X-11331Y111409I-2J2199D01*
G02X-11315Y106771I1488J-2314D01*
G03X-12569Y107184I-1283J-1786D01*
G01X-12599D01*
G03X-13866Y106781I2J-2199D01*
G02X-13882Y111419I-1488J2314D01*
G03X-12628Y111006I1283J1786D01*
G01X-12598D01*
G37*
G36*
G01X1194046Y109239D02*
G03X1194040Y108660I273J-292D01*
G02X1192106Y108680I-977J-1005D01*
G03X1192112Y109259I-273J292D01*
G02X1194046Y109239I977J1005D01*
G37*
G36*
G01X1157235D02*
G03X1157229Y108660I273J-292D01*
G02X1155295Y108680I-977J-1005D01*
G03X1155301Y109259I-273J292D01*
G02X1157235Y109239I977J1005D01*
G37*
G36*
G01X939715D02*
G03X939709Y108660I273J-292D01*
G02X937775Y108680I-977J-1005D01*
G03X937781Y109259I-273J292D01*
G02X939715Y109239I977J1005D01*
G37*
G36*
G01X902904D02*
G03X902898Y108660I273J-292D01*
G02X900964Y108680I-977J-1005D01*
G03X900970Y109259I-273J292D01*
G02X902904Y109239I977J1005D01*
G37*
G36*
G01X544438D02*
G03X544432Y108660I273J-292D01*
G02X542498Y108680I-977J-1005D01*
G03X542504Y109259I-273J292D01*
G02X544438Y109239I977J1005D01*
G37*
G36*
G01X507627D02*
G03X507621Y108660I273J-292D01*
G02X505687Y108680I-977J-1005D01*
G03X505693Y109259I-273J292D01*
G02X507627Y109239I977J1005D01*
G37*
G36*
G01X290107D02*
G03X290101Y108660I273J-292D01*
G02X288167Y108680I-977J-1005D01*
G03X288173Y109259I-273J292D01*
G02X290107Y109239I977J1005D01*
G37*
G36*
G01X253296D02*
G03X253290Y108660I273J-292D01*
G02X251356Y108680I-977J-1005D01*
G03X251362Y109259I-273J292D01*
G02X253296Y109239I977J1005D01*
G37*
G36*
G01X1853181Y106802D02*
G03X1852743Y106393I-38J-398D01*
G02X1851477Y107753I-1402J-35D01*
G03X1851915Y108162I38J398D01*
G02X1853181Y106802I1402J35D01*
G37*
G36*
G01X66896Y109760D02*
Y104665D01*
X66886Y104581D01*
G02X63872Y104750I-1502J169D01*
G01Y109751D01*
G02X66896Y109760I1512J-1D01*
G37*
G36*
G01X52892D02*
Y104665D01*
X52883Y104581D01*
G02X49870Y104750I-1502J169D01*
G01Y109750D01*
G02X52892Y109760I1511J0D01*
G37*
G36*
G01X1512424Y108332D02*
G02X1515446Y108342I1511J0D01*
G01Y104447D01*
X1515437Y104363D01*
G02X1512424Y104532I-1502J169D01*
G01Y108332D01*
G37*
G36*
G01X1811259Y105468D02*
G03X1811814Y105445I289J276D01*
G02X1811729Y103427I929J-1050D01*
G03X1811174Y103450I-289J-276D01*
G02X1811259Y105468I-929J1050D01*
G37*
G36*
G01X1525004Y103876D02*
X1524995Y104048D01*
X1524994D01*
X1525295Y109060D01*
X1525327Y109232D01*
G02X1528314Y109136I1486J-275D01*
G01X1528335Y108960D01*
X1528378D01*
X1528498Y108816D01*
X1528246Y107442D01*
X1528032Y103868D01*
X1528031Y103867D01*
X1528027Y103788D01*
X1528015Y103789D01*
G02X1525004Y103876I-1502J168D01*
G37*
G36*
G01X1490430Y104578D02*
G03X1490268Y104024I185J-355D01*
G02X1488403Y104567I-1215J-699D01*
G03X1488565Y105121I-185J355D01*
G02X1490430Y104578I1215J699D01*
G37*
G36*
G01X700017Y103801D02*
G03X699840Y103255I176J-359D01*
G02X697587Y101631I-1240J-655D01*
G03X697032Y101653I-289J-277D01*
G02X694970Y101870I-932J1047D01*
G03X694415Y101959I-323J-236D01*
G02X692290Y103599I-815J1141D01*
G03X691892Y104140I-374J142D01*
G02X692897Y106425I-82J1400D01*
G03X693485Y106390I310J253D01*
G02X695554Y106258I974J-1008D01*
G03X696081Y106170I312J249D01*
G02X697803Y105998I751J-1184D01*
G03X698373Y106014I277J288D01*
G02X700454Y105984I1027J-954D01*
G03X701021Y105949I301J264D01*
G02X703095Y105716I932J-1047D01*
G03X703642Y105615I326J232D01*
G02X703277Y103634I777J-1167D01*
G03X702730Y103735I-326J-232D01*
G02X700899Y103978I-777J1167D01*
G03X700332Y104013I-301J-264D01*
G02X700017Y103801I-933J1046D01*
G37*
G36*
G01X743520Y101574D02*
G03X742965Y101396I-194J-350D01*
G02X742380Y103226I-1265J604D01*
G03X742935Y103404I194J350D01*
G02X744736Y104095I1265J-604D01*
G03X745269Y104340I153J370D01*
G02X746064Y102605I1331J-440D01*
G03X745531Y102360I-153J-370D01*
G02X743520Y101574I-1331J440D01*
G37*
G36*
G01X25591Y103132D02*
G03X26858Y103535I-2J2199D01*
G02X26874Y98897I1488J-2314D01*
G03X25620Y99310I-1283J-1786D01*
G01X25590D01*
G03X24323Y98907I2J-2199D01*
G02X24307Y103545I-1488J2314D01*
G03X25561Y103132I1283J1786D01*
G01X25591D01*
G37*
G36*
G01X9054Y99310D02*
G03X7787Y98907I2J-2199D01*
G02X7771Y103545I-1488J2314D01*
G03X9025Y103132I1283J1786D01*
G01X9056D01*
G03X10323Y103535I-2J2199D01*
G02X10339Y98897I1488J-2314D01*
G03X9085Y99310I-1283J-1786D01*
G01X9054D01*
G37*
G36*
G01X-7480Y103132D02*
G03X-6213Y103535I-2J2199D01*
G02X-6197Y98897I1488J-2314D01*
G03X-7451Y99310I-1283J-1786D01*
G01X-7481D01*
G03X-8748Y98907I2J-2199D01*
G02X-8764Y103545I-1488J2314D01*
G03X-7510Y103132I1283J1786D01*
G01X-7480D01*
G37*
G36*
G01X1500216Y99529D02*
G02X1497194Y99501I-1511J-7D01*
G01X1497149Y102725D01*
G02X1500161Y102924I1511J21D01*
G01X1500169Y102860D01*
X1500171Y102795D01*
G02X1500172Y102767I-1510J-68D01*
G01Y102746D01*
X1500216Y99544D01*
G02Y99529I-1511J-8D01*
G37*
G36*
G01X757771Y100989D02*
G03Y100411I277J-289D01*
G02X755829I-971J-1011D01*
G03Y100989I-277J289D01*
G02X757771I971J1011D01*
G37*
G36*
G01X1375685Y100772D02*
G03Y100460I125J-156D01*
G02X1373798Y100339I-877J-1094D01*
G03Y100893I-288J277D01*
G02Y102839I1010J973D01*
G03Y103393I-288J277D01*
G02Y105339I1010J973D01*
G03Y105893I-288J277D01*
G02X1375781Y107876I1010J973D01*
G03X1376335I277J288D01*
G02X1378318Y105893I973J-1010D01*
G03Y105339I288J-277D01*
G02Y103393I-1010J-973D01*
G03Y102839I288J-277D01*
G02X1376335Y100856I-1010J-973D01*
G03X1375781I-277J-288D01*
G02X1375685Y100772I-970J1012D01*
G37*
G36*
G01X1687931Y99885D02*
G03X1688484Y99838I301J264D01*
G02X1688313Y97827I884J-1088D01*
G03X1687760Y97874I-301J-264D01*
G02X1687931Y99885I-884J1088D01*
G37*
G36*
G01X1659322Y99975D02*
G03X1659840Y99785I359J177D01*
G02X1659108Y97957I560J-1285D01*
G03X1658601Y98177I-369J-155D01*
G02X1659322Y99975I-447J1223D01*
G37*
G36*
G01X62312Y102760D02*
Y97665D01*
X62303Y97581D01*
G02X59290Y97750I-1502J169D01*
G01Y102751D01*
G02X62312Y102760I1511J-1D01*
G37*
G36*
G01X48412D02*
Y97665D01*
X48402Y97581D01*
G02X45388Y97750I-1502J169D01*
G01Y102751D01*
G02X48412Y102760I1512J-1D01*
G37*
G36*
G01X1542883Y98810D02*
G03X1542905Y98277I309J-254D01*
G02X1540817Y98190I-1005J-977D01*
G03X1540795Y98723I-309J254D01*
G02X1542883Y98810I1005J977D01*
G37*
G36*
G01X763520Y94433D02*
G03X762998Y94166I-137J-376D01*
G02X762130Y95867I-1348J384D01*
G03X762652Y96134I137J376D01*
G02X763520Y94433I1348J-384D01*
G37*
G36*
G01X1525232Y98265D02*
G02X1528256Y98275I1512J0D01*
G01Y93180D01*
X1528246Y93096D01*
G02X1525232Y93265I-1502J169D01*
G01Y98265D01*
G37*
G36*
G01X1405579Y90903D02*
G03X1404913I-333J-222D01*
G02X1403448Y93050I-1167J777D01*
G03X1403759Y93494I-85J391D01*
G02X1406205Y94601I1390J185D01*
G03X1406829Y94628I301J263D01*
G02X1408382Y92463I1131J-828D01*
G03X1408113Y91993I121J-381D01*
G02X1405579Y90903I-1367J-313D01*
G37*
G36*
G01X35367Y93038D02*
G03X35733Y92550I390J-89D01*
G02X34283Y91462I-83J-1400D01*
G03X33917Y91950I-390J89D01*
G02X35367Y93038I83J1400D01*
G37*
G36*
G01X1908421Y92839D02*
G03X1908430Y92252I276J-289D01*
G02X1906392Y92220I-1002J-1119D01*
G03X1906383Y92807I-276J289D01*
G02X1906348Y92840I1013J1109D01*
G03X1905778Y92823I-277J-289D01*
G02X1903649Y94939I-1100J1022D01*
G03X1903662Y95508I-274J291D01*
G02X1905786Y97632I1080J1044D01*
G03X1906355Y97645I278J288D01*
G02X1908485Y95528I1092J-1031D01*
G03X1908472Y94963I276J-289D01*
G02X1908421Y92839I-1087J-1037D01*
G37*
G36*
G01X68725Y89388D02*
X63724D01*
G02X63725Y92412I1J1512D01*
G01X68725D01*
G02X70236Y90910I-1J-1512D01*
G01Y90815D01*
X70227Y90731D01*
G02X68725Y89388I-1502J168D01*
G37*
G36*
G01X52892Y95760D02*
Y90665D01*
X52883Y90581D01*
G02X49870Y90750I-1502J169D01*
G01Y95750D01*
G02X52892Y95760I1511J0D01*
G37*
G36*
G01X1676372Y91718D02*
G03X1676946Y91514I374J142D01*
G02X1676339Y89802I703J-1213D01*
G03X1675765Y90006I-374J-142D01*
G02X1676372Y91718I-703J1213D01*
G37*
G36*
G01X733655Y89330D02*
G03X734242Y89312I302J263D01*
G02X734185Y87407I999J-983D01*
G03X733598Y87425I-302J-263D01*
G02X731603Y87422I-999J983D01*
G03X731034I-284J-282D01*
G02Y89394I-996J986D01*
G03X731603I285J282D01*
G02X733655Y89330I996J-986D01*
G37*
G36*
G01X1542878Y89123D02*
G03X1542807Y88580I253J-309D01*
G02X1540780Y88844I-1137J-820D01*
G03X1540851Y89387I-253J309D01*
G02X1540978Y91180I1137J820D01*
G03Y91734I-288J277D01*
G02X1543287Y93234I1010J973D01*
G03X1543774Y93002I371J151D01*
G02X1543857Y90296I406J-1342D01*
G03X1543370Y89973I-92J-389D01*
G02X1542878Y89123I-1383J233D01*
G37*
G36*
G01X1230845Y89103D02*
G03Y88525I277J-289D01*
G02X1228903I-971J-1011D01*
G03Y89103I-277J289D01*
G02X1230845I971J1011D01*
G37*
G36*
G01X1194034D02*
G03Y88525I277J-289D01*
G02X1192092I-971J-1011D01*
G03Y89103I-277J289D01*
G02X1194034I971J1011D01*
G37*
G36*
G01X1157223D02*
G03Y88525I277J-289D01*
G02X1155281I-971J-1011D01*
G03Y89103I-277J289D01*
G02X1157223I971J1011D01*
G37*
G36*
G01X1120411D02*
G03Y88525I277J-289D01*
G02X1118469I-971J-1011D01*
G03Y89103I-277J289D01*
G02X1120411I971J1011D01*
G37*
G36*
G01X939703D02*
G03Y88525I277J-289D01*
G02X937761I-971J-1011D01*
G03Y89103I-277J289D01*
G02X939703I971J1011D01*
G37*
G36*
G01X902892D02*
G03Y88525I277J-289D01*
G02X900950I-971J-1011D01*
G03Y89103I-277J289D01*
G02X902892I971J1011D01*
G37*
G36*
G01X866081D02*
G03Y88525I277J-289D01*
G02X864139I-971J-1011D01*
G03Y89103I-277J289D01*
G02X866081I971J1011D01*
G37*
G36*
G01X829270D02*
G03Y88525I277J-289D01*
G02X827328I-971J-1011D01*
G03Y89103I-277J289D01*
G02X829270I971J1011D01*
G37*
G36*
G01X792459D02*
G03Y88525I277J-289D01*
G02X790517I-971J-1011D01*
G03Y89103I-277J289D01*
G02X792459I971J1011D01*
G37*
G36*
G01X581237D02*
G03Y88525I277J-289D01*
G02X579295I-971J-1011D01*
G03Y89103I-277J289D01*
G02X581237I971J1011D01*
G37*
G36*
G01X544426D02*
G03Y88525I277J-289D01*
G02X542484I-971J-1011D01*
G03Y89103I-277J289D01*
G02X544426I971J1011D01*
G37*
G36*
G01X507615D02*
G03Y88525I277J-289D01*
G02X505673I-971J-1011D01*
G03Y89103I-277J289D01*
G02X507615I971J1011D01*
G37*
G36*
G01X470803D02*
G03Y88525I277J-289D01*
G02X468861I-971J-1011D01*
G03Y89103I-277J289D01*
G02X470803I971J1011D01*
G37*
G36*
G01X290095D02*
G03Y88525I277J-289D01*
G02X288153I-971J-1011D01*
G03Y89103I-277J289D01*
G02X290095I971J1011D01*
G37*
G36*
G01X253284D02*
G03Y88525I277J-289D01*
G02X251342I-971J-1011D01*
G03Y89103I-277J289D01*
G02X253284I971J1011D01*
G37*
G36*
G01X216473D02*
G03Y88525I277J-289D01*
G02X214531I-971J-1011D01*
G03Y89103I-277J289D01*
G02X216473I971J1011D01*
G37*
G36*
G01X179662D02*
G03Y88525I277J-289D01*
G02X177720I-971J-1011D01*
G03Y89103I-277J289D01*
G02X179662I971J1011D01*
G37*
G36*
G01X142851D02*
G03Y88525I277J-289D01*
G02X140909I-971J-1011D01*
G03Y89103I-277J289D01*
G02X142851I971J1011D01*
G37*
G36*
G01X1225745Y88889D02*
G03Y88311I277J-289D01*
G02X1223803I-971J-1011D01*
G03Y88889I-277J289D01*
G02X1225745I971J1011D01*
G37*
G36*
G01X1188934D02*
G03Y88311I277J-289D01*
G02X1186992I-971J-1011D01*
G03Y88889I-277J289D01*
G02X1188934I971J1011D01*
G37*
G36*
G01X1152123D02*
G03Y88311I277J-289D01*
G02X1150181I-971J-1011D01*
G03Y88889I-277J289D01*
G02X1152123I971J1011D01*
G37*
G36*
G01X1115311D02*
G03Y88311I277J-289D01*
G02X1113369I-971J-1011D01*
G03Y88889I-277J289D01*
G02X1115311I971J1011D01*
G37*
G36*
G01X934603D02*
G03Y88311I277J-289D01*
G02X932661I-971J-1011D01*
G03Y88889I-277J289D01*
G02X934603I971J1011D01*
G37*
G36*
G01X897792D02*
G03Y88311I277J-289D01*
G02X895850I-971J-1011D01*
G03Y88889I-277J289D01*
G02X897792I971J1011D01*
G37*
G36*
G01X860981D02*
G03Y88311I277J-289D01*
G02X859039I-971J-1011D01*
G03Y88889I-277J289D01*
G02X860981I971J1011D01*
G37*
G36*
G01X824170D02*
G03Y88311I277J-289D01*
G02X822228I-971J-1011D01*
G03Y88889I-277J289D01*
G02X824170I971J1011D01*
G37*
G36*
G01X787359D02*
G03Y88311I277J-289D01*
G02X785417I-971J-1011D01*
G03Y88889I-277J289D01*
G02X787359I971J1011D01*
G37*
G36*
G01X576137D02*
G03Y88311I277J-289D01*
G02X574195I-971J-1011D01*
G03Y88889I-277J289D01*
G02X576137I971J1011D01*
G37*
G36*
G01X539326D02*
G03Y88311I277J-289D01*
G02X537384I-971J-1011D01*
G03Y88889I-277J289D01*
G02X539326I971J1011D01*
G37*
G36*
G01X502515D02*
G03Y88311I277J-289D01*
G02X500573I-971J-1011D01*
G03Y88889I-277J289D01*
G02X502515I971J1011D01*
G37*
G36*
G01X465703D02*
G03Y88311I277J-289D01*
G02X463761I-971J-1011D01*
G03Y88889I-277J289D01*
G02X465703I971J1011D01*
G37*
G36*
G01X284995D02*
G03Y88311I277J-289D01*
G02X283053I-971J-1011D01*
G03Y88889I-277J289D01*
G02X284995I971J1011D01*
G37*
G36*
G01X248184D02*
G03Y88311I277J-289D01*
G02X246242I-971J-1011D01*
G03Y88889I-277J289D01*
G02X248184I971J1011D01*
G37*
G36*
G01X211373D02*
G03Y88311I277J-289D01*
G02X209431I-971J-1011D01*
G03Y88889I-277J289D01*
G02X211373I971J1011D01*
G37*
G36*
G01X174562D02*
G03Y88311I277J-289D01*
G02X172620I-971J-1011D01*
G03Y88889I-277J289D01*
G02X174562I971J1011D01*
G37*
G36*
G01X137751D02*
G03Y88311I277J-289D01*
G02X135809I-971J-1011D01*
G03Y88889I-277J289D01*
G02X137751I971J1011D01*
G37*
G36*
G01X1810901Y85810D02*
G03X1810333I-284J-282D01*
G02X1808171Y87895I-1065J1059D01*
G03Y88441I-292J273D01*
G02X1808209Y90534I1096J1027D01*
G03Y91102I-282J284D01*
G02Y93234I1058J1066D01*
G03Y93802I-282J284D01*
G02X1810333Y95926I1058J1066D01*
G03X1810901I284J282D01*
G02X1813033I1066J-1058D01*
G03X1813601I284J282D01*
G02X1815725Y93802I1066J-1058D01*
G03Y93234I282J-284D01*
G02Y91102I-1058J-1066D01*
G03Y90534I282J-284D01*
G02X1815763Y88441I-1058J-1066D01*
G03Y87895I292J-273D01*
G02X1813601Y85810I-1097J-1026D01*
G03X1813033I-284J-282D01*
G02X1810901I-1066J1058D01*
G37*
G36*
G01X1501386Y90491D02*
Y86596D01*
X1501377Y86512D01*
G02X1498364Y86681I-1502J169D01*
G01Y90481D01*
G02X1501386Y90491I1511J0D01*
G37*
G36*
G01X1598489Y83529D02*
G03X1597911I-289J-277D01*
G02Y85471I-1011J971D01*
G03X1598489I289J277D01*
G02X1600473Y85510I1011J-971D01*
G03X1601027I277J288D01*
G02Y83490I973J-1010D01*
G03X1600473I-277J-288D01*
G02X1598489Y83529I-973J1010D01*
G37*
G36*
G01X1953132Y85697D02*
G03X1953664Y85419I388J95D01*
G02X1952807Y83777I505J-1308D01*
G03X1952275Y84055I-388J-95D01*
G02X1950797Y84353I-505J1308D01*
G03X1950243I-277J-288D01*
G02X1948259Y84392I-973J1010D01*
G03X1947681I-289J-277D01*
G02X1945660Y86336I-1010J972D01*
G03Y86890I-288J277D01*
G02X1945623Y88795I1010J972D01*
G03X1945601Y89350I-299J266D01*
G02X1945560Y91336I969J1013D01*
G03Y91890I-288J277D01*
G02X1947581Y93834I1011J972D01*
G03X1948159I289J277D01*
G02X1948419Y94047I1012J-970D01*
G03X1948517Y94635I-214J338D01*
G02X1950583Y96523I1092J879D01*
G03X1951137I277J288D01*
G02X1953293Y96265I973J-1010D01*
G03X1953904Y96187I338J214D01*
G02X1955834Y96173I958J-1024D01*
G03X1956388I277J288D01*
G02X1958096Y93969I972J-1010D01*
G03X1957992Y93381I210J-340D01*
G02X1955918Y91503I-1100J-869D01*
G03X1955364I-277J-288D01*
G02X1953216Y91747I-973J1010D01*
G03X1952613Y91825I-335J-218D01*
G02X1952547Y91769I-940J1041D01*
G03Y91457I125J-156D01*
G02X1952717Y89431I-877J-1094D01*
G03X1952739Y88876I299J-266D01*
G02X1952780Y86890I-969J-1013D01*
G03Y86336I288J-277D01*
G02X1953132Y85697I-1010J-973D01*
G37*
G36*
G01X753559Y85177D02*
G03X753577Y84578I274J-292D01*
G02X751721Y84523I-897J-1078D01*
G03X751703Y85122I-274J292D01*
G02X753559Y85177I897J1078D01*
G37*
G36*
G01X1491579Y84665D02*
G03X1491783Y84181I380J-125D01*
G02X1489789Y83197I-619J-1258D01*
G03X1489529Y83653I-392J78D01*
G02X1491579Y84665I528J1512D01*
G37*
G36*
G01X1664527Y80590D02*
G03X1663973I-277J-288D01*
G02Y82610I-973J1010D01*
G03X1664527I277J288D01*
G02X1666473I973J-1010D01*
G03X1667027I277J288D01*
G02X1668973I973J-1010D01*
G03X1669527I277J288D01*
G02X1671473I973J-1010D01*
G03X1672027I277J288D01*
G02X1673973I973J-1010D01*
G03X1674527I277J288D01*
G02X1676473I973J-1010D01*
G03X1677027I277J288D01*
G02Y80590I973J-1010D01*
G03X1676473I-277J-288D01*
G02X1674527I-973J1010D01*
G03X1673973I-277J-288D01*
G02X1672027I-973J1010D01*
G03X1671473I-277J-288D01*
G02X1669527I-973J1010D01*
G03X1668973I-277J-288D01*
G02X1667027I-973J1010D01*
G03X1666473I-277J-288D01*
G02X1664527I-973J1010D01*
G37*
G36*
G01X1540631Y78303D02*
G03X1540043Y78212I-253J-310D01*
G02X1539759Y80064I-1173J768D01*
G03X1540347Y80155I253J310D01*
G02X1540631Y78303I1173J-768D01*
G37*
G36*
G01X1695009Y79103D02*
G03X1695533Y79134I244J317D01*
G02Y76848I1122J-1143D01*
G03X1695009Y76879I-280J-286D01*
G02X1693182Y76981I-854J1112D01*
G03X1692628I-277J-288D01*
G02X1690682I-973J1010D01*
G03X1690128I-277J-288D01*
G02Y79001I-973J1010D01*
G03X1690682I277J288D01*
G02X1692628I973J-1010D01*
G03X1693182I277J288D01*
G02X1695009Y79103I973J-1010D01*
G37*
G36*
G01X1822089Y76271D02*
G03X1821521I-284J-282D01*
G02X1819377Y78375I-1065J1059D01*
G03X1819384Y78925I-287J279D01*
G02X1821554Y81001I1104J1018D01*
G03X1822122I284J282D01*
G02X1824266Y78897I1065J-1059D01*
G03X1824259Y78347I287J-279D01*
G02X1822089Y76271I-1104J-1018D01*
G37*
G36*
G01X1394060Y75160D02*
G03X1393524I-268J-297D01*
G02X1391612Y77211I-940J1040D01*
G03Y77787I-277J288D01*
G02X1393523Y79839I972J1011D01*
G03X1394059Y79840I267J297D01*
G02X1395934Y79846I941J-1040D01*
G03X1396466I266J298D01*
G02X1398371Y77789I934J-1045D01*
G03Y77211I277J-289D01*
G02X1396466Y75154I-971J-1012D01*
G03X1395934I-266J-298D01*
G02X1394060Y75160I-934J1046D01*
G37*
G36*
G01X1581396Y74870D02*
G03X1580818I-289J-277D01*
G02Y76812I-1011J971D01*
G03X1581396I289J277D01*
G02Y74870I1011J-971D01*
G37*
G36*
G01X1571535Y76354D02*
G03X1572104Y76339I292J273D01*
G02X1572052Y74370I972J-1011D01*
G03X1571483Y74385I-292J-273D01*
G02X1571535Y76354I-972J1011D01*
G37*
G36*
G01X732634Y74469D02*
G03X732024Y74447I-296J-270D01*
G02X731960Y76258I-1101J868D01*
G03X732570Y76280I296J270D01*
G02X732634Y74469I1101J-868D01*
G37*
G36*
G01X1622583Y74541D02*
G03X1622036Y74329I-175J-359D01*
G02X1621350Y76106I-1303J518D01*
G03X1621897Y76318I175J359D01*
G02X1622583Y74541I1303J-518D01*
G37*
G36*
G01X1675015Y75899D02*
G03X1675598Y75776I347J200D01*
G02X1675213Y73947I830J-1130D01*
G03X1674630Y74070I-347J-200D01*
G02X1675015Y75899I-830J1130D01*
G37*
G36*
G01X1680934Y75447D02*
G03X1681488Y75412I295J270D01*
G02X1681362Y73397I908J-1068D01*
G03X1680808Y73432I-295J-270D01*
G02X1680934Y75447I-908J1068D01*
G37*
G36*
G01X62027Y72990D02*
G03X61473I-277J-288D01*
G02X59490Y74973I-973J1010D01*
G03Y75527I-288J277D01*
G02Y77473I1010J973D01*
G03Y78027I-288J277D01*
G02Y79973I1010J973D01*
G03Y80527I-288J277D01*
G02X61473Y82510I1010J973D01*
G03X62027I277J288D01*
G02X64010Y80527I973J-1010D01*
G03Y79973I288J-277D01*
G02Y78027I-1010J-973D01*
G03Y77473I288J-277D01*
G02Y75527I-1010J-973D01*
G03Y74973I288J-277D01*
G02X62027Y72990I-1010J-973D01*
G37*
G36*
G01X1454277Y74673D02*
G03X1454869Y74662I301J263D01*
G02X1454833Y72777I1020J-962D01*
G03X1454241Y72788I-301J-263D01*
G02X1454277Y74673I-1020J962D01*
G37*
G36*
G01X1563646Y75326D02*
G03X1563707Y74752I306J-258D01*
G02X1561779Y74547I-857J-1110D01*
G03X1561718Y75121I-306J258D01*
G02X1563646Y75326I857J1110D01*
G37*
G36*
G01X1895824Y72653D02*
G03X1895156Y72632I-327J-230D01*
G02X1893701Y74743I-1195J733D01*
G03X1894010Y75250I-74J393D01*
G02X1896722Y75344I1344J400D01*
G03X1897081Y74858I390J-87D01*
G02X1895824Y72653I-111J-1398D01*
G37*
G36*
G01X76473Y71510D02*
G03X77027I277J288D01*
G02X77776Y71884I972J-1010D01*
G03X78109Y72328I-64J395D01*
G02X79724Y71116I1391J172D01*
G03X79391Y70672I64J-395D01*
G02X77027Y69490I-1391J-172D01*
G03X76473I-277J-288D01*
G02X74527I-973J1010D01*
G03X73973I-277J-288D01*
G02X72027I-973J1010D01*
G03X71473I-277J-288D01*
G02X69527I-973J1010D01*
G03X68973I-277J-288D01*
G02X67027I-973J1010D01*
G03X66473I-277J-288D01*
G02X64527I-973J1010D01*
G03X63973I-277J-288D01*
G02X62027I-973J1010D01*
G03X61473I-277J-288D01*
G02Y71510I-973J1010D01*
G03X62027I277J288D01*
G02X63973I973J-1010D01*
G03X64527I277J288D01*
G02X66473I973J-1010D01*
G03X67027I277J288D01*
G02X68973I973J-1010D01*
G03X69527I277J288D01*
G02X71473I973J-1010D01*
G03X72027I277J288D01*
G02X73973I973J-1010D01*
G03X74527I277J288D01*
G02X76473I973J-1010D01*
G37*
G36*
G01X1825029Y71312D02*
G03X1825054Y70681I258J-306D01*
G02X1823028Y68497I-873J-1222D01*
G03X1822416Y68499I-307J-257D01*
G02X1820278Y70598I-1146J971D01*
G03X1820236Y71231I-264J300D01*
G02X1822257Y73401I834J1249D01*
G03X1822886Y73396I316J245D01*
G02X1825029Y71312I1175J-936D01*
G37*
G36*
G01X1795700Y70821D02*
G03X1796100Y70402I400J-19D01*
G01X1796101D01*
G02X1794500Y68877I-1J-1602D01*
G03X1794100Y69296I-400J19D01*
G01X1794099D01*
G02X1795700Y70821I1J1602D01*
G37*
G36*
G01X1225735Y70178D02*
G03X1225740Y69590I274J-292D01*
G02X1223839Y69571I-940J-1040D01*
G03X1223834Y70159I-274J292D01*
G02X1225735Y70178I940J1040D01*
G37*
G36*
G01X1188924D02*
G03X1188929Y69590I274J-292D01*
G02X1187028Y69571I-940J-1040D01*
G03X1187023Y70159I-274J292D01*
G02X1188924Y70178I940J1040D01*
G37*
G36*
G01X1152113D02*
G03X1152118Y69590I274J-292D01*
G02X1150217Y69571I-940J-1040D01*
G03X1150212Y70159I-274J292D01*
G02X1152113Y70178I940J1040D01*
G37*
G36*
G01X1115301D02*
G03X1115306Y69590I274J-292D01*
G02X1113405Y69571I-940J-1040D01*
G03X1113400Y70159I-274J292D01*
G02X1115301Y70178I940J1040D01*
G37*
G36*
G01X934593D02*
G03X934598Y69590I274J-292D01*
G02X932697Y69571I-940J-1040D01*
G03X932692Y70159I-274J292D01*
G02X934593Y70178I940J1040D01*
G37*
G36*
G01X897782D02*
G03X897787Y69590I274J-292D01*
G02X895886Y69571I-940J-1040D01*
G03X895881Y70159I-274J292D01*
G02X897782Y70178I940J1040D01*
G37*
G36*
G01X860971D02*
G03X860976Y69590I274J-292D01*
G02X859075Y69571I-940J-1040D01*
G03X859070Y70159I-274J292D01*
G02X860971Y70178I940J1040D01*
G37*
G36*
G01X824160D02*
G03X824165Y69590I274J-292D01*
G02X822264Y69571I-940J-1040D01*
G03X822259Y70159I-274J292D01*
G02X824160Y70178I940J1040D01*
G37*
G36*
G01X787349D02*
G03X787354Y69590I274J-292D01*
G02X785453Y69571I-940J-1040D01*
G03X785448Y70159I-274J292D01*
G02X787349Y70178I940J1040D01*
G37*
G36*
G01X576127D02*
G03X576132Y69590I274J-292D01*
G02X574231Y69571I-940J-1040D01*
G03X574226Y70159I-274J292D01*
G02X576127Y70178I940J1040D01*
G37*
G36*
G01X539316D02*
G03X539321Y69590I274J-292D01*
G02X537420Y69571I-940J-1040D01*
G03X537415Y70159I-274J292D01*
G02X539316Y70178I940J1040D01*
G37*
G36*
G01X502505D02*
G03X502510Y69590I274J-292D01*
G02X500609Y69571I-940J-1040D01*
G03X500604Y70159I-274J292D01*
G02X502505Y70178I940J1040D01*
G37*
G36*
G01X465693D02*
G03X465698Y69590I274J-292D01*
G02X463797Y69571I-940J-1040D01*
G03X463792Y70159I-274J292D01*
G02X465693Y70178I940J1040D01*
G37*
G36*
G01X284985D02*
G03X284990Y69590I274J-292D01*
G02X283089Y69571I-940J-1040D01*
G03X283084Y70159I-274J292D01*
G02X284985Y70178I940J1040D01*
G37*
G36*
G01X248174D02*
G03X248179Y69590I274J-292D01*
G02X246278Y69571I-940J-1040D01*
G03X246273Y70159I-274J292D01*
G02X248174Y70178I940J1040D01*
G37*
G36*
G01X211363D02*
G03X211368Y69590I274J-292D01*
G02X209467Y69571I-940J-1040D01*
G03X209462Y70159I-274J292D01*
G02X211363Y70178I940J1040D01*
G37*
G36*
G01X174552D02*
G03X174557Y69590I274J-292D01*
G02X172656Y69571I-940J-1040D01*
G03X172651Y70159I-274J292D01*
G02X174552Y70178I940J1040D01*
G37*
G36*
G01X137741D02*
G03X137746Y69590I274J-292D01*
G02X135845Y69571I-940J-1040D01*
G03X135840Y70159I-274J292D01*
G02X137741Y70178I940J1040D01*
G37*
G36*
G01X1230841Y69934D02*
G03Y69355I276J-289D01*
G02X1228907I-967J-1015D01*
G03Y69934I-276J290D01*
G02X1230841I967J1015D01*
G37*
G36*
G01X1194030D02*
G03Y69355I276J-289D01*
G02X1192096I-967J-1015D01*
G03Y69934I-276J290D01*
G02X1194030I967J1015D01*
G37*
G36*
G01X1157219D02*
G03Y69355I276J-289D01*
G02X1155285I-967J-1015D01*
G03Y69934I-276J290D01*
G02X1157219I967J1015D01*
G37*
G36*
G01X1120407D02*
G03Y69355I276J-289D01*
G02X1118473I-967J-1015D01*
G03Y69934I-276J290D01*
G02X1120407I967J1015D01*
G37*
G36*
G01X939699D02*
G03Y69355I276J-289D01*
G02X937765I-967J-1015D01*
G03Y69934I-276J290D01*
G02X939699I967J1015D01*
G37*
G36*
G01X902888D02*
G03Y69355I276J-289D01*
G02X900954I-967J-1015D01*
G03Y69934I-276J290D01*
G02X902888I967J1015D01*
G37*
G36*
G01X866077D02*
G03Y69355I276J-289D01*
G02X864143I-967J-1015D01*
G03Y69934I-276J290D01*
G02X866077I967J1015D01*
G37*
G36*
G01X829266D02*
G03Y69355I276J-289D01*
G02X827332I-967J-1015D01*
G03Y69934I-276J290D01*
G02X829266I967J1015D01*
G37*
G36*
G01X792455D02*
G03Y69355I276J-289D01*
G02X790521I-967J-1015D01*
G03Y69934I-276J290D01*
G02X792455I967J1015D01*
G37*
G36*
G01X581233D02*
G03Y69355I276J-289D01*
G02X579299I-967J-1015D01*
G03Y69934I-276J290D01*
G02X581233I967J1015D01*
G37*
G36*
G01X544422D02*
G03Y69355I276J-289D01*
G02X542488I-967J-1015D01*
G03Y69934I-276J290D01*
G02X544422I967J1015D01*
G37*
G36*
G01X507611D02*
G03Y69355I276J-289D01*
G02X505677I-967J-1015D01*
G03Y69934I-276J290D01*
G02X507611I967J1015D01*
G37*
G36*
G01X470799D02*
G03Y69355I276J-289D01*
G02X468865I-967J-1015D01*
G03Y69934I-276J290D01*
G02X470799I967J1015D01*
G37*
G36*
G01X290091D02*
G03Y69355I276J-289D01*
G02X288157I-967J-1015D01*
G03Y69934I-276J290D01*
G02X290091I967J1015D01*
G37*
G36*
G01X253280D02*
G03Y69355I276J-289D01*
G02X251346I-967J-1015D01*
G03Y69934I-276J290D01*
G02X253280I967J1015D01*
G37*
G36*
G01X216469D02*
G03Y69355I276J-289D01*
G02X214535I-967J-1015D01*
G03Y69934I-276J290D01*
G02X216469I967J1015D01*
G37*
G36*
G01X179658D02*
G03Y69355I276J-289D01*
G02X177724I-967J-1015D01*
G03Y69934I-276J290D01*
G02X179658I967J1015D01*
G37*
G36*
G01X142847D02*
G03Y69355I276J-289D01*
G02X140913I-967J-1015D01*
G03Y69934I-276J290D01*
G02X142847I967J1015D01*
G37*
G36*
G01X1733Y66210D02*
G03X1351Y66698I-390J88D01*
G02X2749Y67790I31J1402D01*
G03X3131Y67302I390J-88D01*
G02X1733Y66210I-31J-1402D01*
G37*
G36*
G01X1328429Y66950D02*
G03Y66350I265J-300D01*
G02X1326571I-929J-1050D01*
G03Y66950I-265J300D01*
G02X1326598Y69073I929J1050D01*
G03X1326591Y69692I-257J307D01*
G02X1328369Y69713I876J1094D01*
G03X1328376Y69094I257J-307D01*
G02X1328429Y66950I-876J-1094D01*
G37*
G36*
G01X1649871Y64260D02*
G03X1649293Y64256I-287J-279D01*
G02X1649281Y66198I-1017J965D01*
G03X1649859Y66202I287J279D01*
G02X1649871Y64260I1017J-965D01*
G37*
G36*
G01X734722Y65252D02*
G03X734742Y64719I308J-255D01*
G02X732775Y62723I-1010J-972D01*
G03X732242Y62735I-273J-292D01*
G02X730252Y64695I-910J1067D01*
G03X730232Y65228I-308J255D01*
G02X730180Y67115I1010J972D01*
G03X730171Y67648I-303J261D01*
G02X732157Y69624I1029J952D01*
G03X732690Y69612I273J292D01*
G02X734662Y67631I909J-1067D01*
G03X734671Y67098I303J-261D01*
G02X734722Y65252I-1029J-952D01*
G37*
G36*
G01X1785725Y65065D02*
G03X1786169Y64732I395J64D01*
G02X1784957Y63117I172J-1391D01*
G03X1784513Y63450I-395J-64D01*
G02X1785725Y65065I-172J1391D01*
G37*
G36*
G01X1610284Y62579D02*
G03X1609752Y62364I-162J-365D01*
G02X1607065Y63094I-1300J526D01*
G03X1606698Y63551I-396J58D01*
G02X1608184Y64745I99J1398D01*
G03X1608551Y64288I396J-58D01*
G02X1609021Y64172I-96J-1399D01*
G03X1609553Y64387I162J365D01*
G02X1610284Y62579I1300J-526D01*
G37*
G36*
G01X1734177Y57140D02*
G03X1733623I-277J-288D01*
G02X1731640Y59123I-973J1010D01*
G03Y59677I-288J277D01*
G02X1733660I1010J973D01*
G03Y59123I288J-277D01*
G02X1733744Y59027I-1012J-970D01*
G03X1734056I156J125D01*
G02X1734177Y57140I1094J-877D01*
G37*
G36*
G01X15614Y55240D02*
G03X15036I-289J-277D01*
G02Y57182I-1011J971D01*
G03X15614I289J277D01*
G02Y55240I1011J-971D01*
G37*
G36*
G01X60527Y54990D02*
G03X59973I-277J-288D01*
G02X57990Y56973I-973J1010D01*
G03Y57527I-288J277D01*
G02Y59473I1010J973D01*
G03Y60027I-288J277D01*
G02X59973Y62010I1010J973D01*
G03X60527I277J288D01*
G02X62510Y60027I973J-1010D01*
G03Y59473I288J-277D01*
G02Y57527I-1010J-973D01*
G03Y56973I288J-277D01*
G02X60527Y54990I-1010J-973D01*
G37*
G36*
G01X1816718Y55668D02*
G03X1817330Y55663I308J255D01*
G02X1817315Y53859I1066J-911D01*
G03X1816703Y53864I-308J-255D01*
G02X1816718Y55668I-1066J911D01*
G37*
G36*
G01X1825763Y54670D02*
G03X1825948Y54402I188J-68D01*
G02X1824461Y53215I-18J-1502D01*
G03X1824129Y53694I-391J84D01*
G02X1823379Y56326I221J1486D01*
G03X1823392Y56926I-258J306D01*
G02X1823160Y58862I1018J1104D01*
G03X1823038Y59424I-333J222D01*
G02X1825080Y59868I792J1276D01*
G03X1825202Y59306I333J-222D01*
G02X1825897Y58245I-792J-1277D01*
G03X1826420Y57923I396J57D01*
G02X1826346Y55104I480J-1423D01*
G03X1825810Y54826I-147J-372D01*
G02X1825763Y54670I-1460J355D01*
G37*
G36*
G01X1668527Y50490D02*
G03X1667973I-277J-288D01*
G02Y52510I-973J1010D01*
G03X1668527I277J288D01*
G02Y50490I973J-1010D01*
G37*
G36*
G01X1230845Y51303D02*
G03Y50725I277J-289D01*
G02X1228903I-971J-1011D01*
G03Y51303I-277J289D01*
G02X1230845I971J1011D01*
G37*
G36*
G01X1194034D02*
G03Y50725I277J-289D01*
G02X1192092I-971J-1011D01*
G03Y51303I-277J289D01*
G02X1194034I971J1011D01*
G37*
G36*
G01X1157222D02*
G03Y50725I277J-289D01*
G02X1155280I-971J-1011D01*
G03Y51303I-277J289D01*
G02X1157222I971J1011D01*
G37*
G36*
G01X1120411D02*
G03Y50725I277J-289D01*
G02X1118469I-971J-1011D01*
G03Y51303I-277J289D01*
G02X1120411I971J1011D01*
G37*
G36*
G01X939703D02*
G03Y50725I277J-289D01*
G02X937761I-971J-1011D01*
G03Y51303I-277J289D01*
G02X939703I971J1011D01*
G37*
G36*
G01X902892D02*
G03Y50725I277J-289D01*
G02X900950I-971J-1011D01*
G03Y51303I-277J289D01*
G02X902892I971J1011D01*
G37*
G36*
G01X866081D02*
G03Y50725I277J-289D01*
G02X864139I-971J-1011D01*
G03Y51303I-277J289D01*
G02X866081I971J1011D01*
G37*
G36*
G01X829270D02*
G03Y50725I277J-289D01*
G02X827328I-971J-1011D01*
G03Y51303I-277J289D01*
G02X829270I971J1011D01*
G37*
G36*
G01X792459D02*
G03Y50725I277J-289D01*
G02X790517I-971J-1011D01*
G03Y51303I-277J289D01*
G02X792459I971J1011D01*
G37*
G36*
G01X581237D02*
G03Y50725I277J-289D01*
G02X579295I-971J-1011D01*
G03Y51303I-277J289D01*
G02X581237I971J1011D01*
G37*
G36*
G01X544426D02*
G03Y50725I277J-289D01*
G02X542484I-971J-1011D01*
G03Y51303I-277J289D01*
G02X544426I971J1011D01*
G37*
G36*
G01X507614D02*
G03Y50725I277J-289D01*
G02X505672I-971J-1011D01*
G03Y51303I-277J289D01*
G02X507614I971J1011D01*
G37*
G36*
G01X470803D02*
G03Y50725I277J-289D01*
G02X468861I-971J-1011D01*
G03Y51303I-277J289D01*
G02X470803I971J1011D01*
G37*
G36*
G01X290095D02*
G03Y50725I277J-289D01*
G02X288153I-971J-1011D01*
G03Y51303I-277J289D01*
G02X290095I971J1011D01*
G37*
G36*
G01X253284D02*
G03Y50725I277J-289D01*
G02X251342I-971J-1011D01*
G03Y51303I-277J289D01*
G02X253284I971J1011D01*
G37*
G36*
G01X216473D02*
G03Y50725I277J-289D01*
G02X214531I-971J-1011D01*
G03Y51303I-277J289D01*
G02X216473I971J1011D01*
G37*
G36*
G01X179662D02*
G03Y50725I277J-289D01*
G02X177720I-971J-1011D01*
G03Y51303I-277J289D01*
G02X179662I971J1011D01*
G37*
G36*
G01X142851D02*
G03Y50725I277J-289D01*
G02X140909I-971J-1011D01*
G03Y51303I-277J289D01*
G02X142851I971J1011D01*
G37*
G36*
G01X1225745Y51089D02*
G03Y50511I277J-289D01*
G02X1223803I-971J-1011D01*
G03Y51089I-277J289D01*
G02X1225745I971J1011D01*
G37*
G36*
G01X1188934D02*
G03Y50511I277J-289D01*
G02X1186992I-971J-1011D01*
G03Y51089I-277J289D01*
G02X1188934I971J1011D01*
G37*
G36*
G01X1152122D02*
G03Y50511I277J-289D01*
G02X1150180I-971J-1011D01*
G03Y51089I-277J289D01*
G02X1152122I971J1011D01*
G37*
G36*
G01X1115311D02*
G03Y50511I277J-289D01*
G02X1113369I-971J-1011D01*
G03Y51089I-277J289D01*
G02X1115311I971J1011D01*
G37*
G36*
G01X934603D02*
G03Y50511I277J-289D01*
G02X932661I-971J-1011D01*
G03Y51089I-277J289D01*
G02X934603I971J1011D01*
G37*
G36*
G01X897792D02*
G03Y50511I277J-289D01*
G02X895850I-971J-1011D01*
G03Y51089I-277J289D01*
G02X897792I971J1011D01*
G37*
G36*
G01X860981D02*
G03Y50511I277J-289D01*
G02X859039I-971J-1011D01*
G03Y51089I-277J289D01*
G02X860981I971J1011D01*
G37*
G36*
G01X824170D02*
G03Y50511I277J-289D01*
G02X822228I-971J-1011D01*
G03Y51089I-277J289D01*
G02X824170I971J1011D01*
G37*
G36*
G01X787359D02*
G03Y50511I277J-289D01*
G02X785417I-971J-1011D01*
G03Y51089I-277J289D01*
G02X787359I971J1011D01*
G37*
G36*
G01X576137D02*
G03Y50511I277J-289D01*
G02X574195I-971J-1011D01*
G03Y51089I-277J289D01*
G02X576137I971J1011D01*
G37*
G36*
G01X539326D02*
G03Y50511I277J-289D01*
G02X537384I-971J-1011D01*
G03Y51089I-277J289D01*
G02X539326I971J1011D01*
G37*
G36*
G01X502514D02*
G03Y50511I277J-289D01*
G02X500572I-971J-1011D01*
G03Y51089I-277J289D01*
G02X502514I971J1011D01*
G37*
G36*
G01X465703D02*
G03Y50511I277J-289D01*
G02X463761I-971J-1011D01*
G03Y51089I-277J289D01*
G02X465703I971J1011D01*
G37*
G36*
G01X284995D02*
G03Y50511I277J-289D01*
G02X283053I-971J-1011D01*
G03Y51089I-277J289D01*
G02X284995I971J1011D01*
G37*
G36*
G01X248184D02*
G03Y50511I277J-289D01*
G02X246242I-971J-1011D01*
G03Y51089I-277J289D01*
G02X248184I971J1011D01*
G37*
G36*
G01X211373D02*
G03Y50511I277J-289D01*
G02X209431I-971J-1011D01*
G03Y51089I-277J289D01*
G02X211373I971J1011D01*
G37*
G36*
G01X174562D02*
G03Y50511I277J-289D01*
G02X172620I-971J-1011D01*
G03Y51089I-277J289D01*
G02X174562I971J1011D01*
G37*
G36*
G01X137751D02*
G03Y50511I277J-289D01*
G02X135809I-971J-1011D01*
G03Y51089I-277J289D01*
G02X137751I971J1011D01*
G37*
G36*
G01X1744121Y46096D02*
G03X1743567I-277J-288D01*
G02Y48116I-973J1010D01*
G03X1744121I277J288D01*
G02Y46096I973J-1010D01*
G37*
G36*
G01X1363531Y44948D02*
G03X1363481Y44361I244J-316D01*
G02X1361591Y44523I-1033J-948D01*
G03X1361641Y45110I-244J316D01*
G02X1363531Y44948I1033J948D01*
G37*
G36*
G01X1309627Y40490D02*
G03X1309073I-277J-288D01*
G02Y42510I-973J1010D01*
G03X1309627I277J288D01*
G02Y40490I973J-1010D01*
G37*
G36*
G01X1324989Y40468D02*
G03X1324411I-289J-277D01*
G02X1322354Y42373I-1012J971D01*
G03Y42905I-298J266D01*
G02X1324392Y44829I1047J933D01*
G03X1324982Y44855I283J283D01*
G02X1327038Y42954I1076J-898D01*
G03X1327025Y42395I280J-286D01*
G02X1324989Y40468I-1025J-956D01*
G37*
G36*
G01X1721758Y38368D02*
X1717958D01*
G02Y41392I0J1512D01*
G01X1721759D01*
G02X1723270Y39890I-1J-1512D01*
G01Y39795D01*
X1723260Y39711D01*
G02X1721758Y38368I-1502J169D01*
G37*
G36*
G01X1703073Y38168D02*
X1699273D01*
G02Y41190I0J1511D01*
G01X1703074D01*
G02X1704584Y39689I-1J-1511D01*
G01Y39594D01*
X1704575Y39510D01*
G02X1703073Y38168I-1502J169D01*
G37*
G36*
G01X1740556Y37975D02*
Y37965D01*
X1736654Y38080D01*
X1736483Y38104D01*
G02X1736742Y41111I217J1496D01*
G01Y41121D01*
X1740642Y41006D01*
X1740650Y40998D01*
X1740723Y40992D01*
G02X1742110Y39496I-125J-1506D01*
G01Y39401D01*
X1742100Y39317D01*
G02X1740556Y37975I-1502J169D01*
G37*
G36*
G01X1731183Y37954D02*
X1727383D01*
G02Y40976I0J1511D01*
G01X1731183D01*
G02X1732694Y39475I0J-1511D01*
G01Y39380D01*
X1732685Y39296D01*
G02X1731183Y37954I-1502J169D01*
G37*
G36*
G01X1694098Y37950D02*
X1689098D01*
G02Y40974I0J1512D01*
G01X1694098D01*
G02X1695610Y39472I0J-1512D01*
G01Y39377D01*
X1695600Y39293D01*
G02X1694098Y37950I-1502J169D01*
G37*
G36*
G01X1684648D02*
X1679648D01*
G02Y40974I0J1512D01*
G01X1684649D01*
G02X1686160Y39472I-1J-1512D01*
G01Y39377D01*
X1686150Y39293D01*
G02X1684648Y37950I-1502J169D01*
G37*
G36*
G01X1675198D02*
X1670198D01*
G02Y40974I0J1512D01*
G01X1675199D01*
G02X1676710Y39472I-1J-1512D01*
G01Y39377D01*
X1676700Y39293D01*
G02X1675198Y37950I-1502J169D01*
G37*
G36*
G01X1646848D02*
X1641848D01*
G02Y40974I0J1512D01*
G01X1646849D01*
G02X1648360Y39472I-1J-1512D01*
G01Y39377D01*
X1648350Y39293D01*
G02X1646848Y37950I-1502J169D01*
G37*
G36*
G01X1712308Y37838D02*
X1708508D01*
G02Y40862I0J1512D01*
G01X1712309D01*
G02X1713820Y39360I-1J-1512D01*
G01Y39265D01*
X1713810Y39181D01*
G02X1712308Y37838I-1502J168D01*
G37*
G36*
G01X1368689Y36829D02*
G03X1368111I-289J-277D01*
G02Y38771I-1011J971D01*
G03X1368689I289J277D01*
G02Y36829I1011J-971D01*
G37*
G36*
G01X1660748Y40974D02*
X1665749D01*
G02X1667260Y39472I-1J-1512D01*
G01Y39377D01*
X1667250Y39293D01*
G02X1665748Y37950I-1502J169D01*
G01X1662563D01*
G03X1662204Y37375I1J-400D01*
G02X1659887Y37682I-1260J-614D01*
G03X1659829Y38262I-302J263D01*
G02X1660748Y40974I919J1200D01*
G37*
G36*
G01X1651297D02*
X1656299D01*
G02X1657810Y39472I-1J-1512D01*
G01Y39377D01*
X1657800Y39293D01*
G02X1656298Y37950I-1502J169D01*
G01X1652864D01*
G03X1652506Y37373I0J-400D01*
G02X1650282Y37764I-1256J-623D01*
G03X1650276Y38348I-276J289D01*
G02X1651297Y40974I1022J1114D01*
G37*
G36*
G01X1847503Y35441D02*
G03X1848058Y35439I279J287D01*
G02X1848051Y33420I969J-1013D01*
G03X1847496Y33422I-279J-287D01*
G02X1847503Y35441I-969J1013D01*
G37*
G36*
G01X655725Y30405D02*
G03X655151Y30327I-250J-312D01*
G02X652986Y30199I-1135J823D01*
G03X652415Y30215I-293J-272D01*
G02X650428Y30257I-973J1010D01*
G03X649856Y30264I-289J-276D01*
G02X649881Y32226I-989J994D01*
G03X650453Y32219I289J276D01*
G02X652472Y32176I989J-994D01*
G03X653043Y32160I293J272D01*
G02X654891Y32245I972J-1010D01*
G03X655465Y32323I250J312D01*
G02X655725Y30405I1135J-823D01*
G37*
G36*
G01X1225735Y32378D02*
G03X1225740Y31790I274J-292D01*
G02X1223839Y31771I-940J-1040D01*
G03X1223834Y32359I-274J292D01*
G02X1225735Y32378I940J1040D01*
G37*
G36*
G01X1188924D02*
G03X1188929Y31790I274J-292D01*
G02X1187028Y31771I-940J-1040D01*
G03X1187023Y32359I-274J292D01*
G02X1188924Y32378I940J1040D01*
G37*
G36*
G01X1152112D02*
G03X1152117Y31790I274J-292D01*
G02X1150216Y31771I-940J-1040D01*
G03X1150211Y32359I-274J292D01*
G02X1152112Y32378I940J1040D01*
G37*
G36*
G01X1115301D02*
G03X1115306Y31790I274J-292D01*
G02X1113405Y31771I-940J-1040D01*
G03X1113400Y32359I-274J292D01*
G02X1115301Y32378I940J1040D01*
G37*
G36*
G01X934593D02*
G03X934598Y31790I274J-292D01*
G02X932697Y31771I-940J-1040D01*
G03X932692Y32359I-274J292D01*
G02X934593Y32378I940J1040D01*
G37*
G36*
G01X897782D02*
G03X897787Y31790I274J-292D01*
G02X895886Y31771I-940J-1040D01*
G03X895881Y32359I-274J292D01*
G02X897782Y32378I940J1040D01*
G37*
G36*
G01X860971D02*
G03X860976Y31790I274J-292D01*
G02X859075Y31771I-940J-1040D01*
G03X859070Y32359I-274J292D01*
G02X860971Y32378I940J1040D01*
G37*
G36*
G01X824160D02*
G03X824165Y31790I274J-292D01*
G02X822264Y31771I-940J-1040D01*
G03X822259Y32359I-274J292D01*
G02X824160Y32378I940J1040D01*
G37*
G36*
G01X787349D02*
G03X787354Y31790I274J-292D01*
G02X785453Y31771I-940J-1040D01*
G03X785448Y32359I-274J292D01*
G02X787349Y32378I940J1040D01*
G37*
G36*
G01X576127D02*
G03X576132Y31790I274J-292D01*
G02X574231Y31771I-940J-1040D01*
G03X574226Y32359I-274J292D01*
G02X576127Y32378I940J1040D01*
G37*
G36*
G01X539316D02*
G03X539321Y31790I274J-292D01*
G02X537420Y31771I-940J-1040D01*
G03X537415Y32359I-274J292D01*
G02X539316Y32378I940J1040D01*
G37*
G36*
G01X502504D02*
G03X502509Y31790I274J-292D01*
G02X500608Y31771I-940J-1040D01*
G03X500603Y32359I-274J292D01*
G02X502504Y32378I940J1040D01*
G37*
G36*
G01X465693D02*
G03X465698Y31790I274J-292D01*
G02X463797Y31771I-940J-1040D01*
G03X463792Y32359I-274J292D01*
G02X465693Y32378I940J1040D01*
G37*
G36*
G01X284985D02*
G03X284990Y31790I274J-292D01*
G02X283089Y31771I-940J-1040D01*
G03X283084Y32359I-274J292D01*
G02X284985Y32378I940J1040D01*
G37*
G36*
G01X248174D02*
G03X248179Y31790I274J-292D01*
G02X246278Y31771I-940J-1040D01*
G03X246273Y32359I-274J292D01*
G02X248174Y32378I940J1040D01*
G37*
G36*
G01X211363D02*
G03X211368Y31790I274J-292D01*
G02X209467Y31771I-940J-1040D01*
G03X209462Y32359I-274J292D01*
G02X211363Y32378I940J1040D01*
G37*
G36*
G01X174552D02*
G03X174557Y31790I274J-292D01*
G02X172656Y31771I-940J-1040D01*
G03X172651Y32359I-274J292D01*
G02X174552Y32378I940J1040D01*
G37*
G36*
G01X137741D02*
G03X137746Y31790I274J-292D01*
G02X135845Y31771I-940J-1040D01*
G03X135840Y32359I-274J292D01*
G02X137741Y32378I940J1040D01*
G37*
G36*
G01X1311586Y30712D02*
G03X1311131Y30400I-64J-395D01*
G02X1309983Y32075I-1371J291D01*
G03X1310438Y32387I64J395D01*
G02X1313179Y32393I1371J-292D01*
G03X1313653Y32086I391J84D01*
G02X1314428Y32029I289J-1372D01*
G03X1314952Y32295I139J375D01*
G02X1317220Y32969I1348J-384D01*
G03X1317752Y32976I262J302D01*
G02X1319816Y32791I948J-1033D01*
G03X1320427Y32760I319J242D01*
G02X1320336Y30955I1025J-956D01*
G03X1319725Y30986I-319J-242D01*
G02X1317780Y30885I-1025J957D01*
G03X1317248Y30878I-262J-302D01*
G02X1315814Y30596I-948J1033D01*
G03X1315290Y30330I-139J-375D01*
G02X1312572Y30417I-1348J384D01*
G03X1312098Y30724I-391J-84D01*
G02X1311586Y30712I-288J1372D01*
G37*
G36*
G01X1230841Y32134D02*
G03Y31555I276J-289D01*
G02X1228907I-967J-1015D01*
G03Y32134I-276J289D01*
G02X1230841I967J1015D01*
G37*
G36*
G01X1194030D02*
G03Y31555I276J-289D01*
G02X1192096I-967J-1015D01*
G03Y32134I-276J289D01*
G02X1194030I967J1015D01*
G37*
G36*
G01X1157218D02*
G03Y31555I276J-289D01*
G02X1155284I-967J-1015D01*
G03Y32134I-276J289D01*
G02X1157218I967J1015D01*
G37*
G36*
G01X1120407D02*
G03Y31555I276J-289D01*
G02X1118473I-967J-1015D01*
G03Y32134I-276J289D01*
G02X1120407I967J1015D01*
G37*
G36*
G01X939699D02*
G03Y31555I276J-289D01*
G02X937765I-967J-1015D01*
G03Y32134I-276J289D01*
G02X939699I967J1015D01*
G37*
G36*
G01X902888D02*
G03Y31555I276J-289D01*
G02X900954I-967J-1015D01*
G03Y32134I-276J289D01*
G02X902888I967J1015D01*
G37*
G36*
G01X866077D02*
G03Y31555I276J-289D01*
G02X864143I-967J-1015D01*
G03Y32134I-276J289D01*
G02X866077I967J1015D01*
G37*
G36*
G01X829266D02*
G03Y31555I276J-289D01*
G02X827332I-967J-1015D01*
G03Y32134I-276J289D01*
G02X829266I967J1015D01*
G37*
G36*
G01X792455D02*
G03Y31555I276J-289D01*
G02X790521I-967J-1015D01*
G03Y32134I-276J289D01*
G02X792455I967J1015D01*
G37*
G36*
G01X581233D02*
G03Y31555I276J-289D01*
G02X579299I-967J-1015D01*
G03Y32134I-276J289D01*
G02X581233I967J1015D01*
G37*
G36*
G01X544422D02*
G03Y31555I276J-289D01*
G02X542488I-967J-1015D01*
G03Y32134I-276J289D01*
G02X544422I967J1015D01*
G37*
G36*
G01X507610D02*
G03Y31555I276J-289D01*
G02X505676I-967J-1015D01*
G03Y32134I-276J289D01*
G02X507610I967J1015D01*
G37*
G36*
G01X470799D02*
G03Y31555I276J-289D01*
G02X468865I-967J-1015D01*
G03Y32134I-276J289D01*
G02X470799I967J1015D01*
G37*
G36*
G01X290091D02*
G03Y31555I276J-289D01*
G02X288157I-967J-1015D01*
G03Y32134I-276J289D01*
G02X290091I967J1015D01*
G37*
G36*
G01X253280D02*
G03Y31555I276J-289D01*
G02X251346I-967J-1015D01*
G03Y32134I-276J289D01*
G02X253280I967J1015D01*
G37*
G36*
G01X216469D02*
G03Y31555I276J-289D01*
G02X214535I-967J-1015D01*
G03Y32134I-276J289D01*
G02X216469I967J1015D01*
G37*
G36*
G01X179658D02*
G03Y31555I276J-289D01*
G02X177724I-967J-1015D01*
G03Y32134I-276J289D01*
G02X179658I967J1015D01*
G37*
G36*
G01X142847D02*
G03Y31555I276J-289D01*
G02X140913I-967J-1015D01*
G03Y32134I-276J289D01*
G02X142847I967J1015D01*
G37*
G36*
G01X1758406Y34262D02*
Y30367D01*
X1758397Y30283D01*
G02X1755384Y30452I-1502J169D01*
G01Y34252D01*
G02X1758406Y34262I1511J0D01*
G37*
G36*
G01X683076Y27208D02*
G03X682476I-300J-265D01*
G02Y29066I-1050J929D01*
G03X683076I300J265D01*
G02Y27208I1050J-929D01*
G37*
G36*
G01X1523780Y27567D02*
G03X1523280Y27252I-106J-386D01*
G02X1522274Y28851I-1380J248D01*
G03X1522774Y29166I106J386D01*
G02X1523780Y27567I1380J-248D01*
G37*
G36*
G01X1509078Y30563D02*
G03X1508559Y30154I-120J-381D01*
G02X1507596Y32459I-3893J-273D01*
G03X1508253Y32540I301J264D01*
G02X1509078Y30563I1247J-640D01*
G37*
G36*
G01X1808288Y27703D02*
G03X1808887Y27629I332J224D01*
G02X1808661Y25800I935J-1044D01*
G03X1808062Y25874I-332J-224D01*
G02X1808288Y27703I-935J1044D01*
G37*
G36*
G01X1380536Y27426D02*
G03X1381078Y27181I381J121D01*
G02X1380306Y25472I564J-1284D01*
G03X1379764Y25717I-381J-121D01*
G02X1380536Y27426I-564J1284D01*
G37*
G36*
G01X14801Y25749D02*
G03X15397Y25723I310J253D01*
G02X15315Y23856I1003J-979D01*
G03X14719Y23882I-310J-253D01*
G02X14801Y25749I-1003J979D01*
G37*
G36*
G01X1767069Y22498D02*
X1763360D01*
G02Y25522I0J1512D01*
G01X1767069D01*
G02X1768580Y24020I-1J-1512D01*
G01Y23925D01*
X1768571Y23841D01*
G02X1767069Y22498I-1502J169D01*
G37*
G36*
G01X1550861Y22846D02*
G03X1550307I-277J-288D01*
G02Y24866I-973J1010D01*
G03X1550861I277J288D01*
G02X1552845Y24827I973J-1010D01*
G03X1553423I289J277D01*
G02Y22885I1011J-971D01*
G03X1552845I-289J-277D01*
G02X1550861Y22846I-1011J971D01*
G37*
G36*
G01X1748152Y21686D02*
X1743152D01*
G02Y24708I0J1511D01*
G01X1748153D01*
G02X1749664Y23207I0J-1512D01*
G01Y23112D01*
X1749654Y23028D01*
G02X1748152Y21686I-1502J169D01*
G37*
G36*
G01X655327Y21790D02*
G03X654773I-277J-288D01*
G02Y23810I-973J1010D01*
G03X655327I277J288D01*
G02Y21790I973J-1010D01*
G37*
G36*
G01X1738168Y20800D02*
X1733168D01*
G02Y23824I0J1512D01*
G01X1738169D01*
G02X1739680Y22322I-1J-1512D01*
G01Y22227D01*
X1739670Y22143D01*
G02X1738168Y20800I-1502J169D01*
G37*
G36*
G01X1532430Y23307D02*
G02Y24629I3693J661D01*
G02Y23307I3693J-661D01*
G37*
G36*
G01X1824343Y22637D02*
G03X1824913Y22612I297J267D01*
G02X1824827Y20650I957J-1025D01*
G03X1824257Y20675I-297J-267D01*
G02X1824343Y22637I-957J1025D01*
G37*
G36*
G01X691427Y19790D02*
G03X690873I-277J-288D01*
G02Y21810I-973J1010D01*
G03X691427I277J288D01*
G02Y19790I973J-1010D01*
G37*
G36*
G01X1760709Y18534D02*
X1757009Y18496D01*
G02X1756976Y21518I-16J1511D01*
G01X1760677Y21556D01*
G02X1762198Y20189I16J-1511D01*
G01X1762204Y20130D01*
X1762205Y20071D01*
G02Y20019I-1512J-26D01*
G01X1762204Y20017D01*
Y20007D01*
G02X1760709Y18534I-1511J38D01*
G37*
G36*
G01X373192Y18898D02*
G03X373437Y19395I-136J376D01*
G02X375251Y18501I1336J424D01*
G03X375006Y18004I136J-376D01*
G02X373192Y18898I-1336J-424D01*
G37*
G36*
G01X1013899Y16081D02*
G03X1013311Y16074I-291J-275D01*
G02X1013290Y17975I-1041J939D01*
G03X1013878Y17982I291J275D01*
G02X1015930Y18013I1040J-940D01*
G03X1016508I289J277D01*
G02Y16071I1011J-971D01*
G03X1015930I-289J-277D01*
G02X1013899Y16081I-1011J971D01*
G37*
G36*
G01X364291D02*
G03X363703Y16074I-291J-275D01*
G02X363682Y17975I-1041J939D01*
G03X364270Y17982I291J275D01*
G02X366322Y18013I1040J-940D01*
G03X366900I289J277D01*
G02Y16071I1011J-971D01*
G03X366322I-289J-277D01*
G02X364291Y16081I-1011J971D01*
G37*
G36*
G01X1047400Y15762D02*
G03X1046927Y15366I-73J-393D01*
G02X1045845Y16722I-1402J-9D01*
G03X1046336Y17095I91J389D01*
G02X1047400Y15762I1301J-53D01*
G37*
G36*
G01X1375911Y14137D02*
G03X1375375Y14134I-266J-299D01*
G02X1373356Y14269I-945J1036D01*
G03X1372795Y14321I-307J-256D01*
G02X1370854Y16334I-895J1079D01*
G03Y16866I-298J266D01*
G02X1370874Y18755I1046J934D01*
G03X1370885Y19288I-293J273D01*
G02X1370907Y21136I1065J911D01*
G03X1370905Y21673I-298J267D01*
G02X1372984Y21681I1036J944D01*
G03X1372986Y21144I298J-267D01*
G02X1372976Y19245I-1036J-944D01*
G03X1372965Y18712I293J-273D01*
G02X1372946Y16866I-1065J-912D01*
G03Y16334I298J-266D01*
G02X1372975Y16301I-1039J-942D01*
G03X1373536Y16249I307J256D01*
G02X1375362Y16218I895J-1079D01*
G03X1375898Y16221I266J299D01*
G02X1375911Y14137I944J-1036D01*
G37*
G36*
G01X1577048Y10994D02*
X1573048D01*
G02Y14018I0J1512D01*
G01X1577049D01*
G02X1578560Y12516I-1J-1512D01*
G01Y12421D01*
X1578550Y12337D01*
G02X1577048Y10994I-1502J169D01*
G37*
G36*
G01X1567498D02*
X1563498D01*
G02Y14018I0J1512D01*
G01X1567499D01*
G02X1569010Y12516I-1J-1512D01*
G01Y12421D01*
X1569000Y12337D01*
G02X1567498Y10994I-1502J169D01*
G37*
G36*
G01X1548698D02*
X1544698D01*
G02Y14018I0J1512D01*
G01X1548699D01*
G02X1550210Y12516I-1J-1512D01*
G01Y12421D01*
X1550200Y12337D01*
G02X1548698Y10994I-1502J169D01*
G37*
G36*
G01X1554148Y13818D02*
X1558148D01*
G02X1559660Y12316I0J-1512D01*
G01Y12221D01*
X1559650Y12137D01*
G02X1558148Y10794I-1502J169D01*
G01X1554148D01*
G02Y13818I0J1512D01*
G37*
G36*
G01X1230845Y13503D02*
G03Y12925I277J-289D01*
G02X1228903I-971J-1011D01*
G03Y13503I-277J289D01*
G02X1230845I971J1011D01*
G37*
G36*
G01X1194034D02*
G03Y12925I277J-289D01*
G02X1192092I-971J-1011D01*
G03Y13503I-277J289D01*
G02X1194034I971J1011D01*
G37*
G36*
G01X1157223D02*
G03Y12925I277J-289D01*
G02X1155281I-971J-1011D01*
G03Y13503I-277J289D01*
G02X1157223I971J1011D01*
G37*
G36*
G01X1120411D02*
G03Y12925I277J-289D01*
G02X1118469I-971J-1011D01*
G03Y13503I-277J289D01*
G02X1120411I971J1011D01*
G37*
G36*
G01X939703D02*
G03Y12925I277J-289D01*
G02X937761I-971J-1011D01*
G03Y13503I-277J289D01*
G02X939703I971J1011D01*
G37*
G36*
G01X902892D02*
G03Y12925I277J-289D01*
G02X900950I-971J-1011D01*
G03Y13503I-277J289D01*
G02X902892I971J1011D01*
G37*
G36*
G01X866081D02*
G03Y12925I277J-289D01*
G02X864139I-971J-1011D01*
G03Y13503I-277J289D01*
G02X866081I971J1011D01*
G37*
G36*
G01X829270D02*
G03Y12925I277J-289D01*
G02X827328I-971J-1011D01*
G03Y13503I-277J289D01*
G02X829270I971J1011D01*
G37*
G36*
G01X792459D02*
G03Y12925I277J-289D01*
G02X790517I-971J-1011D01*
G03Y13503I-277J289D01*
G02X792459I971J1011D01*
G37*
G36*
G01X581237D02*
G03Y12925I277J-289D01*
G02X579295I-971J-1011D01*
G03Y13503I-277J289D01*
G02X581237I971J1011D01*
G37*
G36*
G01X544426D02*
G03Y12925I277J-289D01*
G02X542484I-971J-1011D01*
G03Y13503I-277J289D01*
G02X544426I971J1011D01*
G37*
G36*
G01X507615D02*
G03Y12925I277J-289D01*
G02X505673I-971J-1011D01*
G03Y13503I-277J289D01*
G02X507615I971J1011D01*
G37*
G36*
G01X470803D02*
G03Y12925I277J-289D01*
G02X468861I-971J-1011D01*
G03Y13503I-277J289D01*
G02X470803I971J1011D01*
G37*
G36*
G01X290095D02*
G03Y12925I277J-289D01*
G02X288153I-971J-1011D01*
G03Y13503I-277J289D01*
G02X290095I971J1011D01*
G37*
G36*
G01X253284D02*
G03Y12925I277J-289D01*
G02X251342I-971J-1011D01*
G03Y13503I-277J289D01*
G02X253284I971J1011D01*
G37*
G36*
G01X216473D02*
G03Y12925I277J-289D01*
G02X214531I-971J-1011D01*
G03Y13503I-277J289D01*
G02X216473I971J1011D01*
G37*
G36*
G01X179662D02*
G03Y12925I277J-289D01*
G02X177720I-971J-1011D01*
G03Y13503I-277J289D01*
G02X179662I971J1011D01*
G37*
G36*
G01X142851D02*
G03Y12925I277J-289D01*
G02X140909I-971J-1011D01*
G03Y13503I-277J289D01*
G02X142851I971J1011D01*
G37*
G36*
G01X1225745Y13289D02*
G03Y12711I277J-289D01*
G02X1223803I-971J-1011D01*
G03Y13289I-277J289D01*
G02X1225745I971J1011D01*
G37*
G36*
G01X1188934D02*
G03Y12711I277J-289D01*
G02X1186992I-971J-1011D01*
G03Y13289I-277J289D01*
G02X1188934I971J1011D01*
G37*
G36*
G01X1152123D02*
G03Y12711I277J-289D01*
G02X1150181I-971J-1011D01*
G03Y13289I-277J289D01*
G02X1152123I971J1011D01*
G37*
G36*
G01X1115311D02*
G03Y12711I277J-289D01*
G02X1113369I-971J-1011D01*
G03Y13289I-277J289D01*
G02X1115311I971J1011D01*
G37*
G36*
G01X934603D02*
G03Y12711I277J-289D01*
G02X932661I-971J-1011D01*
G03Y13289I-277J289D01*
G02X934603I971J1011D01*
G37*
G36*
G01X897792D02*
G03Y12711I277J-289D01*
G02X895850I-971J-1011D01*
G03Y13289I-277J289D01*
G02X897792I971J1011D01*
G37*
G36*
G01X860981D02*
G03Y12711I277J-289D01*
G02X859039I-971J-1011D01*
G03Y13289I-277J289D01*
G02X860981I971J1011D01*
G37*
G36*
G01X824170D02*
G03Y12711I277J-289D01*
G02X822228I-971J-1011D01*
G03Y13289I-277J289D01*
G02X824170I971J1011D01*
G37*
G36*
G01X787359D02*
G03Y12711I277J-289D01*
G02X785417I-971J-1011D01*
G03Y13289I-277J289D01*
G02X787359I971J1011D01*
G37*
G36*
G01X576137D02*
G03Y12711I277J-289D01*
G02X574195I-971J-1011D01*
G03Y13289I-277J289D01*
G02X576137I971J1011D01*
G37*
G36*
G01X539326D02*
G03Y12711I277J-289D01*
G02X537384I-971J-1011D01*
G03Y13289I-277J289D01*
G02X539326I971J1011D01*
G37*
G36*
G01X502515D02*
G03Y12711I277J-289D01*
G02X500573I-971J-1011D01*
G03Y13289I-277J289D01*
G02X502515I971J1011D01*
G37*
G36*
G01X465703D02*
G03Y12711I277J-289D01*
G02X463761I-971J-1011D01*
G03Y13289I-277J289D01*
G02X465703I971J1011D01*
G37*
G36*
G01X284995D02*
G03Y12711I277J-289D01*
G02X283053I-971J-1011D01*
G03Y13289I-277J289D01*
G02X284995I971J1011D01*
G37*
G36*
G01X248184D02*
G03Y12711I277J-289D01*
G02X246242I-971J-1011D01*
G03Y13289I-277J289D01*
G02X248184I971J1011D01*
G37*
G36*
G01X211373D02*
G03Y12711I277J-289D01*
G02X209431I-971J-1011D01*
G03Y13289I-277J289D01*
G02X211373I971J1011D01*
G37*
G36*
G01X174562D02*
G03Y12711I277J-289D01*
G02X172620I-971J-1011D01*
G03Y13289I-277J289D01*
G02X174562I971J1011D01*
G37*
G36*
G01X137751D02*
G03Y12711I277J-289D01*
G02X135809I-971J-1011D01*
G03Y13289I-277J289D01*
G02X137751I971J1011D01*
G37*
G36*
G01X1484135Y10052D02*
X1479135D01*
G02Y13074I0J1511D01*
G01X1484136D01*
G02X1485646Y11573I-1J-1511D01*
G01Y11478D01*
X1485637Y11394D01*
G02X1484135Y10052I-1502J169D01*
G37*
G36*
G01X1465237D02*
X1460237D01*
G02Y13074I0J1511D01*
G01X1465238D01*
G02X1466748Y11573I-1J-1511D01*
G01Y11478D01*
X1466739Y11394D01*
G02X1465237Y10052I-1502J169D01*
G37*
G36*
G01X1441340Y13074D02*
X1446341D01*
G02X1447852Y11573I0J-1512D01*
G01Y11478D01*
X1447842Y11394D01*
G02X1446340Y10052I-1502J169D01*
G01X1441340D01*
G02Y13074I1J1511D01*
G37*
G36*
G01X1427442Y10052D02*
X1422442D01*
G02Y13074I0J1511D01*
G01X1427443D01*
G02X1428954Y11573I0J-1512D01*
G01Y11478D01*
X1428944Y11394D01*
G02X1427442Y10052I-1502J169D01*
G37*
G36*
G01X1728678Y9870D02*
X1723678D01*
G02Y12892I0J1511D01*
G01X1728679D01*
G02X1730190Y11391I0J-1512D01*
G01Y11296D01*
X1730180Y11212D01*
G02X1728678Y9870I-1502J169D01*
G37*
G36*
G01X1681428D02*
X1676428D01*
G02Y12892I0J1511D01*
G01X1681429D01*
G02X1682940Y11391I0J-1512D01*
G01Y11296D01*
X1682930Y11212D01*
G02X1681428Y9870I-1502J169D01*
G37*
G36*
G01X1605898Y9844D02*
X1600898D01*
G02Y12866I0J1511D01*
G01X1605899D01*
G02X1607410Y11365I0J-1512D01*
G01Y11270D01*
X1607400Y11186D01*
G02X1605898Y9844I-1502J169D01*
G37*
G36*
G01X1586998D02*
X1581998D01*
G02Y12866I0J1511D01*
G01X1586999D01*
G02X1588510Y11365I0J-1512D01*
G01Y11270D01*
X1588500Y11186D01*
G02X1586998Y9844I-1502J169D01*
G37*
G36*
G01X1700200Y9806D02*
X1695200D01*
G02Y12828I0J1511D01*
G01X1700201D01*
G02X1701712Y11327I0J-1512D01*
G01Y11232D01*
X1701702Y11148D01*
G02X1700200Y9806I-1502J170D01*
G37*
G36*
G01X1709771Y9750D02*
X1704771D01*
G02Y12772I0J1511D01*
G01X1709772D01*
G02X1711282Y11271I-1J-1511D01*
G01Y11176D01*
X1711273Y11092D01*
G02X1709771Y9750I-1502J169D01*
G37*
G36*
G01X1719297Y9668D02*
X1714297D01*
G02Y12692I0J1512D01*
G01X1719298D01*
G02X1720808Y11190I-1J-1512D01*
G01Y11095D01*
X1720799Y11011D01*
G02X1719297Y9668I-1502J169D01*
G37*
G36*
G01X1643865Y9594D02*
X1638865D01*
G02Y12616I0J1511D01*
G01X1643866D01*
G02X1645376Y11115I-1J-1511D01*
G01Y11020D01*
X1645367Y10936D01*
G02X1643865Y9594I-1502J169D01*
G37*
G36*
G01X1690948Y9214D02*
X1685948D01*
G02Y12236I0J1511D01*
G01X1690949D01*
G02X1692460Y10735I0J-1512D01*
G01Y10640D01*
X1692450Y10556D01*
G02X1690948Y9214I-1502J169D01*
G37*
G36*
G01X1302990Y9175D02*
G03X1302368I-311J-252D01*
G02X1300259Y11020I-1089J883D01*
G03X1300242Y11587I-291J275D01*
G02X1300225Y13618I958J1024D01*
G03Y14192I-278J287D01*
G02X1302289Y16083I976J1007D01*
G03X1302911I311J252D01*
G02X1305089I1089J-883D01*
G03X1305711I311J252D01*
G02X1307775Y14192I1088J-884D01*
G03Y13618I278J-287D01*
G02X1307820Y11648I-975J-1008D01*
G03X1307837Y11081I291J-275D01*
G02X1305790Y9175I-957J-1024D01*
G03X1305168I-311J-252D01*
G02X1302990I-1089J883D01*
G37*
G36*
G01X1663884Y10164D02*
Y10069D01*
X1663875Y9985D01*
G02X1662342Y8643I-1502J169D01*
G01X1657338Y8747D01*
G02X1657400Y11769I31J1511D01*
G01X1662403Y11665D01*
G02X1663884Y10164I-30J-1511D01*
G37*
G36*
G01X1401627Y8990D02*
G03X1401073I-277J-288D01*
G02Y11010I-973J1010D01*
G03X1401627I277J288D01*
G02X1403573I973J-1010D01*
G03X1404127I277J288D01*
G02Y8990I973J-1010D01*
G03X1403573I-277J-288D01*
G02X1401627I-973J1010D01*
G37*
G36*
G01X665011Y9117D02*
G03X664389I-311J-252D01*
G02Y10883I-1089J883D01*
G03X665011I311J252D01*
G02Y9117I1089J-883D01*
G37*
G36*
G01X82642Y10684D02*
G03X82629Y10122I278J-288D01*
G02X80364Y8516I-1019J-963D01*
G03X79806Y8677I-355J-184D01*
G02X78085Y10857I-710J1209D01*
G03X78089Y11406I-289J277D01*
G02X78229Y13446I1027J954D01*
G03X78285Y14009I-253J309D01*
G02X80652Y15467I1087J886D01*
G03X81238Y15297I365J164D01*
G02X82894Y13038I775J-1168D01*
G03X82817Y12497I251J-312D01*
G02X82642Y10684I-1148J-804D01*
G37*
G36*
G01X1259473Y10130D02*
G03X1260036Y10118I288J278D01*
G02X1259991Y8127I964J-1018D01*
G03X1259428Y8139I-288J-278D01*
G02X1259473Y10130I-964J1018D01*
G37*
G36*
G01X1754065Y10273D02*
G03X1754640Y10183I330J226D01*
G02X1754343Y8284I860J-1107D01*
G03X1753768Y8374I-330J-226D01*
G02X1754065Y10273I-860J1107D01*
G37*
G36*
G01X1591848Y12918D02*
X1595849D01*
G02X1597360Y11416I-1J-1512D01*
G01Y11321D01*
X1597350Y11237D01*
G02X1595848Y9894I-1502J169D01*
G01X1593957D01*
G03X1593623Y9274I0J-400D01*
G02X1591378Y9402I-1170J-772D01*
G03X1591234Y10025I-306J257D01*
G02X1591848Y12918I614J1381D01*
G37*
G36*
G01X1436025Y6244D02*
X1431025D01*
G02Y9268I0J1512D01*
G01X1436026D01*
G02X1437536Y7766I-1J-1512D01*
G01Y7671D01*
X1437527Y7587D01*
G02X1436025Y6244I-1502J169D01*
G37*
G36*
G01X1493770Y5398D02*
X1488770D01*
G02Y8420I0J1511D01*
G01X1493771D01*
G02X1495282Y6919I0J-1512D01*
G01Y6824D01*
X1495272Y6740D01*
G02X1493770Y5398I-1502J169D01*
G37*
G36*
G01X1634148Y5314D02*
X1629148D01*
G02Y8336I0J1511D01*
G01X1634149D01*
G02X1635660Y6835I0J-1512D01*
G01Y6740D01*
X1635650Y6656D01*
G02X1634148Y5314I-1502J169D01*
G37*
G36*
G01X1653748Y4814D02*
X1648748D01*
G02Y7836I0J1511D01*
G01X1653749D01*
G02X1655260Y6335I0J-1512D01*
G01Y6240D01*
X1655250Y6156D01*
G02X1653748Y4814I-1502J169D01*
G37*
G36*
G01X1671979Y4724D02*
X1666979D01*
G02Y7748I0J1512D01*
G01X1671979D01*
G02X1673490Y6246I-1J-1512D01*
G01Y6151D01*
X1673481Y6067D01*
G02X1671979Y4724I-1502J168D01*
G37*
G36*
G01X1368378Y4805D02*
G03X1367800I-289J-277D01*
G02Y6747I-1011J971D01*
G03X1368378I289J277D01*
G02Y4805I1011J-971D01*
G37*
G36*
G01X1474388Y4078D02*
X1469388D01*
G02Y7100I0J1511D01*
G01X1474389D01*
G02X1475900Y5599I0J-1512D01*
G01Y5504D01*
X1475890Y5420D01*
G02X1474388Y4078I-1502J169D01*
G37*
G36*
G01X1454991D02*
X1449991D01*
G02Y7100I0J1511D01*
G01X1454992D01*
G02X1456502Y5599I-1J-1511D01*
G01Y5504D01*
X1456493Y5420D01*
G02X1454991Y4078I-1502J169D01*
G37*
G36*
G01X1614833Y3914D02*
X1609833D01*
G02Y6936I0J1511D01*
G01X1614834D01*
G02X1616344Y5435I-1J-1511D01*
G01Y5340D01*
X1616335Y5256D01*
G02X1614833Y3914I-1502J169D01*
G37*
G36*
G01X665442Y3406D02*
G03X664944Y3216I-143J-374D01*
G02X664199Y5171I-1245J645D01*
G03X664697Y5361I143J374D01*
G02X665442Y3406I1245J-645D01*
G37*
G36*
G01X115022Y5064D02*
G03X115000Y4483I263J-301D01*
G02X113078Y4556I-1000J-983D01*
G03X113100Y5137I-263J301D01*
G02X115022Y5064I1000J983D01*
G37*
G36*
G01X1381205Y4584D02*
G03X1381223Y3999I282J-284D01*
G02X1379314Y3941I-923J-1055D01*
G03X1379296Y4526I-282J284D01*
G02X1381205Y4584I923J1055D01*
G37*
G36*
G01X1328965Y4380D02*
G03X1329273Y3898I389J-91D01*
G02X1327952Y1579I-286J-1373D01*
G03X1327378Y1596I-295J-270D01*
G02X1325311Y1717I-978J1004D01*
G03X1324689I-311J-252D01*
G02X1322511I-1089J883D01*
G03X1321889I-311J-252D01*
G02X1319672Y1768I-1089J883D01*
G03X1319028I-322J-238D01*
G02X1316783Y1753I-1128J832D01*
G03X1316140Y1745I-319J-242D01*
G02X1313907Y1694I-1136J822D01*
G03X1313306Y1724I-314J-248D01*
G02X1311211Y1817I-1006J976D01*
G03X1310589I-311J-252D01*
G02X1308411I-1089J883D01*
G03X1307789I-311J-252D01*
G02X1305611I-1089J883D01*
G03X1304989I-311J-252D01*
G02X1302811I-1089J883D01*
G03X1302189I-311J-252D01*
G02X1300664Y4033I-1089J883D01*
G03X1300931Y4499I-124J380D01*
G02X1303389Y5683I1369J301D01*
G03X1304011I311J252D01*
G02X1306189I1089J-883D01*
G03X1306811I311J252D01*
G02X1308989I1089J-883D01*
G03X1309611I311J252D01*
G02X1311789I1089J-883D01*
G03X1312411I311J252D01*
G02X1314621Y5642I1089J-883D01*
G03X1315242Y5620I319J241D01*
G02X1317428Y5532I1058J-920D01*
G03X1318072I322J238D01*
G02X1320289Y5583I1128J-832D01*
G03X1320911I311J252D01*
G02X1323089I1089J-883D01*
G03X1323711I311J252D01*
G02X1325889I1089J-883D01*
G03X1326511I311J252D01*
G02X1328965Y4380I1089J-883D01*
G37*
G36*
G01X1825803Y2785D02*
G03X1825972Y2243I354J-187D01*
G02X1824085Y1656I-648J-1243D01*
G03X1823916Y2198I-354J187D01*
G02X1825803Y2785I648J1243D01*
G37*
G36*
G01X752985Y1288D02*
G03X753584Y1266I309J254D01*
G02X753515Y-588I1016J-966D01*
G03X752916Y-566I-309J-254D01*
G02X752985Y1288I-1016J966D01*
G37*
G36*
G01X1600129Y-1610D02*
G03X1599575I-277J-288D01*
G02Y410I-973J1010D01*
G03X1600129I277J288D01*
G02Y-1610I973J-1010D01*
G37*
G36*
G01X63074Y-533D02*
G03X63194Y-1141I308J-255D01*
G02X61456Y-1484I-659J-1238D01*
G03X61336Y-876I-308J255D01*
G02X63074Y-533I659J1238D01*
G37*
G36*
G01X1381410Y-3782D02*
G03X1381885Y-4168I400J7D01*
G02X1380749Y-5568I266J-1377D01*
G03X1380274Y-5182I-400J-7D01*
G02X1381410Y-3782I-266J1377D01*
G37*
G36*
G01X718771Y-5838D02*
G03X718316Y-6193I-57J-396D01*
G02X717125Y-4661I-1395J145D01*
G03X717580Y-4306I57J396D01*
G02X718771Y-5838I1395J-145D01*
G37*
G36*
G01X1225735Y-5422D02*
G03X1225740Y-6010I274J-292D01*
G02X1223839Y-6029I-940J-1040D01*
G03X1223834Y-5441I-274J292D01*
G02X1225735Y-5422I940J1040D01*
G37*
G36*
G01X1188924D02*
G03X1188929Y-6010I274J-292D01*
G02X1187028Y-6029I-940J-1040D01*
G03X1187023Y-5441I-274J292D01*
G02X1188924Y-5422I940J1040D01*
G37*
G36*
G01X1152113D02*
G03X1152118Y-6010I274J-292D01*
G02X1150217Y-6029I-940J-1040D01*
G03X1150212Y-5441I-274J292D01*
G02X1152113Y-5422I940J1040D01*
G37*
G36*
G01X1115301D02*
G03X1115306Y-6010I274J-292D01*
G02X1113405Y-6029I-940J-1040D01*
G03X1113400Y-5441I-274J292D01*
G02X1115301Y-5422I940J1040D01*
G37*
G36*
G01X934593D02*
G03X934598Y-6010I274J-292D01*
G02X932697Y-6029I-940J-1040D01*
G03X932692Y-5441I-274J292D01*
G02X934593Y-5422I940J1040D01*
G37*
G36*
G01X897782D02*
G03X897787Y-6010I274J-292D01*
G02X895886Y-6029I-940J-1040D01*
G03X895881Y-5441I-274J292D01*
G02X897782Y-5422I940J1040D01*
G37*
G36*
G01X860971D02*
G03X860976Y-6010I274J-292D01*
G02X859075Y-6029I-940J-1040D01*
G03X859070Y-5441I-274J292D01*
G02X860971Y-5422I940J1040D01*
G37*
G36*
G01X824160D02*
G03X824165Y-6010I274J-292D01*
G02X822264Y-6029I-940J-1040D01*
G03X822259Y-5441I-274J292D01*
G02X824160Y-5422I940J1040D01*
G37*
G36*
G01X787349D02*
G03X787354Y-6010I274J-292D01*
G02X785453Y-6029I-940J-1040D01*
G03X785448Y-5441I-274J292D01*
G02X787349Y-5422I940J1040D01*
G37*
G36*
G01X576127D02*
G03X576132Y-6010I274J-292D01*
G02X574231Y-6029I-940J-1040D01*
G03X574226Y-5441I-274J292D01*
G02X576127Y-5422I940J1040D01*
G37*
G36*
G01X539316D02*
G03X539321Y-6010I274J-292D01*
G02X537420Y-6029I-940J-1040D01*
G03X537415Y-5441I-274J292D01*
G02X539316Y-5422I940J1040D01*
G37*
G36*
G01X502505D02*
G03X502510Y-6010I274J-292D01*
G02X500609Y-6029I-940J-1040D01*
G03X500604Y-5441I-274J292D01*
G02X502505Y-5422I940J1040D01*
G37*
G36*
G01X465693D02*
G03X465698Y-6010I274J-292D01*
G02X463797Y-6029I-940J-1040D01*
G03X463792Y-5441I-274J292D01*
G02X465693Y-5422I940J1040D01*
G37*
G36*
G01X284985D02*
G03X284990Y-6010I274J-292D01*
G02X283089Y-6029I-940J-1040D01*
G03X283084Y-5441I-274J292D01*
G02X284985Y-5422I940J1040D01*
G37*
G36*
G01X248174D02*
G03X248179Y-6010I274J-292D01*
G02X246278Y-6029I-940J-1040D01*
G03X246273Y-5441I-274J292D01*
G02X248174Y-5422I940J1040D01*
G37*
G36*
G01X211363D02*
G03X211368Y-6010I274J-292D01*
G02X209467Y-6029I-940J-1040D01*
G03X209462Y-5441I-274J292D01*
G02X211363Y-5422I940J1040D01*
G37*
G36*
G01X174552D02*
G03X174557Y-6010I274J-292D01*
G02X172656Y-6029I-940J-1040D01*
G03X172651Y-5441I-274J292D01*
G02X174552Y-5422I940J1040D01*
G37*
G36*
G01X137741D02*
G03X137746Y-6010I274J-292D01*
G02X135845Y-6029I-940J-1040D01*
G03X135840Y-5441I-274J292D01*
G02X137741Y-5422I940J1040D01*
G37*
G36*
G01X1230841Y-5666D02*
G03Y-6245I276J-290D01*
G02X1228907I-967J-1015D01*
G03Y-5666I-276J290D01*
G02X1230841I967J1015D01*
G37*
G36*
G01X1194030D02*
G03Y-6245I276J-290D01*
G02X1192096I-967J-1015D01*
G03Y-5666I-276J290D01*
G02X1194030I967J1015D01*
G37*
G36*
G01X1157219D02*
G03Y-6245I276J-290D01*
G02X1155285I-967J-1015D01*
G03Y-5666I-276J290D01*
G02X1157219I967J1015D01*
G37*
G36*
G01X1120407D02*
G03Y-6245I276J-290D01*
G02X1118473I-967J-1015D01*
G03Y-5666I-276J290D01*
G02X1120407I967J1015D01*
G37*
G36*
G01X939699D02*
G03Y-6245I276J-290D01*
G02X937765I-967J-1015D01*
G03Y-5666I-276J290D01*
G02X939699I967J1015D01*
G37*
G36*
G01X902888D02*
G03Y-6245I276J-290D01*
G02X900954I-967J-1015D01*
G03Y-5666I-276J290D01*
G02X902888I967J1015D01*
G37*
G36*
G01X866077D02*
G03Y-6245I276J-290D01*
G02X864143I-967J-1015D01*
G03Y-5666I-276J290D01*
G02X866077I967J1015D01*
G37*
G36*
G01X829266D02*
G03Y-6245I276J-290D01*
G02X827332I-967J-1015D01*
G03Y-5666I-276J290D01*
G02X829266I967J1015D01*
G37*
G36*
G01X792455D02*
G03Y-6245I276J-290D01*
G02X790521I-967J-1015D01*
G03Y-5666I-276J290D01*
G02X792455I967J1015D01*
G37*
G36*
G01X581233D02*
G03Y-6245I276J-290D01*
G02X579299I-967J-1015D01*
G03Y-5666I-276J290D01*
G02X581233I967J1015D01*
G37*
G36*
G01X544422D02*
G03Y-6245I276J-290D01*
G02X542488I-967J-1015D01*
G03Y-5666I-276J290D01*
G02X544422I967J1015D01*
G37*
G36*
G01X507611D02*
G03Y-6245I276J-290D01*
G02X505677I-967J-1015D01*
G03Y-5666I-276J290D01*
G02X507611I967J1015D01*
G37*
G36*
G01X470799D02*
G03Y-6245I276J-290D01*
G02X468865I-967J-1015D01*
G03Y-5666I-276J290D01*
G02X470799I967J1015D01*
G37*
G36*
G01X290091D02*
G03Y-6245I276J-290D01*
G02X288157I-967J-1015D01*
G03Y-5666I-276J290D01*
G02X290091I967J1015D01*
G37*
G36*
G01X253280D02*
G03Y-6245I276J-290D01*
G02X251346I-967J-1015D01*
G03Y-5666I-276J290D01*
G02X253280I967J1015D01*
G37*
G36*
G01X216469D02*
G03Y-6245I276J-290D01*
G02X214535I-967J-1015D01*
G03Y-5666I-276J290D01*
G02X216469I967J1015D01*
G37*
G36*
G01X179658D02*
G03Y-6245I276J-290D01*
G02X177724I-967J-1015D01*
G03Y-5666I-276J290D01*
G02X179658I967J1015D01*
G37*
G36*
G01X142847D02*
G03Y-6245I276J-290D01*
G02X140913I-967J-1015D01*
G03Y-5666I-276J290D01*
G02X142847I967J1015D01*
G37*
G36*
G01X647971Y-10511D02*
G03Y-11089I277J-289D01*
G02X646029I-971J-1011D01*
G03Y-10511I-277J289D01*
G02X646208Y-8343I971J1011D01*
G03X646297Y-7766I-226J330D01*
G02X648192Y-8057I1103J866D01*
G03X648103Y-8634I226J-330D01*
G02X647971Y-10511I-1103J-866D01*
G37*
G36*
G01X64936Y-12238D02*
G03X65464Y-12420I357J180D01*
G02X64808Y-14317I597J-1268D01*
G03X64280Y-14135I-357J-180D01*
G02X64936Y-12238I-597J1268D01*
G37*
G36*
G01X730372Y-16258D02*
G03X729818Y-16331I-240J-320D01*
G02X727466Y-16100I-1102J866D01*
G03X726936Y-15921I-356J-181D01*
G02X725354Y-15668I-609J1263D01*
G03X724800I-277J-288D01*
G02Y-13648I-973J1010D01*
G03X725354I277J288D01*
G02X726891Y-13374I973J-1010D01*
G03X727448Y-12954I161J366D01*
G02X729716Y-13856I1389J191D01*
G03X729689Y-14455I250J-311D01*
G02X729693Y-14460I-1084J-871D01*
G03X730004Y-14418I139J144D01*
G02X730372Y-16258I1206J-716D01*
G37*
G36*
G01X1585527Y-17110D02*
G03X1584973I-277J-288D01*
G02Y-15090I-973J1010D01*
G03X1585527I277J288D01*
G02Y-17110I973J-1010D01*
G37*
G36*
G01X42908Y-15061D02*
G03X43095Y-15617I351J-191D01*
G02X41289Y-16225I-575J-1279D01*
G03X41102Y-15669I-351J191D01*
G02X42908Y-15061I575J1279D01*
G37*
G36*
G01X1375736Y-17802D02*
G03X1375155Y-17824I-280J-285D01*
G02X1373046I-1055J924D01*
G03X1372502Y-17769I-301J-263D01*
G02X1370658Y-15667I-849J1115D01*
G03X1370647Y-15093I-284J282D01*
G02X1370569Y-13124I958J1024D01*
G03X1370568Y-12584I-296J269D01*
G02X1370580Y-10669I1030J951D01*
G03X1370588Y-10127I-290J275D01*
G02X1372650Y-10155I1044J936D01*
G03X1372642Y-10697I290J-275D01*
G02X1372634Y-12578I-1044J-936D01*
G03X1372635Y-13118I296J-269D01*
G02X1372600Y-15056I-1030J-951D01*
G03X1372611Y-15630I284J-282D01*
G02X1372707Y-15730I-962J-1020D01*
G03X1373251Y-15785I301J263D01*
G02X1375083Y-15900I850J-1115D01*
G03X1375664Y-15878I280J285D01*
G02X1375736Y-17802I1055J-924D01*
G37*
G36*
G01X1316783Y-17747D02*
G03X1316140Y-17755I-319J-242D01*
G02X1313907Y-17806I-1136J822D01*
G03X1313306Y-17776I-314J-248D01*
G02X1311211Y-17683I-1006J976D01*
G03X1310589I-311J-252D01*
G02X1308411I-1089J883D01*
G03X1307789I-311J-252D01*
G02X1306264Y-15467I-1089J883D01*
G03X1306531Y-15001I-124J380D01*
G02X1308989Y-13817I1369J301D01*
G03X1309611I311J252D01*
G02X1311789I1089J-883D01*
G03X1312411I311J252D01*
G02X1314621Y-13858I1089J-883D01*
G03X1315242Y-13880I319J241D01*
G02X1317428Y-13968I1058J-920D01*
G03X1318072I322J238D01*
G02X1320289Y-13917I1128J-832D01*
G03X1320911I311J252D01*
G02X1321879Y-13403I1089J-883D01*
G03X1322234Y-12915I-35J398D01*
G02X1324577Y-11595I1366J315D01*
G03X1325110Y-11617I279J287D01*
G02X1327089Y-11817I890J-1083D01*
G03X1327711I311J252D01*
G02X1329236Y-14033I1089J-883D01*
G03X1328969Y-14499I124J-380D01*
G02X1328036Y-16133I-1369J-302D01*
G03X1327769Y-16599I124J-380D01*
G02X1325311Y-17783I-1369J-301D01*
G03X1324689I-311J-252D01*
G02X1322511I-1089J883D01*
G03X1321889I-311J-252D01*
G02X1319672Y-17732I-1089J883D01*
G03X1319028I-322J-238D01*
G02X1316783Y-17747I-1128J832D01*
G37*
G36*
G01X1606531Y-18356D02*
G03X1605977I-277J-288D01*
G02Y-16336I-973J1010D01*
G03X1606531I277J288D01*
G02X1608477I973J-1010D01*
G03X1609031I277J288D01*
G02Y-18356I973J-1010D01*
G03X1608477I-277J-288D01*
G02X1606531I-973J1010D01*
G37*
G36*
G01X1596531D02*
G03X1595977I-277J-288D01*
G02Y-16336I-973J1010D01*
G03X1596531I277J288D01*
G02X1598477I973J-1010D01*
G03X1599031I277J288D01*
G02Y-18356I973J-1010D01*
G03X1598477I-277J-288D01*
G02X1596531I-973J1010D01*
G37*
G36*
G01X661185Y-16750D02*
G03X661784Y-16839I338J214D01*
G02X661515Y-18650I916J-1062D01*
G03X660916Y-18561I-338J-214D01*
G02X661185Y-16750I-916J1062D01*
G37*
G36*
G01X1300366Y-16666D02*
G03X1300430Y-17281I284J-281D01*
G02X1298511Y-17399I-881J-1338D01*
G03X1298500Y-16780I-259J305D01*
G02X1300366Y-16666I869J1100D01*
G37*
G36*
G01X21111Y-18129D02*
G03X21683Y-18241I339J213D01*
G02X21312Y-20127I816J-1140D01*
G03X20740Y-20015I-339J-213D01*
G02X21111Y-18129I-816J1140D01*
G37*
G36*
G01X709720Y-17986D02*
G03X710115Y-18437I397J-51D01*
G02X708717Y-19659I-8J-1402D01*
G03X708322Y-19208I-397J51D01*
G02X709720Y-17986I8J1402D01*
G37*
G36*
G01X1902168Y-18425D02*
G02X1901892Y-20014I992J-991D01*
G03X1901248Y-19902I-361J-171D01*
G02X1901524Y-18313I-992J991D01*
G03X1902168Y-18425I361J171D01*
G37*
G36*
G01X714334Y-17027D02*
G02X712514Y-17832I-510J-1306D01*
G03X712286Y-17317I-373J143D01*
G02X711398Y-16115I510J1306D01*
G03X710836Y-15780I-399J-30D01*
G02X709291Y-13490I-573J1280D01*
G03X709305Y-12928I-277J288D01*
G02X711299Y-12978I1022J960D01*
G03X711285Y-13540I277J-288D01*
G02X711661Y-14396I-1022J-960D01*
G03X712223Y-14731I399J30D01*
G02X714106Y-16512I573J-1280D01*
G03X714334Y-17027I373J-143D01*
G37*
G36*
G01X1674935Y-17561D02*
G02X1674904Y-16078I-1435J712D01*
G03X1675602Y-16084I351J193D01*
G02X1675632Y-17526I1217J-696D01*
G03X1674935Y-17561I-339J-213D01*
G37*
G36*
G01X1280343Y-15495D02*
G02X1280321Y-14060I-1443J696D01*
G03X1281025Y-14068I354J186D01*
G02X1283184Y-13700I1227J-679D01*
G03X1283763Y-13650I266J299D01*
G02X1283927Y-15571I1096J-874D01*
G03X1283348Y-15621I-266J-299D01*
G02X1281047Y-15464I-1096J874D01*
G03X1280343Y-15495I-344J-205D01*
G37*
G36*
G01X1498611Y-11287D02*
G02X1497445Y-12317I189J-1389D01*
G03X1496979Y-11822I-387J103D01*
G02X1498178Y-10763I-319J1570D01*
G03X1498611Y-11287I379J-127D01*
G37*
G36*
G01X90170Y-10745D02*
G02X88916Y-9191I-1393J159D01*
G03X89311Y-8609I40J398D01*
G02X90822Y-10483I5373J2786D01*
G03X90170Y-10745I-255J-308D01*
G37*
G36*
G01X735454Y-7525D02*
G02X734182Y-7734I-434J-1333D01*
G03X734066Y-7033I-239J320D01*
G02X733101Y-5790I434J1333D01*
G03X732588Y-5432I-399J-25D01*
G02X731232Y-3064I-397J1345D01*
G03X731260Y-2509I-273J292D01*
G02X733327Y-616I1056J922D01*
G03X733905I289J277D01*
G02Y-2558I1011J-971D01*
G03X733327I-289J-277D01*
G02X733275Y-2610I-1017J965D01*
G03X733247Y-3165I273J-292D01*
G02X733590Y-3997I-1056J-922D01*
G03X734103Y-4355I399J25D01*
G02X735338Y-6824I397J-1345D01*
G03X735454Y-7525I239J-320D01*
G37*
G36*
G01X1606667Y-4377D02*
G02Y-2823I-1167J777D01*
G03X1607333I333J222D01*
G02Y-4377I1167J-777D01*
G03X1606667I-333J-222D01*
G37*
G36*
G01X1837406Y-2254D02*
G02X1836404Y-3467I394J-1346D01*
G03X1835894Y-3046I-398J37D01*
G02X1836896Y-1833I-394J1346D01*
G03X1837406Y-2254I398J-37D01*
G37*
G36*
G01X624333Y-2565D02*
G02X623044Y-1599I-1333J-435D01*
G03X623437Y-1075I13J400D01*
G02X624726Y-2041I1333J435D01*
G03X624333Y-2565I-13J-400D01*
G37*
G36*
G01X1689167Y2223D02*
G02Y3777I-1167J777D01*
G03X1689833I333J222D01*
G02Y2223I1167J-777D01*
G03X1689167I-333J-222D01*
G37*
G36*
G01X1547967Y2623D02*
G02Y4177I-1167J777D01*
G03X1548633I333J222D01*
G02X1550773Y4410I1167J-777D01*
G03X1551327I277J288D01*
G02X1553273I973J-1010D01*
G03X1553827I277J288D01*
G02X1556045Y4045I973J-1010D01*
G03X1556755I355J184D01*
G02X1558973Y4410I1245J-645D01*
G03X1559527I277J288D01*
G02X1561550Y4329I973J-1010D01*
G03X1562150I300J265D01*
G02X1564289Y4283I1050J-929D01*
G03X1564911I311J252D01*
G02X1567167Y4177I1089J-883D01*
G03X1567833I333J222D01*
G02Y2623I1167J-777D01*
G03X1567167I-333J-222D01*
G02X1564911Y2517I-1167J777D01*
G03X1564289I-311J-252D01*
G02X1562150Y2471I-1089J883D01*
G03X1561550I-300J-265D01*
G02X1559527Y2390I-1050J929D01*
G03X1558973I-277J-288D01*
G02X1556755Y2755I-973J1010D01*
G03X1556045I-355J-184D01*
G02X1553827Y2390I-1245J645D01*
G03X1553273I-277J-288D01*
G02X1551327I-973J1010D01*
G03X1550773I-277J-288D01*
G02X1548633Y2623I-973J1010D01*
G03X1547967I-333J-222D01*
G37*
G36*
G01X1510373Y2490D02*
G02Y4510I-973J1010D01*
G03X1510927I277J288D01*
G02X1512873I973J-1010D01*
G03X1513427I277J288D01*
G02X1515373I973J-1010D01*
G03X1515927I277J288D01*
G02X1518145Y4145I973J-1010D01*
G03X1518855I355J184D01*
G02Y2855I1245J-645D01*
G03X1518145I-355J-184D01*
G02X1515927Y2490I-1245J645D01*
G03X1515373I-277J-288D01*
G02X1513427I-973J1010D01*
G03X1512873I-277J-288D01*
G02X1510927I-973J1010D01*
G03X1510373I-277J-288D01*
G37*
G36*
G01X1525889Y2617D02*
G02Y4383I-1089J883D01*
G03X1526511I311J252D01*
G02X1528845Y4145I1089J-883D01*
G03X1529555I355J184D01*
G02X1532045I1245J-645D01*
G03X1532755I355J184D01*
G02Y2855I1245J-645D01*
G03X1532045I-355J-184D01*
G02X1529555I-1245J645D01*
G03X1528845I-355J-184D01*
G02X1526511Y2617I-1245J645D01*
G03X1525889I-311J-252D01*
G37*
G36*
G01X1786560Y7365D02*
G02X1786549Y8852I-1194J735D01*
G03X1787227Y8857I337J215D01*
G02X1787238Y7370I1194J-735D01*
G03X1786560Y7365I-337J-215D01*
G37*
G36*
G01X649581Y7600D02*
G02X647784Y9724I-1031J950D01*
G03X647773Y10401I-218J335D01*
G02X649474Y12608I727J1199D01*
G03X650051Y12630I278J288D01*
G02X651847Y10513I1049J-931D01*
G03Y9837I213J-338D01*
G02X650147Y7622I-747J-1186D01*
G03X649581Y7600I-272J-293D01*
G37*
G36*
G01X1809523Y10358D02*
G02X1807832Y10471I-920J-1058D01*
G03X1807875Y11107I-220J334D01*
G02X1809566Y10994I920J1058D01*
G03X1809523Y10358I220J-334D01*
G37*
G36*
G01X1619797Y12266D02*
X1624799D01*
G02X1626310Y10765I0J-1512D01*
G01Y10670D01*
X1626300Y10586D01*
G02X1624798Y9244I-1502J169D01*
G01X1619796D01*
G02X1618983Y9482I1J1511D01*
G03X1618375Y9224I-216J-336D01*
G02X1617708Y10710I-1375J276D01*
G03X1618305Y10992I202J345D01*
G02X1619797Y12266I1493J-237D01*
G37*
G36*
G01X1842292Y10352D02*
G02X1842206Y8838I1134J-824D01*
G03X1841534Y8876I-348J-197D01*
G02X1839427Y8690I-1134J824D01*
G03X1838873I-277J-288D01*
G02Y10710I-973J1010D01*
G03X1839427I277J288D01*
G02X1841620Y10390I972J-1010D01*
G03X1842292Y10352I348J197D01*
G37*
G36*
G01X1323621Y8939D02*
G02X1321743Y10981I-1089J883D01*
G03X1321733Y11650I-224J331D01*
G02X1321660Y13969I750J1184D01*
G03X1321666Y14613I-234J324D01*
G02X1323597Y16617I842J1121D01*
G03X1324219I311J252D01*
G02X1326340Y16682I1089J-883D01*
G03X1326948Y16704I295J271D01*
G02X1328789Y14643I1097J-873D01*
G03X1328806Y13954I212J-339D01*
G02X1328959Y11604I-683J-1224D01*
G03X1328950Y10968I238J-321D01*
G02X1327028Y8944I-865J-1103D01*
G03X1326417Y8934I-301J-263D01*
G02X1324243Y8939I-1085J888D01*
G03X1323621I-311J-252D01*
G37*
G36*
G01X1833522Y11557D02*
G02X1831621Y9726I-622J-1257D01*
G03X1830952Y9822I-365J-164D01*
G02X1831167Y11309I-1064J913D01*
G03X1831836Y11213I365J164D01*
G02X1832233Y11533I1064J-913D01*
G03X1832220Y12243I-190J352D01*
G02X1833509Y12267I621J1257D01*
G03X1833522Y11557I190J-352D01*
G37*
G36*
G01X63880Y12677D02*
G02X62764Y11443I279J-1374D01*
G03X62287Y11875I-398J40D01*
G02X63403Y13109I-279J1374D01*
G03X63880Y12677I398J-40D01*
G37*
G36*
G01X1847352Y13735D02*
G02X1847035Y12168I970J-1012D01*
G03X1846390Y12298I-368J-158D01*
G02X1846707Y13865I-970J1012D01*
G03X1847352Y13735I368J158D01*
G37*
G36*
G01X1869503Y12151D02*
G02X1869308Y13808I-1217J697D01*
G03X1869946Y13883I291J274D01*
G02X1870141Y12226I1217J-697D01*
G03X1869503Y12151I-291J-274D01*
G37*
G36*
G01X1414946Y12458D02*
G02Y13820I-1225J681D01*
G03X1415646I350J194D01*
G02Y12458I1225J-681D01*
G03X1414946I-350J-194D01*
G37*
G36*
G01X25301Y17595D02*
G02X23782Y16791I-241J-1381D01*
G03X23487Y17350I-364J165D01*
G02X25006Y18154I241J1381D01*
G03X25301Y17595I364J-165D01*
G37*
G36*
G01X63377Y18524D02*
G02X62881Y16915I823J-1135D01*
G03X62269Y17103I-376J-135D01*
G02X62765Y18712I-823J1135D01*
G03X63377Y18524I376J135D01*
G37*
G36*
G01X1025003Y18760D02*
G02X1023684Y19551I-1263J-610D01*
G03X1024028Y20124I-16J399D01*
G02X1025347Y19333I1263J610D01*
G03X1025003Y18760I16J-399D01*
G37*
G36*
G01X35905Y18708D02*
G02X35882Y20238I-1186J747D01*
G03X36553Y20248I332J223D01*
G02X38615Y20596I1186J-747D01*
G03X39234Y20755I250J312D01*
G02X39654Y19125I1296J-535D01*
G03X39035Y18966I-250J-312D01*
G02X36576Y18718I-1296J535D01*
G03X35905Y18708I-332J-223D01*
G37*
G36*
G01X702306Y18872D02*
G02X700071Y18689I-1186J747D01*
G03X699483Y18700I-299J-266D01*
G02X699519Y20599I-1013J969D01*
G03X700107Y20588I299J266D01*
G02X702291Y20390I1013J-969D01*
G03X702964Y20397I334J220D01*
G02X702979Y18879I1186J-747D01*
G03X702306Y18872I-334J-220D01*
G37*
G36*
G01X1853568Y21812D02*
G02X1851033Y22017I-1332J-694D01*
G03X1850781Y22650I-321J239D01*
G02X1850430Y25502I259J1479D01*
G03X1850618Y26060I-163J366D01*
G02X1852351Y25337I1318J720D01*
G03X1852246Y25025I56J-192D01*
G02X1852325Y24907I-1207J-894D01*
G03X1852647Y24879I171J104D01*
G02X1853803Y25396I1134J-985D01*
G03X1854151Y26003I6J400D01*
G02X1855414Y25278I1285J777D01*
G03X1855066Y24671I-6J-400D01*
G02X1853893Y22396I-1285J-777D01*
G03X1853568Y21812I29J-399D01*
G37*
G36*
G01X1857168D02*
G02X1855724Y22616I-1332J-694D01*
G03X1856049Y23200I-29J399D01*
G02X1857403Y25396I1332J694D01*
G03X1857751Y26003I6J400D01*
G02X1859014Y25278I1285J777D01*
G03X1858666Y24671I-6J-400D01*
G02X1857493Y22396I-1285J-777D01*
G03X1857168Y21812I29J-399D01*
G37*
G36*
G01X1860768D02*
G02X1859324Y22616I-1332J-694D01*
G03X1859649Y23200I-29J399D01*
G02X1861003Y25396I1332J694D01*
G03X1861351Y26003I6J400D01*
G02X1864093Y26413I1285J777D01*
G03X1864384Y25927I388J-98D01*
G02X1865444Y23992I-364J-1457D01*
G03X1865745Y23473I379J-127D01*
G02X1864812Y20640I-296J-1473D01*
G03X1864284Y20455I-170J-362D01*
G02X1861610Y21824I-1348J663D01*
G03X1861199Y22408I-353J188D01*
G02X1861093Y22396I-222J1486D01*
G03X1860768Y21812I29J-399D01*
G37*
G36*
G01X1839435Y20812D02*
G02X1836914Y20579I-1335J688D01*
G03X1836287Y20585I-316J-245D01*
G02X1833917Y20634I-1166J947D01*
G03X1833275I-321J-239D01*
G02Y22430I-1204J898D01*
G03X1833917I321J239D01*
G02X1836307Y22453I1204J-898D01*
G03X1836934Y22447I316J245D01*
G02X1839375Y22295I1166J-947D01*
G03X1840064Y22312I339J211D01*
G02X1840124Y20852I1225J-681D01*
G03X1839435Y20812I-333J-222D01*
G37*
G36*
G01X755559Y23924D02*
G02X755505Y22420I1155J-794D01*
G03X754830Y22445I-345J-202D01*
G02X754884Y23949I-1155J794D01*
G03X755559Y23924I345J202D01*
G37*
G36*
G01X713670Y24408D02*
G02X713617Y22895I1153J-798D01*
G03X712944Y22918I-344J-204D01*
G02X712997Y24431I-1153J798D01*
G03X713670Y24408I344J204D01*
G37*
G36*
G01X308620Y32550D02*
X308598Y32570D01*
Y33485D01*
X307237Y34846D01*
X307976Y35693D01*
Y35694D01*
G03X307824Y36329I-301J264D01*
G01X307066Y36630D01*
Y50138D01*
X308028Y50336D01*
X308029Y50337D01*
G03Y51121I-79J392D01*
G01X308028Y51122D01*
X307066Y51320D01*
Y53706D01*
G02Y56008I609J1151D01*
G01Y66826D01*
G02X307770Y69094I862J976D01*
G02X308254Y70097I1400J-57D01*
G03X308061Y70794I-262J303D01*
G01X307066Y70968D01*
Y73113D01*
X307761Y73437D01*
G03Y74163I-169J363D01*
G01X307759Y74164D01*
X307066Y74489D01*
Y85797D01*
G02X308191Y86994I1201J-2D01*
G03Y87794I-25J400D01*
G02X307066Y88991I76J1199D01*
G01Y91394D01*
G02Y93920I609J1263D01*
G01Y95286D01*
X307441Y95665D01*
X308190Y96415D01*
Y106465D01*
X310240Y108515D01*
Y113833D01*
X332372Y135965D01*
Y155870D01*
G03X331749Y156201I-400J-1D01*
G02Y170963I-4977J7381D01*
G03X332372Y171294I223J332D01*
G01Y197394D01*
G02X334205Y198727I1402J-1D01*
G03Y199489I123J381D01*
G02X332372Y200822I-431J1334D01*
G01Y213435D01*
X331340Y214467D01*
Y218218D01*
X332194Y218477D01*
G03Y219243I-116J383D01*
G01X331340Y219502D01*
Y221568D01*
G02X332092Y224162I738J1192D01*
G03X332294Y224362I2J200D01*
G01Y225058D01*
G03X332092Y225258I-200J0D01*
G02X333452Y226382I-14J1402D01*
G03X333805Y225904I392J-80D01*
G02X333823Y225903I-69J-1398D01*
G03X334264Y226344I44J397D01*
G02X334524Y227324I1393J155D01*
G03X334499Y227587I-162J117D01*
G02X334440Y229575I959J1023D01*
G01Y231545D01*
G02X336379Y233567I1018J965D01*
G01X336520Y233444D01*
X337865Y234790D01*
X338571Y234161D01*
G03X339137Y234727I267J299D01*
G01X338508Y235433D01*
X339190Y236115D01*
Y238118D01*
X339226Y238262D01*
X339227Y238263D01*
G03Y238457I-389J97D01*
G01X339226Y238458D01*
X339190Y238602D01*
Y242018D01*
X339226Y242162D01*
X339227Y242163D01*
G03Y242357I-389J97D01*
G01X339226Y242358D01*
X339190Y242502D01*
Y244715D01*
X341077Y246602D01*
X341492D01*
Y246905D01*
X341408Y246965D01*
G02X343324Y247247I810J1144D01*
G03X343639Y246602I316J-245D01*
G01X344261D01*
X344313Y246721D01*
G02X346883I1285J-561D01*
G01X346935Y246602D01*
X351020D01*
X351072Y246721D01*
G02X353642I1285J-561D01*
G01X353694Y246602D01*
X357780D01*
X357832Y246721D01*
G02X360402I1285J-561D01*
G01X360454Y246602D01*
X361076D01*
G03X361391Y247247I-1J400D01*
G02X363603I1106J862D01*
G03X363918Y246602I316J-245D01*
G01X364540D01*
X364592Y246721D01*
G02X367162I1285J-561D01*
G01X367214Y246602D01*
X368355D01*
X368580Y246826D01*
X368428Y246978D01*
X368417Y246986D01*
G02X370264Y249085I840J1123D01*
G03X370834Y249080I287J278D01*
G01X371172Y249418D01*
X373096D01*
X373534Y249857D01*
Y251418D01*
X374628Y252512D01*
X374702D01*
X374757Y252624D01*
G02X377277I1260J-615D01*
G01X377332Y252512D01*
X383831D01*
G03X384096Y253211I0J400D01*
G02X385958I931J1048D01*
G03X386223Y252512I265J-299D01*
G01X390591D01*
G03X390856Y253211I0J400D01*
G02X392718I931J1048D01*
G03X392983Y252512I265J-299D01*
G01X397350D01*
G03X397615Y253211I0J400D01*
G02X399477I931J1048D01*
G03X399742Y252512I265J-299D01*
G01X408205D01*
X410682Y250035D01*
Y214298D01*
X409852Y213467D01*
Y210750D01*
G02X407871Y209474I-1402J0D01*
G03Y208744I-165J-365D01*
G02X409852Y207468I579J-1276D01*
G01Y205757D01*
X411114Y204495D01*
Y197687D01*
X414294Y194507D01*
Y135007D01*
X449140Y100161D01*
Y90589D01*
X448502Y90253D01*
G03Y89547I190J-353D01*
G01X449140Y89211D01*
Y85978D01*
X448441Y85659D01*
G03Y84933I169J-363D01*
G01X449140Y84614D01*
Y74273D01*
X448434Y73954D01*
G03X448339Y73284I165J-365D01*
G02X448379Y71191I-911J-1064D01*
G03X448397Y70587I272J-294D01*
G02X448379Y68404I-888J-1084D01*
G03X448454Y67728I248J-315D01*
G01X449140Y67404D01*
Y55505D01*
X448735Y55205D01*
G03Y54561I238J-322D01*
G01X449140Y54261D01*
Y51664D01*
X448353Y51376D01*
G03Y50624I139J-376D01*
G01X449140Y50336D01*
Y47648D01*
X448373Y47349D01*
X448372Y47348D01*
G03Y46602I145J-373D01*
G01X448373Y46601D01*
X449140Y46302D01*
Y36401D01*
X448293Y36143D01*
G03Y35379I121J-382D01*
G01X449140Y35121D01*
Y32506D01*
X448205Y32291D01*
X448203Y32290D01*
G03Y31510I89J-390D01*
G01X448205Y31509D01*
X449140Y31294D01*
Y28674D01*
X448154Y28494D01*
G03Y27706I72J-394D01*
G01X449140Y27526D01*
Y25281D01*
X446957Y23098D01*
X382541D01*
G02X381181Y24837I0J1402D01*
G03X381033Y25253I-389J96D01*
G02X380927Y25341I841J1121D01*
G03X380657I-135J-148D01*
G02X380551Y25253I-947J1033D01*
G03X380403Y24837I241J-320D01*
G02X379043Y23098I-1360J-337D01*
G01X311827D01*
X308620Y26306D01*
Y26401D01*
G03X308092Y26780I-400J0D01*
G02Y29248I-417J1234D01*
G03X308620Y29627I128J379D01*
G01Y32550D01*
G37*
G36*
G01X981980Y197394D02*
G02X983813Y198727I1402J-1D01*
G03Y199489I123J381D01*
G02X981980Y200822I-431J1334D01*
G01Y213435D01*
X980948Y214467D01*
Y218218D01*
X981802Y218477D01*
G03Y219243I-116J383D01*
G01X980948Y219502D01*
Y221568D01*
G02X981696Y224162I738J1192D01*
G03X982098Y224562I2J400D01*
G01Y224858D01*
G03X981696Y225258I-400J0D01*
G02X983084Y226767I-10J1402D01*
G01X983090Y226693D01*
X983283Y226500D01*
X983490Y226707D01*
X983691Y226507D01*
X983876Y226693D01*
X983887Y226754D01*
G02X984132Y227324I1378J-255D01*
G03X984107Y227587I-162J117D01*
G02X984048Y229575I959J1023D01*
G01Y231544D01*
G02X985987Y233566I1018J965D01*
G01X986127Y233444D01*
X987390Y234707D01*
X988216Y234132D01*
X988217Y234131D01*
G03X988775Y234689I229J329D01*
G01X988774Y234690D01*
X988199Y235516D01*
X988798Y236115D01*
Y238118D01*
X988834Y238262D01*
X988835Y238263D01*
G03Y238457I-389J97D01*
G01X988834Y238458D01*
X988798Y238602D01*
Y242018D01*
X988834Y242162D01*
X988835Y242163D01*
G03Y242357I-389J97D01*
G01X988834Y242358D01*
X988798Y242502D01*
Y244715D01*
X990685Y246602D01*
X991100D01*
Y246905D01*
X991016Y246965D01*
G02X992932Y247247I810J1144D01*
G03X993247Y246602I316J-245D01*
G01X993869D01*
X993921Y246721D01*
G02X996491I1285J-561D01*
G01X996543Y246602D01*
X1000628D01*
X1000680Y246721D01*
G02X1003250I1285J-561D01*
G01X1003302Y246602D01*
X1007388D01*
X1007440Y246721D01*
G02X1010010I1285J-561D01*
G01X1010062Y246602D01*
X1010684D01*
G03X1010999Y247247I-1J400D01*
G02X1013211I1106J862D01*
G03X1013526Y246602I316J-245D01*
G01X1014148D01*
X1014200Y246721D01*
G02X1016770I1285J-561D01*
G01X1016822Y246602D01*
X1017835D01*
X1018117Y246883D01*
X1017969Y247031D01*
X1017963Y247036D01*
G02X1019822Y249134I903J1073D01*
G03X1020377Y249144I272J293D01*
G01X1020703Y249470D01*
X1022802D01*
X1022876Y249544D01*
Y251520D01*
X1023868Y252512D01*
X1024310D01*
X1024365Y252624D01*
G02X1026885I1260J-615D01*
G01X1026940Y252512D01*
X1033439D01*
G03X1033704Y253211I0J400D01*
G02X1035566I931J1048D01*
G03X1035831Y252512I265J-299D01*
G01X1040199D01*
G03X1040464Y253211I0J400D01*
G02X1042326I931J1048D01*
G03X1042591Y252512I265J-299D01*
G01X1046958D01*
G03X1047223Y253211I0J400D01*
G02X1049085I931J1048D01*
G03X1049350Y252512I265J-299D01*
G01X1057985D01*
X1060502Y249995D01*
Y214827D01*
X1059460Y213785D01*
Y210750D01*
G02X1057479Y209474I-1402J0D01*
G03Y208744I-165J-365D01*
G02X1059460Y207468I579J-1276D01*
G01Y205757D01*
X1060722Y204495D01*
Y197687D01*
X1063902Y194507D01*
Y135007D01*
X1098748Y100161D01*
Y90589D01*
X1098110Y90253D01*
G03Y89547I190J-353D01*
G01X1098748Y89211D01*
Y85978D01*
X1098049Y85659D01*
G03Y84933I169J-363D01*
G01X1098748Y84614D01*
Y74273D01*
X1098042Y73954D01*
G03X1097947Y73284I165J-365D01*
G02X1097987Y71191I-911J-1064D01*
G03X1098005Y70587I272J-294D01*
G02X1097987Y68404I-888J-1084D01*
G03X1098062Y67728I248J-315D01*
G01X1098748Y67404D01*
Y55505D01*
X1098343Y55205D01*
G03Y54561I238J-322D01*
G01X1098748Y54261D01*
Y51664D01*
X1097961Y51376D01*
G03Y50624I139J-376D01*
G01X1098748Y50336D01*
Y47648D01*
X1097981Y47349D01*
X1097980Y47348D01*
G03Y46602I145J-373D01*
G01X1097981Y46601D01*
X1098748Y46302D01*
Y36401D01*
X1097901Y36143D01*
G03Y35379I121J-382D01*
G01X1098748Y35121D01*
Y32506D01*
X1097813Y32291D01*
X1097811Y32290D01*
G03Y31510I89J-390D01*
G01X1097813Y31509D01*
X1098748Y31294D01*
Y28674D01*
X1097762Y28494D01*
G03Y27706I72J-394D01*
G01X1098748Y27526D01*
Y25281D01*
X1096565Y23098D01*
X1031042D01*
X1030745Y23421D01*
G03X1030666Y23487I-294J-272D01*
G02X1030441Y23666I756J1181D01*
G02X1030223Y23480I-1014J968D01*
G03X1030155Y23421I227J-330D01*
G01X1029858Y23098D01*
X961435D01*
X957998Y26535D01*
Y26803D01*
X957763D01*
X957730Y26791D01*
G02X957683Y29253I-447J1223D01*
G01X957799Y29216D01*
X958698Y30115D01*
Y32385D01*
X956465Y34619D01*
X957404Y35558D01*
X957506Y35624D01*
G03X957432Y36329I-223J333D01*
G01X956674Y36630D01*
Y50138D01*
X957636Y50336D01*
X957637Y50337D01*
G03Y51121I-79J392D01*
G01X957636Y51122D01*
X956674Y51320D01*
Y53706D01*
G02Y56008I609J1151D01*
G01Y66826D01*
G02X957378Y69094I862J976D01*
G02X957862Y70097I1400J-57D01*
G03X957669Y70794I-262J303D01*
G01X957668Y70795D01*
X956674Y70969D01*
Y73111D01*
X957367Y73436D01*
X957369Y73437D01*
G03Y74163I-169J363D01*
G01X957367Y74164D01*
X956674Y74489D01*
Y85797D01*
G02X957799Y86994I1201J-2D01*
G03X957877Y87781I-25J400D01*
G01X957590Y87843D01*
X956948Y88484D01*
Y91288D01*
X956815Y91335D01*
G02X956197Y93543I468J1322D01*
G02X955856Y94458I1060J916D01*
G01Y96129D01*
X956321Y96596D01*
X957248Y97524D01*
Y106465D01*
X959248Y108465D01*
Y113233D01*
X981980Y135965D01*
Y155871D01*
G03X981357Y156203I-400J0D01*
G02Y170961I-4979J7379D01*
G03X981980Y171293I223J332D01*
G01Y197394D01*
G37*
G36*
G01X1871884Y25563D02*
G02X1869964Y26249I-1284J-563D01*
G03X1870029Y26921I-181J357D01*
G02X1872259Y26123I2314J2953D01*
G03X1871884Y25563I-8J-400D01*
G37*
G36*
G01X69167Y25215D02*
G02X66831Y25218I-1167J777D01*
G03X66165Y25220I-334J-221D01*
G02X63833Y25223I-1165J780D01*
G03X63167I-333J-222D01*
G02X61027Y24990I-1167J777D01*
G03X60473I-277J-288D01*
G02X58490Y26973I-973J1010D01*
G03Y27527I-288J277D01*
G02X60473Y29510I1010J973D01*
G03X61027I277J288D01*
G02X63167Y29277I973J-1010D01*
G03X63833I333J222D01*
G02X66167I1167J-777D01*
G03X66833I333J222D01*
G02X69167I1167J-777D01*
G03X69833I333J222D01*
G02X72167I1167J-777D01*
G03X72833I333J222D01*
G02X75167I1167J-777D01*
G03X75833I333J222D01*
G02X78043Y29436I1167J-777D01*
G03X78709Y29547I298J267D01*
G02X80777Y27833I1291J-547D01*
G03Y27167I222J-333D01*
G02X78835Y25220I-777J-1167D01*
G03X78169Y25218I-332J-223D01*
G02X75833Y25215I-1169J774D01*
G03X75167I-333J-222D01*
G02X72833I-1167J777D01*
G03X72167I-333J-222D01*
G02X69833I-1167J777D01*
G03X69167I-333J-222D01*
G37*
G36*
G01X1837669Y27730D02*
G02X1837537Y25688I1031J-1092D01*
G03X1836952Y25726I-310J-253D01*
G02X1834677Y25976I-1031J1092D01*
G03X1834015I-331J-224D01*
G02X1831521Y25986I-1244J842D01*
G03X1830843Y25967I-333J-222D01*
G02X1830776Y27496I-1207J713D01*
G03X1831452Y27537I325J233D01*
G02X1834015Y27660I1319J-719D01*
G03X1834677I331J224D01*
G02X1837084Y27768I1244J-842D01*
G03X1837669Y27730I310J253D01*
G37*
G36*
G01X643566Y30162D02*
G02X643831Y32385I-5773J1815D01*
G03X644497Y32113I399J26D01*
G02X644277Y30270I933J-1046D01*
G03X643566Y30162I-329J-228D01*
G37*
G36*
G01X1855356Y35523D02*
G02X1855081Y33888I977J-1005D01*
G03X1854444Y33995I-358J-180D01*
G02X1854719Y35630I-977J1005D01*
G03X1855356Y35523I358J180D01*
G37*
G36*
G01X702098Y36889D02*
G02X700469Y36532I-573J-1279D01*
G03X700331Y37160I-302J263D01*
G02X701960Y37517I573J1279D01*
G03X702098Y36889I302J-263D01*
G37*
G36*
G01X3401Y37588D02*
G02X2221Y36451I199J-1388D01*
G03X1771Y36919I-393J72D01*
G02X2951Y38056I-199J1388D01*
G03X3401Y37588I393J-72D01*
G37*
G36*
G01X1818049Y38126D02*
G02X1816526Y38042I-697J-1217D01*
G03X1816489Y38712I-236J323D01*
G02X1818012Y38796I697J1217D01*
G03X1818049Y38126I236J-323D01*
G37*
G36*
G01X1879863Y38648D02*
G02X1877978Y38508I-866J-1102D01*
G03X1877934Y39098I-291J275D01*
G02X1878027Y41370I866J1102D01*
G03Y42037I-220J334D01*
G02X1879573I773J1170D01*
G03Y41370I220J-333D01*
G02X1879819Y39238I-773J-1169D01*
G03X1879863Y38648I291J-275D01*
G37*
G36*
G01X717821Y39557D02*
G02X715736Y37718I-921J-1057D01*
G03X715097Y37752I-332J-223D01*
G02X712873Y37851I-1074J901D01*
G03X712224Y37862I-328J-228D01*
G02X710054Y39634I-1123J839D01*
G03Y40166I-298J266D01*
G02X712250Y41902I1046J933D01*
G03X712899Y41891I328J228D01*
G02X713154Y42154I1126J-836D01*
G03X713149Y42786I-247J314D01*
G02X713067Y44947I851J1114D01*
G03X712995Y45595I-266J298D01*
G02X714647Y47831I679J1227D01*
G03X715203I278J288D01*
G02X717077Y47896I973J-1009D01*
G03X717615Y47918I257J307D01*
G02X718193Y48263I987J-996D01*
G03X718471Y48718I-115J383D01*
G02X720796Y50005I1379J252D01*
G03X721342Y50011I270J295D01*
G02X723690Y48740I970J-1012D01*
G03X723976Y48280I393J-75D01*
G02X722657Y45894I-373J-1351D01*
G03X722111Y45888I-270J-295D01*
G02X720144Y45914I-970J1012D01*
G03X719580Y45919I-285J-281D01*
G02X717699Y45847I-980J1002D01*
G03X717161Y45825I-257J-307D01*
G02X717105Y45772I-991J991D01*
G03X717222Y45101I265J-299D01*
G02X717628Y42749I-522J-1301D01*
G03X717637Y42141I264J-300D01*
G02X717786Y40126I-895J-1079D01*
G03X717821Y39557I298J-267D01*
G37*
G36*
G01X1825416Y39145D02*
G02X1824999Y40803I-1286J558D01*
G03X1825614Y40958I248J314D01*
G02X1826031Y39300I1286J-558D01*
G03X1825416Y39145I-248J-314D01*
G37*
G36*
G01X1637398Y38350D02*
X1632398D01*
G02X1630896Y39694I0J1512D01*
G03X1630473Y40049I-398J-44D01*
G02X1629531Y40337I-87J1399D01*
G03X1629211Y40150I-122J-159D01*
G02X1629219Y40082I-1497J-211D01*
G01X1629226Y40019D01*
X1629227Y39956D01*
G02Y39911I-1512J-23D01*
G01X1629226Y39910D01*
Y39900D01*
G02X1627725Y38423I-1511J34D01*
G01X1622645Y38389D01*
G02X1622625Y41411I-10J1511D01*
G01X1627704Y41445D01*
G02X1628410Y41277I13J-1512D01*
G03X1628991Y41591I183J355D01*
G02X1631767Y41690I1395J-143D01*
G03X1632211Y41362I394J69D01*
G02X1632398Y41374I190J-1500D01*
G01X1637399D01*
G02X1638910Y39872I-1J-1512D01*
G01Y39777D01*
X1638900Y39693D01*
G02X1637398Y38350I-1502J169D01*
G37*
G36*
G01X1868660Y40718D02*
G02X1867396Y41163I-1041J-939D01*
G03X1867629Y41826I-64J395D01*
G02X1868893Y41381I1041J939D01*
G03X1868660Y40718I64J-395D01*
G37*
G36*
G01X685717Y41085D02*
G02X684243Y41179I-813J-1142D01*
G03X684287Y41858I-188J353D01*
G02X685761Y41764I813J1142D01*
G03X685717Y41085I188J-353D01*
G37*
G36*
G01X1350135Y39522D02*
G02X1350061Y41113I-1190J742D01*
G03X1350718Y41144I318J243D01*
G02X1350792Y39553I1190J-742D01*
G03X1350135Y39522I-318J-243D01*
G37*
G36*
G01X1856584Y40050D02*
G02X1856393Y41790I-1184J751D01*
G03X1857014Y41858I283J282D01*
G02X1859170Y42118I1184J-750D01*
G03X1859745Y42139I277J288D01*
G02X1859814Y40190I1041J-939D01*
G03X1859239Y40169I-277J-288D01*
G02X1857205Y40118I-1041J939D01*
G03X1856584Y40050I-283J-282D01*
G37*
G36*
G01X59973Y42490D02*
G02X58223Y44667I-972J1010D01*
G03Y45333I-222J333D01*
G02Y47667I777J1167D01*
G03Y48333I-222J333D01*
G02X59973Y50510I778J1167D01*
G03X60527I277J288D01*
G02X62667Y50277I973J-1010D01*
G03X63333I333J222D01*
G02X65667I1167J-777D01*
G03X66333I333J222D01*
G02X68667I1167J-777D01*
G03X69333I333J222D01*
G02X71667I1167J-777D01*
G03X72333I333J222D01*
G02X74667I1167J-777D01*
G03X75333I333J222D01*
G02X77667I1167J-777D01*
G03X78333I333J222D01*
G02X80277Y48333I1167J-777D01*
G03Y47667I222J-333D01*
G02Y45333I-777J-1167D01*
G03Y44667I222J-333D01*
G02X78333Y42723I-777J-1167D01*
G03X77667I-333J-222D01*
G02X75333I-1167J777D01*
G03X74667I-333J-222D01*
G02X72333I-1167J777D01*
G03X71667I-333J-222D01*
G02X69333I-1167J777D01*
G03X68667I-333J-222D01*
G02X66333I-1167J777D01*
G03X65667I-333J-222D01*
G02X63333I-1167J777D01*
G03X62667I-333J-222D01*
G02X60527Y42490I-1167J777D01*
G03X59973I-277J-288D01*
G37*
G36*
G01X657040Y43629D02*
G02X655290Y45806I-972J1010D01*
G03Y46472I-222J333D01*
G02X657040Y48649I778J1167D01*
G03X657594I277J288D01*
G02X659344Y46472I972J-1010D01*
G03Y45806I222J-333D01*
G02X657594Y43629I-778J-1167D01*
G03X657040I-277J-288D01*
G37*
G36*
G01X1378856Y46412D02*
G02X1377714Y45162I254J-1379D01*
G03X1377243Y45592I-398J37D01*
G02X1378385Y46842I-254J1379D01*
G03X1378856Y46412I398J-37D01*
G37*
G36*
G01X1266336Y46199D02*
G02X1266158Y47939I-1179J758D01*
G03X1266780Y48003I285J280D01*
G02X1266958Y46263I1179J-758D01*
G03X1266336Y46199I-285J-280D01*
G37*
G36*
G01X12409Y48226D02*
G02X10405Y47952I-870J-1099D01*
G03X10330Y48501I-323J235D01*
G02X10187Y48631I869J1100D01*
G03X9632Y48653I-289J-277D01*
G02X9713Y50669I-932J1047D01*
G03X10268Y50647I289J277D01*
G02X12303Y50466I932J-1047D01*
G03X12926Y50459I314J247D01*
G02X12773Y48910I1084J-889D01*
G03X12422Y48913I-176J-94D01*
G02X12334Y48775I-1224J684D01*
G03X12409Y48226I323J-235D01*
G37*
G36*
G01X-8844Y50087D02*
G02X-8845Y51712I-1143J812D01*
G03X-8193I326J232D01*
G02X-8192Y50087I1143J-812D01*
G03X-8844I-326J-232D01*
G37*
G36*
G01X114508Y56436D02*
G02X112892Y55842I-426J-1336D01*
G03X112674Y56434I-339J211D01*
G02X114290Y57028I426J1336D01*
G03X114508Y56436I339J-211D01*
G37*
G36*
G01X1393023Y54549D02*
G02X1391273Y56726I-972J1010D01*
G03Y57392I-222J333D01*
G02X1393023Y59569I778J1167D01*
G03X1393577I277J288D01*
G02X1395523I973J-1010D01*
G03X1396077I277J288D01*
G02X1397827Y57392I972J-1010D01*
G03Y56726I222J-333D01*
G02X1396077Y54549I-778J-1167D01*
G03X1395523I-277J-288D01*
G02X1393577I-973J1010D01*
G03X1393023I-277J-288D01*
G37*
G36*
G01X2629Y57596D02*
G02X1052Y57616I-803J-1149D01*
G03X1060Y58277I-221J333D01*
G02X2637Y58257I803J1149D01*
G03X2629Y57596I221J-333D01*
G37*
G36*
G01X81777Y59667D02*
G02X80223I-777J-1167D01*
G03Y60333I-222J333D01*
G02X81777I777J1167D01*
G03Y59667I222J-333D01*
G37*
G36*
G01X-7239Y59518D02*
G02X-9396Y60971I-1371J292D01*
G03X-9343Y61590I-224J331D01*
G02X-9771Y62657I973J1010D01*
G03X-10237Y63068I-400J16D01*
G02X-11672Y63728I-234J1382D01*
G03X-12369Y63708I-343J-206D01*
G02X-12408Y65082I-1241J652D01*
G03X-11711Y65102I343J206D01*
G02X-10689Y65835I1241J-652D01*
G03X-10449Y66492I-62J395D01*
G02X-9171Y66025I1060J918D01*
G03X-9411Y65368I62J-395D01*
G02X-9069Y64393I-1059J-919D01*
G03X-8603Y63982I400J-16D01*
G02X-6972Y62710I233J-1382D01*
G03X-6449Y62362I398J32D01*
G02X-6662Y59789I439J-1332D01*
G03X-7239Y59518I-186J-354D01*
G37*
G36*
G01X1875282Y59842D02*
G02X1875079Y61138I-1326J456D01*
G03X1875777Y61248I320J240D01*
G02X1875980Y59952I1326J-456D01*
G03X1875282Y59842I-320J-240D01*
G37*
G36*
G01X1393350Y64127D02*
G02X1391442Y66175I-1011J971D01*
G03X1391400Y66821I-256J308D01*
G02X1393262Y68858I749J1185D01*
G03X1393906Y68870I318J243D01*
G02X1396023Y69069I1144J-811D01*
G03X1396577I277J288D01*
G02X1398345Y66904I972J-1011D01*
G03X1398342Y66247I227J-330D01*
G02X1396528Y64127I-802J-1149D01*
G03X1395950I-289J-277D01*
G02X1393928I-1011J971D01*
G03X1393350I-289J-277D01*
G37*
G36*
G01X656573Y65090D02*
G02X654823Y67267I-972J1010D01*
G03Y67933I-222J333D01*
G02X656573Y70110I778J1167D01*
G03X657127I277J288D01*
G02X658877Y67933I972J-1010D01*
G03Y67267I222J-333D01*
G02X657127Y65090I-778J-1167D01*
G03X656573I-277J-288D01*
G37*
G36*
G01X1845071Y66284D02*
G02X1842659Y67986I-1046J1078D01*
G03X1842341Y68550I-364J167D01*
G02X1841469Y68964I174J1492D01*
G03X1840911I-279J-286D01*
G02X1838843Y68942I-1046J1078D01*
G03X1838274Y68917I-272J-293D01*
G02X1835783Y69328I-1113J1009D01*
G03X1835131Y69449I-367J-159D01*
G02X1832991Y69445I-1072J1052D01*
G03X1832445Y69466I-284J-281D01*
G02X1830402Y71666I-985J1134D01*
G03Y72234I-282J284D01*
G02X1832518I1058J1066D01*
G03Y71666I282J-284D01*
G02X1832528Y71656I-1057J-1067D01*
G03X1833074Y71635I284J281D01*
G02X1835531Y70802I985J-1134D01*
G03X1835895Y70734I196J40D01*
G02X1836052Y70939I1267J-807D01*
G03X1836045Y71486I-295J270D01*
G02X1835714Y73030I1084J1040D01*
G03X1835417Y73557I-377J135D01*
G02X1835353Y76487I297J1472D01*
G03X1835640Y76992I-96J388D01*
G02X1838194Y78433I1437J437D01*
G03X1838806Y78452I298J267D01*
G02X1841062Y78569I1179J-930D01*
G03X1841650Y78585I287J279D01*
G02X1844210Y77131I1133J-986D01*
G03X1844476Y76624I380J-124D01*
G02X1845115Y76242I-427J-1440D01*
G03X1845665Y76225I284J281D01*
G02X1846921Y73626I1002J-1119D01*
G03X1846605Y73118I68J-394D01*
G02X1846243Y71646I-1440J-426D01*
G03Y71088I286J-279D01*
G02X1846531Y69418I-1078J-1046D01*
G03X1846849Y68854I364J-167D01*
G02X1847721Y68440I-174J-1492D01*
G03X1848279I279J286D01*
G02Y66284I1046J-1078D01*
G03X1847721I-279J-286D01*
G02X1845629I-1046J1078D01*
G03X1845071I-279J-286D01*
G37*
G36*
G01X1665360Y70935D02*
G02X1663340I-1010J-973D01*
G03Y71489I-288J277D01*
G02X1663233Y71615I1013J969D01*
G03X1662885Y71561I-159J-121D01*
G02X1661123Y70697I-1322J467D01*
G03X1660598Y70311I-125J-380D01*
G02X1659636Y71622I-1402J-20D01*
G03X1660161Y72008I125J380D01*
G02X1660178Y72245I1402J19D01*
G03X1659870Y72443I-198J31D01*
G02X1658127Y72604I-771J1171D01*
G03X1657573I-277J-288D01*
G02Y74624I-973J1010D01*
G03X1658127I277J288D01*
G02X1660500Y73684I973J-1010D01*
G03X1661047Y73332I399J20D01*
G02X1662513Y73059I516J-1304D01*
G03X1663132Y73155I271J294D01*
G02X1665360Y71489I1219J-693D01*
G03Y70935I288J-277D01*
G37*
G36*
G01X1767991Y71341D02*
G02X1767899Y69490I1259J-990D01*
G03X1767268Y69547I-338J-215D01*
G02X1767358Y71346I-1028J953D01*
G03X1767991Y71341I318J242D01*
G37*
G36*
G01X1931256Y69430D02*
G02X1929064Y71484I-1106J1017D01*
G03X1929024Y72073I-289J276D01*
G02X1928738Y72375I937J1174D01*
G03X1928075Y72356I-325J-233D01*
G02X1928001Y73961I-1185J750D01*
G03X1928663Y74004I317J244D01*
G02X1931031Y74301I1298J-757D01*
G03X1931613Y74314I285J281D01*
G02X1933791Y74373I1117J-1004D01*
G03X1934342Y74360I282J284D01*
G02X1935084Y74725I1008J-1113D01*
G03X1935370Y75302I-70J394D01*
G02X1937793Y77024I1337J685D01*
G03X1938374Y77027I289J276D01*
G02X1940610Y76978I1096J-1027D01*
G03X1941224Y76987I303J261D01*
G02X1943420Y77133I1166J-947D01*
G03X1943973Y77137I274J291D01*
G02X1946398Y75462I1047J-1077D01*
G03X1946678Y74913I367J-159D01*
G02X1947377Y74543I-328J-1466D01*
G03X1947924Y74544I273J292D01*
G02Y72352I1027J-1096D01*
G03X1947377Y72351I-273J-292D01*
G02X1945281Y72392I-1027J1096D01*
G03X1944692Y72371I-285J-281D01*
G02X1944640Y72314I-1135J983D01*
G03X1944682Y71725I290J-275D01*
G02X1942644Y69530I-933J-1177D01*
G03X1942056I-294J-270D01*
G02X1939881Y69492I-1106J1017D01*
G03X1939292Y69471I-285J-281D01*
G02X1937123Y69351I-1142J976D01*
G03X1936577I-273J-292D01*
G02X1934523I-1027J1096D01*
G03X1933977I-273J-292D01*
G02X1931844Y69430I-1027J1096D01*
G03X1931256I-294J-270D01*
G37*
G36*
G01X1613948Y71562D02*
G02X1613859Y70164I1167J-776D01*
G03X1613167Y70208I-359J-178D01*
G02X1613256Y71606I-1167J776D01*
G03X1613948Y71562I359J178D01*
G37*
G36*
G01X1585945Y70110D02*
G02X1585874Y71675I-1197J730D01*
G03X1586537Y71704I322J238D01*
G02X1586608Y70139I1197J-730D01*
G03X1585945Y70110I-322J-238D01*
G37*
G36*
G01X650973Y71290D02*
G02X649223Y73467I-972J1010D01*
G03Y74133I-222J333D01*
G02X650973Y76310I778J1167D01*
G03X651527I277J288D01*
G02X653277Y74133I972J-1010D01*
G03Y73467I222J-333D01*
G02X651527Y71290I-778J-1167D01*
G03X650973I-277J-288D01*
G37*
G36*
G01X657473D02*
G02X655723Y73467I-972J1010D01*
G03Y74133I-222J333D01*
G02X657473Y76310I778J1167D01*
G03X658027I277J288D01*
G02X659777Y74133I972J-1010D01*
G03Y73467I222J-333D01*
G02X658027Y71290I-778J-1167D01*
G03X657473I-277J-288D01*
G37*
G36*
G01X1592905Y76213D02*
G02X1590493Y74840I-1305J-513D01*
G03X1589907Y74890I-316J-245D01*
G02X1590069Y76786I-945J1036D01*
G03X1590655Y76736I316J245D01*
G02X1591385Y77085I944J-1037D01*
G03X1591695Y77627I-62J395D01*
G02X1593215Y76755I1305J513D01*
G03X1592905Y76213I62J-395D01*
G37*
G36*
G01X80403Y77220D02*
G02X78872Y77105I-678J-1227D01*
G03X78822Y77773I-243J318D01*
G02X78723Y80167I678J1227D01*
G03Y80833I-222J333D01*
G02X80277I777J1167D01*
G03Y80167I222J-333D01*
G02X80353Y77888I-777J-1167D01*
G03X80403Y77220I243J-318D01*
G37*
G36*
G01X1408457Y76508D02*
G02X1406582Y78504I-1157J792D01*
G03X1406729Y79037I-205J343D01*
G02X1406651Y79208I1234J666D01*
G03X1406277I-187J-70D01*
G02X1403617Y80088I-1313J492D01*
G03X1403239Y80598I-385J110D01*
G02X1404431Y82777I25J1402D01*
G03X1405097I333J222D01*
G02X1407431I1167J-777D01*
G03X1408097I333J222D01*
G02X1409588Y80636I1167J-777D01*
G03X1409300Y80126I93J-389D01*
G02X1408682Y78496I-1336J-426D01*
G03X1408535Y77963I205J-343D01*
G02X1408549Y77938I-1216J-697D01*
G03X1408911Y77950I178J91D01*
G02X1409100Y76530I1289J-551D01*
G03X1408457Y76508I-313J-248D01*
G37*
G36*
G01X6314Y78585D02*
G02X4763Y78637I-815J-1141D01*
G03X4786Y79303I-210J341D01*
G02X6337Y79251I815J1141D01*
G03X6314Y78585I210J-341D01*
G37*
G36*
G01X764202Y79450D02*
G02X762559Y79422I-802J-1150D01*
G03X762548Y80070I-240J320D01*
G02X764191Y80098I802J1150D01*
G03X764202Y79450I240J-320D01*
G37*
G36*
G01X12658Y79649D02*
G02X10884Y79496I-794J-1155D01*
G03X10831Y80112I-280J286D01*
G02X10652Y80257I790J1158D01*
G03X10098I-277J-288D01*
G02X8520Y82532I-972J1010D01*
G03X8543Y83242I-172J361D01*
G02X8187Y83524I681J1226D01*
G03X7583Y83509I-296J-269D01*
G02X7538Y85343I-1083J891D01*
G03X8142Y85358I296J269D01*
G02X10198Y85477I1083J-891D01*
G03X10752I277J288D01*
G02X12330Y83202I972J-1010D01*
G03X12307Y82492I172J-361D01*
G02X12605Y80265I-682J-1225D01*
G03X12658Y79649I280J-286D01*
G37*
G36*
G01X1518409Y78143D02*
G02X1518368Y79500I-1247J641D01*
G03X1519067Y79521I344J204D01*
G02X1519077Y79539I1230J-672D01*
G03X1518914Y80079I-353J188D01*
G02X1520817Y80654I666J1234D01*
G03X1520980Y80114I353J-188D01*
G02X1519108Y78164I-666J-1234D01*
G03X1518409Y78143I-344J-204D01*
G37*
G36*
G01X-10313Y78490D02*
G02X-12501Y78378I-1139J818D01*
G03X-13089Y78389I-299J-266D01*
G02X-15075Y78348I-1013J969D01*
G03X-15629I-277J-288D01*
G02X-17612Y80331I-973J1010D01*
G03Y80885I-288J277D01*
G02X-15629Y82868I1010J973D01*
G03X-15075I277J288D01*
G02X-13053Y82788I973J-1010D01*
G03X-12465Y82777I299J266D01*
G02X-10342Y82665I1013J-969D01*
G03X-9701Y82676I316J244D01*
G02X-9678Y82707I1137J-820D01*
G03X-9733Y83251I-318J243D01*
G02X-7669Y85121I922J1057D01*
G03X-7026Y85109I326J232D01*
G02X-4846Y83347I1114J-852D01*
G03X-4835Y82814I304J-260D01*
G02X-4878Y80857I-1025J-956D01*
G03X-4894Y80302I280J-286D01*
G02X-6954Y78400I-1036J-944D01*
G03X-7538I-292J-273D01*
G02X-9672Y78501I-1024J958D01*
G03X-10313Y78490I-316J-244D01*
G37*
G36*
G01X733908Y81859D02*
G02X733868Y83450I-1174J766D01*
G03X734526Y83467I323J236D01*
G02X734566Y81876I1174J-766D01*
G03X733908Y81859I-323J-236D01*
G37*
G36*
G01X99998Y84565D02*
G02X98747Y83325I142J-1395D01*
G03X98122Y83698I-398J44D01*
G02X99631Y85193I-3439J4980D01*
G03X99998Y84565I327J-230D01*
G37*
G36*
G01X1574210Y83318D02*
G02X1574165Y84982I-1150J802D01*
G03X1574809Y85000I315J246D01*
G02X1574854Y83336I1150J-802D01*
G03X1574210Y83318I-315J-246D01*
G37*
G36*
G01X648982Y84439D02*
G02X646223Y84462I-1382J-239D01*
G03X645912Y84928I-393J74D01*
G02X645190Y87273I288J1372D01*
G03Y87827I-288J277D01*
G02X647367Y89577I1010J972D01*
G03X648033I333J222D01*
G02X648721Y90117I1166J-778D01*
G03X648943Y90668I-137J376D01*
G02X648914Y90733I1266J604D01*
G03X648270Y90866I-368J-157D01*
G02X646161Y91070I-966J1016D01*
G03X645628Y91181I-326J-231D01*
G02X646047Y93194I-724J1201D01*
G03X646580Y93083I326J231D01*
G02X648594Y92431I724J-1201D01*
G03X649238Y92298I368J157D01*
G02X651486Y91850I966J-1016D01*
G03X652063Y91672I366J162D01*
G02X651522Y89914I741J-1190D01*
G03X650945Y90092I-366J-162D01*
G02X650683Y89965I-739J1191D01*
G03X650461Y89414I137J-376D01*
G02X650210Y87827I-1261J-614D01*
G03Y87273I288J-277D01*
G02X649337Y84905I-1010J-973D01*
G03X648982Y84439I39J-398D01*
G37*
G36*
G01X1318622Y84134D02*
G02X1316250Y85529I-1322J466D01*
G03X1316227Y86084I-299J266D01*
G02X1316228Y88114I968J1015D01*
G03X1316252Y88669I-275J290D01*
G02X1318267Y88584I1049J931D01*
G03X1318243Y88029I275J-290D01*
G02X1318245Y86169I-1048J-931D01*
G03X1318268Y85614I299J-266D01*
G02X1318278Y85605I-933J-1047D01*
G03X1318615Y85717I140J143D01*
G02X1319222Y84334I1385J-217D01*
G03X1318622Y84134I-222J-333D01*
G37*
G36*
G01X768798Y85914D02*
G02X768120Y84453I702J-1214D01*
G03X767526Y84729I-394J-70D01*
G02X765913Y84877I-702J1214D01*
G03X765271Y84690I-260J-304D01*
G02X764841Y86166I-1341J410D01*
G03X765483Y86353I260J304D01*
G02X768204Y86190I1341J-410D01*
G03X768798Y85914I394J70D01*
G37*
G36*
G01X1758640Y84149D02*
G02X1758460Y85705I-1245J644D01*
G03X1759119Y85781I304J260D01*
G02X1759299Y84225I1245J-644D01*
G03X1758640Y84149I-304J-260D01*
G37*
G36*
G01X714182Y87090D02*
G02X712274Y86956I-882J-1090D01*
G03X712233Y87539I-293J272D01*
G02X714330Y89329I882J1090D01*
G03X715030Y89341I347J199D01*
G02X715053Y87983I1238J-658D01*
G03X714353Y87971I-347J-199D01*
G02X714141Y87673I-1239J657D01*
G03X714182Y87090I293J-272D01*
G37*
G36*
G01X707312Y87073D02*
G02X704606Y86976I-1340J-413D01*
G03X704134Y87458I-389J91D01*
G02X705211Y88514I-289J1372D01*
G03X705683Y88032I389J-91D01*
G02X705688Y88033I277J-1374D01*
G03X705989Y88542I-81J392D01*
G02X707613Y87582I1340J413D01*
G03X707312Y87073I81J-392D01*
G37*
G36*
G01X1676511Y87846D02*
G02X1676437Y86108I1062J-916D01*
G03X1675811Y86134I-323J-235D01*
G02X1675885Y87872I-1062J916D01*
G03X1676511Y87846I323J235D01*
G37*
G36*
G01X7750Y87098D02*
G02X7648Y88832I-1150J802D01*
G03X8275Y88869I299J265D01*
G02X10398Y89077I1150J-802D01*
G03X10952I277J288D01*
G02Y87057I973J-1010D01*
G03X10398I-277J-288D01*
G02X8377Y87135I-973J1010D01*
G03X7750Y87098I-299J-265D01*
G37*
G36*
G01X1312558Y92415D02*
G02X1310554Y92409I-999J-984D01*
G03X1310552Y92968I-287J278D01*
G02X1310472Y93057I1002J981D01*
G03X1310152Y93039I-153J-128D01*
G02X1308161Y94950I-1168J775D01*
G03X1308159Y95600I-234J324D01*
G02X1309794Y95606I813J1142D01*
G03X1309796Y94956I234J-324D01*
G02X1309929Y94848I-815J-1140D01*
G03X1310499Y94879I270J295D01*
G02X1312556Y92974I1052J-927D01*
G03X1312558Y92415I287J-278D01*
G37*
G36*
G01X1377332Y92806D02*
G02X1377230Y91313I1132J-827D01*
G03X1376554Y91358I-352J-190D01*
G02X1376656Y92853I-1142J829D01*
G03X1377332Y92806I353J189D01*
G37*
G36*
G01X1455416Y93465D02*
G02X1454081Y92667I-69J-1400D01*
G03X1453740Y93239I-361J172D01*
G02X1455075Y94037I69J1400D01*
G03X1455416Y93465I361J-172D01*
G37*
G36*
G01X692056Y93537D02*
G02X691687Y92008I944J-1037D01*
G03X691044Y92163I-374J-141D01*
G02X691413Y93692I-944J1037D01*
G03X692056Y93537I374J141D01*
G37*
G36*
G01X110302Y92129D02*
G02X110107Y93703I-1245J645D01*
G03X110762Y93784I300J265D01*
G02X110957Y92210I1245J-645D01*
G03X110302Y92129I-300J-265D01*
G37*
G36*
G01X733219Y93291D02*
G02X732024Y94187I-1309J-501D01*
G03X732431Y94729I33J399D01*
G02X733626Y93833I1309J501D01*
G03X733219Y93291I-33J-399D01*
G37*
G36*
G01X1919149Y94521D02*
G02X1917153Y94597I-1035J-945D01*
G03X1917174Y95158I-274J291D01*
G02X1917252Y97127I1036J945D01*
G03X1917206Y97748I-273J292D01*
G02X1918960Y97878I796J1154D01*
G03X1919006Y97257I273J-292D01*
G02X1919170Y95082I-796J-1154D01*
G03X1919149Y94521I274J-291D01*
G37*
G36*
G01X1296358Y95487D02*
G02X1294804I-777J-1167D01*
G03Y96153I-222J333D01*
G02X1296358I777J1167D01*
G03Y95487I222J-333D01*
G37*
G36*
G01X1693483Y93884D02*
G02X1693432Y95418I-1198J728D01*
G03X1694102Y95440I328J229D01*
G02X1696313Y95681I1198J-728D01*
G03X1696868Y95659I289J277D01*
G02X1696787Y93643I932J-1047D01*
G03X1696232Y93665I-289J-277D01*
G02X1694153Y93906I-932J1047D01*
G03X1693483Y93884I-328J-229D01*
G37*
G36*
G01X1363012Y95261D02*
G02X1360588Y96453I-1378J258D01*
G03Y96985I-298J266D01*
G02X1362680I1046J934D01*
G03Y96453I298J-266D01*
G02X1362959Y95976I-1047J-932D01*
G03X1363342Y96091I189J64D01*
G02X1363693Y95465I1358J350D01*
G03X1363012Y95261I-288J-278D01*
G37*
G36*
G01X1573433Y96756D02*
G02X1571776Y96784I-848J-1117D01*
G03X1571787Y97429I-231J327D01*
G02X1573444Y97401I848J1117D01*
G03X1573433Y96756I231J-327D01*
G37*
G36*
G01X1745442Y96580D02*
G02X1745127Y95325I1049J-930D01*
G03X1744447Y95507I-389J-93D01*
G02X1743673Y97690I-947J893D01*
G03X1744111Y98196I53J397D01*
G02X1745191Y97260I1253J354D01*
G03X1744753Y96754I-53J-397D01*
G02X1744757Y96741I-1242J-389D01*
G03X1745442Y96580I386J104D01*
G37*
G36*
G01X1289548Y96543D02*
G02Y98097I-1167J777D01*
G03X1290214I333J222D01*
G02Y96543I1167J-777D01*
G03X1289548I-333J-222D01*
G37*
G36*
G01X1945567Y98870D02*
G02X1945553Y97453I1203J-720D01*
G03X1944863Y97460I-347J-199D01*
G02X1944877Y98877I-1203J720D01*
G03X1945567Y98870I347J199D01*
G37*
G36*
G01X1269667Y101323D02*
G02X1267570Y103149I-1167J777D01*
G03X1267592Y103726I-266J299D01*
G02X1269724Y105538I1008J975D01*
G03X1270366I321J239D01*
G02X1272465Y103692I1124J-839D01*
G03X1272467Y103115I278J-288D01*
G02X1270333Y101323I-967J-1015D01*
G03X1269667I-333J-222D01*
G37*
G36*
G01X1875618Y103538D02*
G02X1874255Y104598I-1360J-342D01*
G03X1874641Y105096I-2J400D01*
G02X1876004Y104036I1360J342D01*
G03X1875618Y103538I2J-400D01*
G37*
G36*
G01X74915Y103760D02*
G02Y106240I-2115J1240D01*
G03X75606I346J202D01*
G02X79837Y106239I2115J-1240D01*
G03X80527I345J202D01*
G02X84758Y106240I2116J-1239D01*
G03X85449I345J202D01*
G02X89679I2115J-1240D01*
G03X90370I346J202D01*
G02X94600I2115J-1240D01*
G03X95291I345J202D01*
G02X99522Y106239I2115J-1240D01*
G03X100212I345J202D01*
G02X104443Y106240I2116J-1239D01*
G03X105134I345J202D01*
G02Y103760I2115J-1240D01*
G03X104443I-345J-202D01*
G02X100212Y103761I-2115J1240D01*
G03X99522I-345J-202D01*
G02X95291Y103760I-2116J1239D01*
G03X94600I-345J-202D01*
G02X90370I-2115J1240D01*
G03X89679I-345J-202D01*
G02X85449I-2115J1240D01*
G03X84758I-345J-202D01*
G02X80527Y103761I-2115J1240D01*
G03X79837I-345J-202D01*
G02X75606Y103760I-2116J1239D01*
G03X74915I-345J-202D01*
G37*
G36*
G01X1345919Y105559D02*
G02X1344470Y105798I-919J-1059D01*
G03X1344581Y106470I-151J370D01*
G02X1346030Y106231I919J1059D01*
G03X1345919Y105559I151J-370D01*
G37*
G36*
G01X121118Y107644D02*
G02X119537Y107824I-921J-1057D01*
G03X119612Y108478I-188J353D01*
G02X121193Y108298I921J1057D01*
G03X121118Y107644I188J-353D01*
G37*
G36*
G01X1392517Y107705D02*
G02X1392488Y109327I-1158J791D01*
G03X1393140Y109339I322J237D01*
G02X1393502Y109702I1157J-792D01*
G03X1393504Y110359I-227J329D01*
G02X1395106Y110352I806J1147D01*
G03X1395104Y109695I227J-329D01*
G02X1393169Y107717I-806J-1147D01*
G03X1392517Y107705I-322J-237D01*
G37*
G36*
G01X1452447Y110885D02*
G02X1451038Y110235I-215J-1385D01*
G03X1450758Y110840I-341J210D01*
G02X1452167Y111490I215J1385D01*
G03X1452447Y110885I341J-210D01*
G37*
G36*
G01X1512424Y120143D02*
G02X1515446Y120153I1511J0D01*
G01Y116258D01*
X1515437Y116174D01*
G02X1514779Y115089I-1502J169D01*
G03X1514753Y114445I224J-332D01*
G02X1513046Y114477I-874J-1096D01*
G03X1513044Y115122I-237J322D01*
G02X1512424Y116343I892J1221D01*
G01Y120143D01*
G37*
G36*
G01X1258565Y115056D02*
G02X1257135I-715J-1206D01*
G03Y115744I-204J344D01*
G02X1258565I715J1206D01*
G03Y115056I204J-344D01*
G37*
G36*
G01X619388Y115330D02*
G02X618655Y114188I666J-1234D01*
G03X618066Y114566I-399J26D01*
G02X618799Y115708I-666J1234D01*
G03X619388Y115330I399J-26D01*
G37*
G36*
G01X1286893Y117099D02*
G02X1285339I-777J-1167D01*
G03Y117765I-222J333D01*
G02X1286893I777J1167D01*
G03Y117099I222J-333D01*
G37*
G36*
G01X1398444Y117893D02*
G02X1397340Y117114I156J-1393D01*
G03X1396936Y117687I-360J175D01*
G02X1398040Y118466I-156J1393D01*
G03X1398444Y117893I360J-175D01*
G37*
G36*
G01X1554838Y121420D02*
G02X1554273Y122169I-1337J-421D01*
G03X1554545Y122454I111J167D01*
G02X1554398Y122705I1130J830D01*
G03X1553883Y122911I-364J-164D01*
G02X1554631Y124787I-530J1298D01*
G03X1555146Y124581I364J164D01*
G02X1556219Y124576I530J-1298D01*
G03X1556757Y124830I155J369D01*
G02X1557557Y123134I1343J-403D01*
G03X1557019Y122880I-155J-369D01*
G02X1555321Y121927I-1343J403D01*
G03X1554838Y121420I-102J-387D01*
G37*
G36*
G01X1928184Y121747D02*
G02X1926314Y122480I-1292J-544D01*
G03X1926518Y123000I-165J365D01*
G02X1926888Y124600I1292J544D01*
G03X1926912Y125180I-263J301D01*
G02X1927962Y127557I1006J976D01*
G03X1928366Y128041I13J400D01*
G02X1928815Y129394I1370J296D01*
G03X1928820Y129994I-262J302D01*
G02X1930677Y129980I936J1043D01*
G03X1930672Y129380I262J-302D01*
G02X1929692Y126936I-936J-1043D01*
G03X1929288Y126452I-13J-400D01*
G02X1928840Y125100I-1370J-296D01*
G03X1928816Y124520I263J-301D01*
G02X1928388Y122267I-1006J-976D01*
G03X1928184Y121747I165J-365D01*
G37*
G36*
G01X1401422Y122341D02*
G02X1399879Y122837I-1122J-841D01*
G03X1400078Y123459I-121J381D01*
G02X1399817Y124532I1122J841D01*
G03X1399418Y124998I-394J66D01*
G02X1400783Y126168I-18J1402D01*
G03X1401182Y125702I394J-66D01*
G02X1401621Y122963I18J-1402D01*
G03X1401422Y122341I121J-381D01*
G37*
G36*
G01X1392867Y122173D02*
G02X1390923Y124117I-1167J777D01*
G03Y124783I-222J333D01*
G02Y127117I777J1167D01*
G03Y127783I-222J333D01*
G02X1392867Y129727I777J1167D01*
G03X1393533I333J222D01*
G02X1395477Y127783I1167J-777D01*
G03Y127117I222J-333D01*
G02Y124783I-777J-1167D01*
G03Y124117I222J-333D01*
G02X1393533Y122173I-777J-1167D01*
G03X1392867I-333J-222D01*
G37*
G36*
G01X1525319Y122826D02*
G02X1524803Y124449I-1319J474D01*
G03X1525409Y124642I229J328D01*
G02X1525925Y123019I1319J-474D01*
G03X1525319Y122826I-229J-328D01*
G37*
G36*
G01X3938Y126754D02*
G03X5205Y127157I-2J2199D01*
G02X9264Y125823I1488J-2314D01*
G03X10004Y125805I374J143D01*
G02Y123881I2201J-962D01*
G03X9264Y123863I-366J-161D01*
G02X5221Y122519I-2571J980D01*
G03X3967Y122932I-1283J-1786D01*
G01X3936D01*
G03X2669Y122529I2J-2199D01*
G02X2653Y127167I-1488J2314D01*
G03X3907Y126754I1283J1786D01*
G01X3938D01*
G37*
G36*
G01X1864351Y125131D02*
G02X1864331Y123808I1226J-680D01*
G03X1863626Y123819I-355J-183D01*
G02X1863646Y125142I-1226J680D01*
G03X1864351Y125131I355J183D01*
G37*
G36*
G01X1857797Y127786D02*
G02X1856243I-777J-1167D01*
G03Y128452I-222J333D01*
G02X1857797I777J1167D01*
G03Y127786I222J-333D01*
G37*
G36*
G01X1513634Y127666D02*
G02X1513388Y125945I966J-1016D01*
G03X1512766Y126034I-346J-201D01*
G02X1513012Y127755I-966J1016D01*
G03X1513634Y127666I346J201D01*
G37*
G36*
G01X1473905Y130098D02*
G02X1472295I-805J-1148D01*
G03Y130752I-230J327D01*
G02X1473905I805J1148D01*
G03Y130098I230J-327D01*
G37*
G36*
G01X1861800Y131977D02*
G02X1860194Y131952I-785J-1162D01*
G03X1860184Y132607I-234J324D01*
G02X1859998Y134780I785J1162D01*
G03Y135358I-277J289D01*
G02X1861940I971J1011D01*
G03Y134780I277J-289D01*
G02X1861790Y132632I-971J-1011D01*
G03X1861800Y131977I234J-324D01*
G37*
G36*
G01X1531353Y133302D02*
G02X1530076Y134073I-1252J-631D01*
G03X1530426Y134653I-7J400D01*
G02X1530308Y135583I1252J631D01*
G03X1529813Y136054I-391J85D01*
G02X1530819Y137109I-364J1354D01*
G03X1531314Y136638I391J-85D01*
G02X1531703Y133882I364J-1354D01*
G03X1531353Y133302I7J-400D01*
G37*
G36*
G01X1324193Y132546D02*
G02Y134100I-1167J777D01*
G03X1324859I333J222D01*
G02Y132546I1167J-777D01*
G03X1324193I-333J-222D01*
G37*
G36*
G01X1262697Y134362D02*
G02X1262517Y132923I1101J-868D01*
G03X1261838Y133008I-365J-163D01*
G02X1262018Y134447I-1101J868D01*
G03X1262697Y134362I365J163D01*
G37*
G36*
G01X1590927Y135783D02*
G02X1588569Y134355I-1047J-932D01*
G03X1588067Y134592I-374J-142D01*
G02X1588931Y136417I-447J1329D01*
G03X1589433Y136180I374J142D01*
G02X1589549Y136213I441J-1331D01*
G03X1589753Y136868I-95J389D01*
G02X1591850Y138729I1047J932D01*
G03X1592450I300J265D01*
G02Y136871I1050J-929D01*
G03X1591850I-300J-265D01*
G02X1591131Y136438I-1050J929D01*
G03X1590927Y135783I95J-389D01*
G37*
G36*
G01X1568792Y137816D02*
G02X1567154Y137824I-825J-1134D01*
G03X1567157Y138473I-232J326D01*
G02X1568795Y138465I825J1134D01*
G03X1568792Y137816I232J-326D01*
G37*
G36*
G01X1513514Y139046D02*
G02X1513185Y137327I911J-1065D01*
G03X1512571Y137444I-354J-187D01*
G02X1512900Y139163I-911J1065D01*
G03X1513514Y139046I354J187D01*
G37*
G36*
G01X1952235Y142296D02*
G02X1950569Y141828I-535J-1296D01*
G03X1950399Y142434I-323J236D01*
G02X1952065Y142902I535J1296D01*
G03X1952235Y142296I323J-236D01*
G37*
G36*
G01X1240805Y142936D02*
G02X1239229Y142929I-783J-1163D01*
G03X1239227Y143591I-226J330D01*
G02X1240803Y143598I783J1163D01*
G03X1240805Y142936I226J-330D01*
G37*
G36*
G01X1822623Y142854D02*
G02X1822532Y144188I-1275J583D01*
G03X1823234Y144236I338J214D01*
G02X1823325Y142902I1275J-583D01*
G03X1822623Y142854I-338J-214D01*
G37*
G36*
G01X1937319Y144841D02*
G02X1935737Y145341I-1132J-828D01*
G03X1935922Y145968I-128J379D01*
G02X1935778Y146188I1180J929D01*
G03X1935109Y146242I-352J-190D01*
G02X1935210Y147808I-1109J858D01*
G03X1935880Y147776I345J202D01*
G02X1937528Y145460I1220J-876D01*
G03X1937319Y144841I114J-383D01*
G37*
G36*
G01X1542460Y150283D02*
G02X1540828Y150010I-629J-1253D01*
G03X1540722Y150647I-286J280D01*
G02X1542354Y150920I629J1253D01*
G03X1542460Y150283I286J-280D01*
G37*
G36*
G01X1715223Y148268D02*
G02Y149632I-1109J682D01*
G03X1715905I341J209D01*
G02Y148268I1109J-682D01*
G03X1715223I-341J-209D01*
G37*
G36*
G01X1914609Y148685D02*
G02X1914445Y150306I-1217J696D01*
G03X1915093Y150372I300J264D01*
G02X1917581Y150267I1217J-696D01*
G03X1918286Y150228I363J169D01*
G02X1918213Y148909I1198J-728D01*
G03X1917508Y148948I-363J-169D01*
G02X1915257Y148751I-1198J728D01*
G03X1914609Y148685I-300J-264D01*
G37*
G36*
G01X1578563Y150675D02*
G02X1577117Y150760I-793J-1156D01*
G03X1577157Y151444I-186J354D01*
G02X1576957Y153590I793J1156D01*
G03X1576901Y154201I-283J282D01*
G02X1578693Y154363I799J1152D01*
G03X1578749Y153752I283J-282D01*
G02X1578603Y151359I-799J-1152D01*
G03X1578563Y150675I186J-354D01*
G37*
G36*
G01X1829274Y151006D02*
G02X1827889Y151287I-933J-1046D01*
G03X1828026Y151964I-129J379D01*
G02X1829411Y151683I933J1046D01*
G03X1829274Y151006I129J-379D01*
G37*
G36*
G01X1906106Y151138D02*
G02X1904426Y151404I-1014J-968D01*
G03X1904526Y152032I-190J352D01*
G02X1906206Y151766I1014J968D01*
G03X1906106Y151138I190J-352D01*
G37*
G36*
G01X1493400Y154196D02*
G02X1491916Y153632I-331J-1362D01*
G03X1491682Y154248I-329J227D01*
G02X1493166Y154812I331J1362D01*
G03X1493400Y154196I329J-227D01*
G37*
G36*
G01X1263621Y155695D02*
G02X1263522Y154039I1079J-895D01*
G03X1262879Y154078I-336J-217D01*
G02X1262978Y155734I-1079J895D01*
G03X1263621Y155695I336J217D01*
G37*
G36*
G01X1808218Y163430D02*
G02X1806662I-778J-1400D01*
G03Y164130I-194J350D01*
G02Y166930I778J1400D01*
G03Y167630I-194J350D01*
G02X1808218I778J1400D01*
G03Y166930I194J-350D01*
G02Y164130I-778J-1400D01*
G03Y163430I194J-350D01*
G37*
G36*
G01X-14373Y161787D02*
G02X-14902Y163024I-1395J135D01*
G03X-14256Y163300I248J315D01*
G02X-13727Y162063I1395J-135D01*
G03X-14373Y161787I-248J-315D01*
G37*
G36*
G01X1455114Y164296D02*
G02X1453485Y164634I-1044J-936D01*
G03X1453616Y165264I-167J363D01*
G02X1455245Y164926I1044J936D01*
G03X1455114Y164296I167J-363D01*
G37*
G36*
G01X1929290Y171119D02*
G02X1929132Y169372I1010J-972D01*
G03X1928510Y169428I-333J-221D01*
G02X1928668Y171175I-1010J972D01*
G03X1929290Y171119I333J221D01*
G37*
G36*
G01X1452032Y171551D02*
G02X1450714Y171560I-667J-1233D01*
G03X1450719Y172266I-185J354D01*
G02X1450374Y174469I667J1233D01*
G03X1450369Y175027I-289J276D01*
G02X1450089Y176595I996J987D01*
G03X1449904Y177118I-364J165D01*
G02X1451808Y177791I628J1254D01*
G03X1451993Y177268I364J-165D01*
G02X1452377Y175044I-628J-1254D01*
G03X1452382Y174486I289J-276D01*
G02X1452037Y172257I-996J-987D01*
G03X1452032Y171551I185J-354D01*
G37*
G36*
G01X1675688Y171990D02*
G02X1675669Y173359I-1233J668D01*
G03X1676367Y173368I346J200D01*
G02X1676386Y171999I1233J-668D01*
G03X1675688Y171990I-346J-200D01*
G37*
G36*
G01X1929349Y174614D02*
G02X1927318Y176518I-1131J829D01*
G03X1927325Y177125I-257J307D01*
G02X1929149Y177104I924J1054D01*
G03X1929142Y176497I257J-307D01*
G02X1929302Y176332I-923J-1055D01*
G03X1929934Y176349I309J253D01*
G02X1930489Y176798I1130J-830D01*
G03X1930617Y177437I-164J365D01*
G02X1932215Y177118I1022J959D01*
G03X1932087Y176479I164J-365D01*
G02X1929981Y174631I-1022J-959D01*
G03X1929349Y174614I-309J-253D01*
G37*
G36*
G01X1720013Y177316D02*
G02X1718316Y177397I-913J-1316D01*
G03X1718371Y178058I-195J349D01*
G02X1720021Y177979I879J1092D01*
G03X1720013Y177316I220J-334D01*
G37*
G36*
G01X1752390Y178036D02*
X1757391D01*
G02X1758902Y176535I0J-1512D01*
G01Y176440D01*
X1758892Y176356D01*
G02X1757390Y175014I-1502J169D01*
G01X1752390D01*
G02X1751337Y175442I1J1511D01*
G03X1750706Y175345I-279J-287D01*
G02X1750451Y177213I-1411J759D01*
G03X1751086Y177288I289J276D01*
G02X1752390Y178036I1304J-763D01*
G37*
G36*
G01X1884675Y177325D02*
G02X1883084Y177255I-745J-1188D01*
G03X1883055Y177912I-242J318D01*
G02X1884957Y179892I745J1188D01*
G03X1885534Y179803I330J226D01*
G02X1885243Y177908I866J-1103D01*
G03X1884666Y177997I-330J-226D01*
G02X1884646Y177982I-851J1114D01*
G03X1884675Y177325I242J-318D01*
G37*
G36*
G01X63421Y177506D02*
G02X62786Y176279I766J-1174D01*
G03X62168Y176599I-400J-15D01*
G02X62803Y177826I-766J1174D01*
G03X63421Y177506I400J15D01*
G37*
G36*
G01X1489739Y177922D02*
G02X1488381Y177890I-650J-1242D01*
G03X1488364Y178590I-202J345D01*
G02X1489722Y178622I650J1242D01*
G03X1489739Y177922I202J-345D01*
G37*
G36*
G01X1227947Y178203D02*
G02X1226003Y180147I-1167J777D01*
G03Y180813I-222J333D01*
G02X1225919Y183086I777J1167D01*
G03X1225948Y183692I-246J315D01*
G02X1227775Y183602I966J1016D01*
G03X1227746Y182996I246J-315D01*
G02X1227947Y182757I-966J-1016D01*
G03X1228613I333J222D01*
G02X1230947I1167J-777D01*
G03X1231613I333J222D01*
G02X1233557Y180813I1167J-777D01*
G03Y180147I222J-333D01*
G02X1231613Y178203I-777J-1167D01*
G03X1230947I-333J-222D01*
G02X1228613I-1167J777D01*
G03X1227947I-333J-222D01*
G37*
G36*
G01X1597025Y179619D02*
G02Y180981I-1225J681D01*
G03X1597725I350J194D01*
G02Y179619I1225J-681D01*
G03X1597025I-350J-194D01*
G37*
G36*
G01X1855682Y182846D02*
G02X1854144Y182808I-740J-1191D01*
G03X1854128Y183476I-228J329D01*
G02X1855666Y183514I740J1191D01*
G03X1855682Y182846I228J-329D01*
G37*
G36*
G01X87704Y182904D02*
G02X86355Y182989I-752J-1183D01*
G03X86399Y183689I-170J362D01*
G02X87748Y183604I752J1183D01*
G03X87704Y182904I170J-362D01*
G37*
G36*
G01X767754Y183850D02*
G02X765216Y182837I-1386J-214D01*
G03X764664Y182940I-328J-229D01*
G02X762508Y184389I-783J1163D01*
G03X762239Y184851I-391J81D01*
G02X761777Y185103I428J1335D01*
G03X761242Y185079I-254J-309D01*
G02X759160Y186949I-984J999D01*
G03X759122Y187489I-313J249D01*
G02X759037Y187575I954J1028D01*
G03X758734Y187570I-149J-133D01*
G02X756760Y187384I-1080J894D01*
G03X756226Y187363I-255J-308D01*
G02X754226Y187408I-978J1005D01*
G03X753662Y187428I-292J-273D01*
G02X751706Y187475I-954J1027D01*
G03X751142Y187482I-286J-280D01*
G02X749159Y187515I-975J1008D01*
G03X748561Y187488I-287J-278D01*
G02X746453Y187402I-1092J880D01*
G03X745889Y187417I-290J-276D01*
G02X743856Y187534I-961J1021D01*
G03X743227Y187511I-305J-258D01*
G02X741097Y187344I-1136J822D01*
G03X740491Y187298I-283J-282D01*
G02X737962Y188013I-1132J827D01*
G03X737509Y188377I-399J-32D01*
G02X737404Y188367I-185J1389D01*
G03X737028Y187967I24J-399D01*
G02X734269Y187614I-1402J-2D01*
G03X733811Y187908I-387J-100D01*
G02X732641Y188233I-247J1380D01*
G03X732106Y188226I-264J-301D01*
G02X732078Y190311I-951J1030D01*
G03X732613Y190318I264J301D01*
G02X734921Y189639I951J-1030D01*
G03X735379Y189345I387J100D01*
G02X735541Y189364I244J-1380D01*
G03X735917Y189764I-24J399D01*
G02X736450Y190866I1402J2D01*
G03X736498Y191449I-248J314D01*
G02X738938Y192406I1038J943D01*
G03X739405Y192016I400J4D01*
G02X740525Y189546I236J-1382D01*
G03X740463Y188989I253J-310D01*
G02X740499Y188941I-1103J-865D01*
G03X740840Y188967I163J116D01*
G02X743163Y189237I1251J-634D01*
G03X743792Y189260I305J258D01*
G02X745944Y189404I1136J-822D01*
G03X746508Y189389I290J276D01*
G02X748477Y189343I961J-1021D01*
G03X749075Y189370I287J278D01*
G02X751169Y189470I1091J-880D01*
G03X751733Y189463I286J280D01*
G02X753730Y189415I975J-1008D01*
G03X754294Y189395I292J273D01*
G02X756142Y189448I954J-1027D01*
G03X756676Y189469I255J308D01*
G02X758581Y189516I978J-1005D01*
G03X759120Y189526I264J300D01*
G02X760987Y189580I964J-1018D01*
G03X761531Y189606I258J306D01*
G02X763513Y189628I1002J-980D01*
G03X764062Y189619I279J286D01*
G02X766074Y189493I945J-1036D01*
G03X766622Y189435I304J259D01*
G02X768495Y187360I854J-1112D01*
G03X768543Y186768I291J-274D01*
G02X768047Y184298I-851J-1114D01*
G03X767754Y183850I102J-387D01*
G37*
G36*
G01X1643138Y183981D02*
G02X1640433Y184087I-1338J419D01*
G03X1639869Y184358I-390J-89D01*
G02X1640658Y185686I-611J1262D01*
G03X1640976Y185534I200J10D01*
G02X1641128Y185630I823J-1135D01*
G03X1641274Y186196I-192J351D01*
G02X1643844Y187149I1183J752D01*
G03X1644283Y186809I396J58D01*
G02X1643722Y184206I150J-1394D01*
G03X1643138Y183981I-203J-345D01*
G37*
G36*
G01X1703257Y188180D02*
G02X1701704Y188154I-757J-1180D01*
G03X1701693Y188820I-227J329D01*
G02X1703246Y188846I757J1180D01*
G03X1703257Y188180I227J-329D01*
G37*
G36*
G01X1709077Y188435D02*
G02X1708544Y186943I823J-1135D01*
G03X1707923Y187165I-387J-102D01*
G02X1708456Y188657I-823J1135D01*
G03X1709077Y188435I387J102D01*
G37*
G36*
G01X726687Y189694D02*
G02X726618Y188021I1089J-883D01*
G03X725977Y188047I-330J-226D01*
G02X726046Y189720I-1089J883D01*
G03X726687Y189694I330J226D01*
G37*
G36*
G01X1945242Y191496D02*
G02X1943626Y191653I-942J-1296D01*
G03X1943713Y192323I-169J363D01*
G02X1945285Y192170I898J1077D01*
G03X1945242Y191496I192J-351D01*
G37*
G36*
G01X1264031Y192350D02*
G02X1261842Y190662I-951J-1030D01*
G03X1261189Y190740I-354J-187D01*
G02X1258828Y191177I-1049J930D01*
G03X1258177Y191325I-374J-141D01*
G02X1255826Y192116I-967J1015D01*
G03X1255404Y192451I-395J-64D01*
G02X1254628Y192625I-94J1399D01*
G03X1254099Y192497I-196J-349D01*
G02X1251543Y193067I-1169J773D01*
G03X1251134Y193409I-396J-58D01*
G02X1249691Y194909I-45J1401D01*
G03X1249354Y195333I-399J29D01*
G02X1248169Y196692I217J1385D01*
G03X1247777Y197084I-400J-8D01*
G02X1246401Y198520I26J1402D01*
G03X1246021Y198930I-400J11D01*
G02X1244688Y200354I69J1400D01*
G03X1244309Y200760I-400J7D01*
G02X1242987Y202316I71J1400D01*
G03X1242636Y202758I-398J45D01*
G02X1242119Y205375I164J1392D01*
G03X1242207Y206008I-194J350D01*
G02X1241812Y206781I990J993D01*
G03X1241202Y207056I-395J-63D01*
G02X1239442Y209213I-750J1184D01*
G03Y209767I-288J277D01*
G02Y211713I1010J973D01*
G03Y212267I-288J277D01*
G02Y214213I1010J973D01*
G03Y214767I-288J277D01*
G02X1239446Y216717I1010J973D01*
G03X1239457Y217263I-287J279D01*
G02X1241506Y217223I1043J937D01*
G03X1241495Y216677I287J-279D01*
G02X1241462Y214767I-1043J-937D01*
G03Y214213I288J-277D01*
G02Y212267I-1010J-973D01*
G03Y211713I288J-277D01*
G02Y209767I-1010J-973D01*
G03Y209213I288J-277D01*
G02X1241836Y208461I-1011J-972D01*
G03X1242446Y208186I395J63D01*
G02X1244589Y207161I750J-1184D01*
G03X1244992Y206807I397J46D01*
G02X1246416Y205371I22J-1402D01*
G03X1246772Y204964I400J-10D01*
G02X1248021Y203529I-152J-1394D01*
G03X1248392Y203118I400J-12D01*
G02X1248785Y203032I-100J-1398D01*
G03X1249304Y203272I142J374D01*
G02X1252027Y202824I1321J-468D01*
G03X1252405Y202430I400J5D01*
G02X1252469Y202425I-77J-1400D01*
G03X1252908Y202827I39J398D01*
G02X1255088Y204006I1402J13D01*
G03X1255643Y204117I222J333D01*
G02X1256982Y204731I1167J-777D01*
G03X1257426Y205064I49J397D01*
G02X1258739Y206240I1384J-224D01*
G03X1259117Y206684I-20J400D01*
G02X1260386Y208236I1393J156D01*
G03X1260734Y208747I-36J398D01*
G02X1262016Y210541I1346J393D01*
G03X1262382Y211052I-18J399D01*
G02X1265099Y211149I1346J392D01*
G03X1265481Y210665I391J-84D01*
G02X1266852Y209289I-31J-1402D01*
G03X1267244Y208897I400J8D01*
G02X1268620Y207521I-26J-1402D01*
G03X1269012Y207129I400J8D01*
G02X1270388Y205753I-26J-1402D01*
G03X1270780Y205361I400J8D01*
G02X1272156Y203985I-26J-1402D01*
G03X1272548Y203593I400J8D01*
G02X1272678Y200798I-26J-1402D01*
G03X1272325Y200360I45J-398D01*
G02X1270974Y198819I-1395J-140D01*
G03X1270602Y198309I13J-400D01*
G02X1269325Y196523I-1348J-386D01*
G03X1268947Y196079I20J-400D01*
G02X1267382Y194532I-1393J-156D01*
G03X1266941Y194218I-50J-397D01*
G02X1264803Y193336I-1371J292D01*
G03X1264242Y193208I-219J-335D01*
G02X1264022Y192929I-1202J722D01*
G03X1264031Y192350I280J-285D01*
G37*
G36*
G01X706309Y191605D02*
G02X705545Y192886I-1402J32D01*
G03X706127Y193233I182J356D01*
G02X707720Y194589I1402J-33D01*
G03X708135Y195158I54J396D01*
G02X710728Y196211I1264J605D01*
G03X711280Y195978I379J128D01*
G02X712356Y196035I606J-1264D01*
G03X712855Y196250I133J377D01*
G02X715433Y196217I1282J-568D01*
G03X715953Y195999I370J153D01*
G02X715184Y194165I527J-1299D01*
G03X714664Y194383I-370J-153D01*
G02X713667Y194361I-527J1299D01*
G03X713168Y194146I-133J-377D01*
G02X710558Y194266I-1282J568D01*
G03X710006Y194499I-379J-128D01*
G02X709209Y194374I-607J1264D01*
G03X708794Y193805I-54J-396D01*
G02X706891Y191952I-1265J-605D01*
G03X706309Y191605I-182J-356D01*
G37*
G36*
G01X698454Y194415D02*
G02X696900Y194323I-708J-1210D01*
G03X696860Y194987I-242J319D01*
G02X698414Y195079I708J1210D01*
G03X698454Y194415I242J-319D01*
G37*
G36*
G01X98575Y195729D02*
G02X97147Y195683I-675J-1229D01*
G03X97125Y196371I-214J337D01*
G02X97155Y198845I675J1229D01*
G03Y199555I-184J355D01*
G02X98445I645J1245D01*
G03Y198845I184J-355D01*
G02X98553Y196417I-645J-1245D01*
G03X98575Y195729I214J-337D01*
G37*
G36*
G01X1630836Y196158D02*
G02X1630732Y196162I2J1402D01*
G03X1630314Y195670I-29J-399D01*
G02X1629054Y196742I-1364J-326D01*
G03X1629472Y197234I29J399D01*
G02X1632121Y197000I1364J326D01*
G03X1632340Y196724I184J-79D01*
G02X1632363Y196727I193J-1387D01*
G03X1632691Y197196I-65J395D01*
G02X1634296Y196071I1378J258D01*
G03X1633968Y195602I65J-395D01*
G02X1631226Y195666I-1378J-258D01*
G03X1630837Y196158I-389J92D01*
G01X1630836D01*
G37*
G36*
G01X105535Y196906D02*
G02X104105I-715J-1206D01*
G03Y197594I-204J344D01*
G02X105535I715J1206D01*
G03Y196906I204J-344D01*
G37*
G36*
G01X1731771Y195558D02*
G02X1731397Y196835I-1371J292D01*
G03X1732076Y197045I285J281D01*
G02X1733563Y198288I1487J-268D01*
G01X1738564D01*
G02X1740074Y196786I-1J-1512D01*
G01Y196691D01*
X1740065Y196607D01*
G02X1738563Y195264I-1502J168D01*
G01X1733563D01*
G02X1732456Y195747I1J1512D01*
G03X1731771Y195558I-294J-272D01*
G37*
G36*
G01X607489Y199401D02*
G02X605767Y199172I-716J-1205D01*
G03X605684Y199795I-287J279D01*
G02X605006Y201146I716J1205D01*
G03X604573Y201586I-398J41D01*
G02X605847Y202837I-120J1397D01*
G03X606280Y202397I398J-41D01*
G02X607406Y200024I120J-1397D01*
G03X607489Y199401I287J-279D01*
G37*
G36*
G01X799325Y200502D02*
G02X798088Y199804I-24J-1402D01*
G03X797737Y200405I-346J201D01*
G02X798992Y201113I-20J1502D01*
G03X799325Y200502I340J-211D01*
G37*
G36*
G01X1894193Y200047D02*
G02X1893186Y201414I-1402J22D01*
G03X1893698Y201792I112J384D01*
G02X1894569Y203068I1402J-22D01*
G03X1894683Y203737I-152J370D01*
G02X1896145Y203487I932J1048D01*
G03X1896031Y202818I152J-370D01*
G02X1894705Y200425I-931J-1048D01*
G03X1894193Y200047I-112J-384D01*
G37*
G36*
G01X579220Y203377D02*
G02X578123Y202280I277J-1374D01*
G03X577652Y202751I-392J79D01*
G02X578749Y203848I-277J1374D01*
G03X579220Y203377I392J-79D01*
G37*
G36*
G01X1403833Y206100D02*
G02X1402555Y205885I-433J-1334D01*
G03X1402437Y206584I-241J319D01*
G02X1403715Y206799I433J1334D01*
G03X1403833Y206100I241J-319D01*
G37*
G36*
G01X562584Y206877D02*
G02X561487Y205780I277J-1374D01*
G03X561016Y206251I-392J79D01*
G02X562113Y207348I-277J1374D01*
G03X562584Y206877I392J-79D01*
G37*
G36*
G01X1955487Y214076D02*
G03X1955651Y214607I-193J350D01*
G02X1956220Y216466I1250J634D01*
G03Y217166I-194J350D01*
G02X1957582I681J1225D01*
G03Y216466I194J-350D01*
G02X1958147Y214599I-681J-1225D01*
G03X1958308Y214067I356J-183D01*
G02X1959541Y212715I-1418J-2532D01*
G03X1960200Y212606I365J163D01*
G02X1959928Y209839I1690J-1563D01*
G03X1959260Y209861I-341J-209D01*
G02X1957697Y208747I-2371J1673D01*
G01X1957552Y208706D01*
Y204492D01*
X1946598D01*
Y213346D01*
X1954623D01*
G02X1955487Y214076I2269J-1809D01*
G37*
G36*
G01X1330337Y207982D02*
G02X1330256Y209998I-1013J969D01*
G03X1330811Y210020I266J299D01*
G02X1332952Y209883I1013J-969D01*
G03X1333596I322J238D01*
G02Y208219I1128J-832D01*
G03X1332952I-322J-238D01*
G02X1330892Y208004I-1128J832D01*
G03X1330337Y207982I-266J-299D01*
G37*
G36*
G01X1884653Y211688D02*
G02X1882947I-853J-1113D01*
G03Y212323I-243J317D01*
G02X1885092Y213981I853J1113D01*
G03X1885791Y213912I368J155D01*
G02X1885660Y212580I1161J-787D01*
G03X1884961Y212649I-368J-155D01*
G02X1884653Y212323I-1160J788D01*
G03Y211688I243J-318D01*
G37*
G36*
G01X565773Y212929D02*
G02X564656Y211694I278J-1374D01*
G03X564178Y212126I-398J40D01*
G02X565295Y213361I-278J1374D01*
G03X565773Y212929I398J-40D01*
G37*
G36*
G01X174485Y210977D02*
G02X172328Y213045I-1185J923D01*
G03Y213655I-259J305D01*
G02Y215945I972J1145D01*
G03Y216555I-259J305D01*
G02X174603Y218448I972J1145D01*
G03X175233Y218366I346J199D01*
G02X177779Y217570I1067J-1058D01*
G03X178410Y217318I394J70D01*
G02X180485Y217031I890J-1210D01*
G03X181115I315J246D01*
G02Y215185I1185J-923D01*
G03X180485I-315J-246D01*
G02X180272Y214963I-1185J923D01*
G03Y214353I259J-305D01*
G02X178421Y211990I-972J-1145D01*
G03X177791Y211715I-233J-325D01*
G02X175115Y210977I-1491J185D01*
G03X174485I-315J-246D01*
G37*
G36*
G01X1848935Y212284D02*
G02Y213608I-1236J662D01*
G03X1849640I353J189D01*
G02Y212284I1236J-662D01*
G03X1848935I-352J-189D01*
G37*
G36*
G01X116300Y214684D02*
G02X114751Y214669I-763J-1176D01*
G03X114744Y215336I-224J331D01*
G02X116293Y215351I763J1176D01*
G03X116300Y214684I224J-331D01*
G37*
G36*
G01X765908D02*
G02X764359Y214669I-763J-1176D01*
G03X764352Y215336I-224J331D01*
G02X765901Y215351I763J1176D01*
G03X765908Y214684I224J-331D01*
G37*
G36*
G01X1220270Y214898D02*
G02X1218893Y216271I-1402J-29D01*
G03X1219300Y216679I7J400D01*
G02X1219317Y216923I1402J25D01*
G03X1218979Y217097I-198J31D01*
G02X1219396Y218228I-979J1003D01*
G03X1219996Y217919I398J37D01*
G02X1220677Y215306I706J-1211D01*
G03X1220270Y214898I-7J-400D01*
G37*
G36*
G01X1331241Y215723D02*
G02Y217277I-1167J777D01*
G03X1331907I333J222D01*
G02X1334241I1167J-777D01*
G03X1334907I333J222D01*
G02Y215723I1167J-777D01*
G03X1334241I-333J-222D01*
G02X1331907I-1167J777D01*
G03X1331241I-333J-222D01*
G37*
G36*
G01X580354Y218161D02*
G02X579257Y219258I-1374J-277D01*
G03X579728Y219729I79J392D01*
G02X580825Y218632I1374J277D01*
G03X580354Y218161I-79J-392D01*
G37*
G36*
G01X743908Y222185D02*
G02X741579Y220827I-971J-1011D01*
G03X741024Y221091I-388J-99D01*
G02X739426Y221393I-587J1273D01*
G03X738848I-289J-277D01*
G02X736866Y223375I-1011J971D01*
G03Y223953I-277J289D01*
G02X738848Y225935I971J1011D01*
G03X739426I289J277D01*
G02X739696Y226154I1011J-971D01*
G03X739665Y226850I-212J339D01*
G02X741685Y228317I635J1250D01*
G03X742262Y228023I395J62D01*
G02X743690Y225617I635J-1250D01*
G03X743699Y224951I226J-330D01*
G02X743908Y222763I-762J-1177D01*
G03Y222185I277J-289D01*
G37*
G36*
G01X642696Y222427D02*
G02X640504I-1096J-1027D01*
G03Y222973I-292J273D01*
G02Y225027I1096J1027D01*
G03Y225573I-292J273D01*
G02Y227627I1096J1027D01*
G03Y228173I-292J273D01*
G02Y230227I1096J1027D01*
G03Y230773I-292J273D01*
G02X642745Y232772I1096J1027D01*
G03X643355I305J259D01*
G02X645724Y232670I1145J-972D01*
G03X646376I326J232D01*
G02X648824I1224J-870D01*
G03X649476I326J232D01*
G02X651796Y230773I1225J-869D01*
G03Y230227I292J-273D01*
G02Y228173I-1096J-1027D01*
G03Y227627I292J-273D01*
G02X652171Y226905I-1096J-1027D01*
G03X652812Y226673I392J81D01*
G02X652843Y224303I938J-1173D01*
G03X652202Y223987I-241J-319D01*
G02X649476Y223130I-1502J13D01*
G03X648824I-326J-232D01*
G02X646376I-1224J870D01*
G03X645724I-326J-232D01*
G02X643355Y223028I-1224J870D01*
G03X642745I-305J-259D01*
G02X642696Y222973I-1146J971D01*
G03Y222427I292J-273D01*
G37*
G36*
G01X1903999Y226780D02*
G02X1902051Y226789I-979J-1004D01*
G03X1902053Y227364I-277J288D01*
G02X1902167Y229471I979J1004D01*
G03X1902139Y230121I-247J315D01*
G02X1903772Y230191I768J1173D01*
G03X1903800Y229541I247J-315D01*
G02X1904001Y227355I-768J-1173D01*
G03X1903999Y226780I277J-288D01*
G37*
G36*
G01X1398440Y226716D02*
G02X1395924Y225485I-1229J-675D01*
G03X1395407Y225697I-367J-159D01*
G02X1396168Y227553I-526J1300D01*
G03X1396685Y227341I367J159D01*
G02X1397063Y227435I524J-1300D01*
G03X1397371Y228025I-43J398D01*
G02X1399574Y229708I1229J675D01*
G03X1400233Y229871I279J287D01*
G02X1400591Y228427I1332J-436D01*
G03X1399932Y228264I-279J-287D01*
G02X1398748Y227306I-1332J436D01*
G03X1398440Y226716I43J-398D01*
G37*
G36*
G01X602200Y227570D02*
G02X602143Y225908I1100J-870D01*
G03X601500Y225930I-330J-226D01*
G02X601557Y227592I-1100J870D01*
G03X602200Y227570I330J226D01*
G37*
G36*
G01X1279850Y230736D02*
G02X1278675Y229922I99J-1398D01*
G03X1278283Y230488I-363J167D01*
G02X1276858Y232344I-100J1398D01*
G03X1276513Y232873I-378J130D01*
G02X1275240Y234465I115J1397D01*
G03X1274912Y234915I-396J56D01*
G02X1276542Y236101I242J1381D01*
G03X1276870Y235651I396J-56D01*
G02X1277953Y233812I-242J-1381D01*
G03X1278298Y233283I378J-130D01*
G02X1279458Y231302I-115J-1397D01*
G03X1279850Y230736I363J-167D01*
G37*
G36*
G01X1967564Y228788D02*
G02Y230412I-1264J812D01*
G03X1968236I336J216D01*
G02Y228788I1264J-812D01*
G03X1967564I-336J-216D01*
G37*
G36*
G01X1398802Y232142D02*
G02X1398004Y233383I-1402J-24D01*
G03X1398576Y233751I172J361D01*
G02X1399003Y234783I1402J24D01*
G03X1399023Y235337I-278J287D01*
G02X1398664Y236309I1043J937D01*
G03X1398073Y236670I-400J10D01*
G02X1398802Y237865I-673J1230D01*
G03X1399393Y237504I400J-10D01*
G02X1401041Y235266I674J-1230D01*
G03X1401021Y234712I278J-287D01*
G02X1399374Y232510I-1043J-937D01*
G03X1398802Y232142I-172J-361D01*
G37*
G36*
G01X1837228Y234063D02*
G02X1835822Y233596I-328J-1363D01*
G03X1835608Y234241I-307J256D01*
G02X1837014Y234708I328J1363D01*
G03X1837228Y234063I307J-256D01*
G37*
G36*
G01X1735168Y232256D02*
G02X1734900Y233771I-1288J553D01*
G03X1735559Y233888I291J274D01*
G02X1738014Y234111I1288J-554D01*
G03X1738680I333J222D01*
G02X1740447Y234601I1167J-777D01*
G03X1741013Y234900I171J362D01*
G02X1741191Y235395I1385J-219D01*
G03X1741020Y235959I-344J204D01*
G02X1740644Y236215I648J1355D01*
G03X1740093Y236209I-272J-293D01*
G02X1737939Y236267I-1049J1075D01*
G03X1737368Y236286I-295J-270D01*
G02X1735427Y236290I-968J1014D01*
G03X1734873I-277J-288D01*
G02Y238310I-973J1010D01*
G03X1735427I277J288D01*
G02X1737380Y238302I972J-1010D01*
G03X1737951Y238314I280J286D01*
G02X1740068Y238383I1093J-1030D01*
G03X1740619Y238389I272J293D01*
G02X1742718Y238388I1049J-1075D01*
G03X1743273Y238384I280J286D01*
G02X1745454Y238266I1035J-1089D01*
G03X1746068Y238270I305J258D01*
G02X1746081Y236343I1159J-956D01*
G03X1745467Y236339I-305J-258D01*
G02X1744101Y235807I-1159J956D01*
G03X1743680Y235249I-56J-396D01*
G02X1741798Y233414I-1282J-568D01*
G03X1741232Y233115I-171J-362D01*
G02X1738680Y232557I-1385J219D01*
G03X1738014I-333J-222D01*
G02X1735827Y232373I-1167J777D01*
G03X1735168Y232256I-291J-274D01*
G37*
G36*
G01X123238Y235830D02*
G02X121540Y236050I-1008J-1114D01*
G03X121625Y236702I-183J355D01*
G02X123790Y238773I1007J1114D01*
G03X124406I308J255D01*
G02Y236859I1158J-957D01*
G03X123790I-308J-255D01*
G02X123323Y236482I-1158J957D01*
G03X123238Y235830I183J-355D01*
G37*
G36*
G01X1608415Y241546D02*
G02X1607183Y242777I-1566J-336D01*
G03X1607662Y243223I83J391D01*
G02X1608861Y242026I1389J192D01*
G03X1608415Y241546I-55J-396D01*
G37*
G36*
G01X1667018Y243217D02*
G02X1665659Y243210I-673J-1230D01*
G03X1665656Y243909I-196J349D01*
G02X1667015Y243916I673J1230D01*
G03X1667018Y243217I196J-349D01*
G37*
G36*
G01X1682647Y243237D02*
G02X1682508Y241656I1082J-892D01*
G03X1681851Y241714I-348J-196D01*
G02X1680454Y243971I-1082J891D01*
G03X1680674Y244614I-90J390D01*
G02X1682786Y246455I1086J886D01*
G03X1683397Y246484I293J272D01*
G02X1683483Y244676I1112J-853D01*
G03X1682872Y244647I-293J-272D01*
G02X1682075Y244134I-1113J853D01*
G03X1681855Y243491I90J-390D01*
G02X1681990Y243295I-1083J-890D01*
G03X1682647Y243237I348J196D01*
G37*
G36*
G01X128755Y242876D02*
G02X128442Y244539I-1255J625D01*
G03X129069Y244657I269J296D01*
G02X129382Y242994I1255J-625D01*
G03X128755Y242876I-269J-296D01*
G37*
G36*
G01X778282Y242932D02*
G02X778000Y244483I-1282J568D01*
G03X778650Y244601I285J281D01*
G02X778932Y243050I1282J-568D01*
G03X778282Y242932I-285J-281D01*
G37*
G36*
G01X1437365Y245552D02*
G02X1436078Y244616I35J-1402D01*
G03X1435690Y245148I-377J132D01*
G02X1436977Y246084I-35J1402D01*
G03X1437365Y245552I377J-132D01*
G37*
G36*
G01X116289Y246548D02*
G02X114740Y246533I-763J-1176D01*
G03X114733Y247200I-224J331D01*
G02X116282Y247215I763J1176D01*
G03X116289Y246548I224J-331D01*
G37*
G36*
G01X765908Y246684D02*
G02X764359Y246669I-763J-1176D01*
G03X764352Y247336I-224J331D01*
G02X765901Y247351I763J1176D01*
G03X765908Y246684I224J-331D01*
G37*
G36*
G01X849467Y245504D02*
G02X847186Y247454I-1185J923D01*
G03Y248000I-292J273D01*
G02X847224Y250093I1096J1027D01*
G03Y250661I-282J284D01*
G02X846884Y251179I1059J1065D01*
G03X846204Y251289I-373J-146D01*
G02X846448Y252798I-1154J961D01*
G03X847128Y252688I373J146D01*
G02X847186Y252754I1157J-958D01*
G03Y253300I-292J273D01*
G02X849467Y255250I1096J1027D01*
G03X850097I315J246D01*
G02X852467I1185J-923D01*
G03X853097I315J246D01*
G02X855467I1185J-923D01*
G03X856097I315J246D01*
G02X858378Y253300I1185J-923D01*
G03Y252754I292J-273D01*
G02X858340Y250661I-1096J-1027D01*
G03Y250093I282J-284D01*
G02X858378Y248000I-1058J-1066D01*
G03Y247454I292J-273D01*
G02X856097Y245504I-1096J-1027D01*
G03X855467I-315J-246D01*
G02X853097I-1185J923D01*
G03X852467I-315J-246D01*
G02X850097I-1185J923D01*
G03X849467I-315J-246D01*
G37*
G36*
G01X199345Y245528D02*
G02X197277Y247685I-1145J972D01*
G03Y248315I-246J315D01*
G02Y250685I923J1185D01*
G03Y251315I-246J315D01*
G02X197111Y251466I925J1183D01*
G03X196459Y251360I-290J-276D01*
G02X196189Y253034I-1359J640D01*
G03X196841Y253140I290J276D01*
G02X199385Y253423I1359J-640D01*
G03X200015I315J246D01*
G02X202385I1185J-923D01*
G03X203015I315J246D01*
G02X205385I1185J-923D01*
G03X206015I315J246D01*
G02X208123Y251315I1185J-923D01*
G03Y250685I246J-315D01*
G02X207871Y248156I-923J-1185D01*
G03X207772Y247510I179J-358D01*
G02X205722Y245604I-972J-1010D01*
G03X205096Y245591I-308J-255D01*
G02X202794Y245483I-1196J909D01*
G03X202206I-294J-270D01*
G02X199955Y245528I-1106J1017D01*
G03X199345I-305J-259D01*
G37*
G36*
G01X1663900Y249338D02*
G02X1662940Y248226I424J-1336D01*
G03X1662424Y248672I-395J65D01*
G02X1663384Y249784I-424J1336D01*
G03X1663900Y249338I395J-65D01*
G37*
G36*
G01X718606Y249173D02*
G02X718591Y250691I-1186J747D01*
G03X719264Y250697I335J219D01*
G02X721584Y250774I1186J-747D01*
G03X722239Y250786I323J236D01*
G02X724545Y250809I1161J-786D01*
G03X725195Y250805I326J231D01*
G02X725183Y249170I1133J-826D01*
G03X724533Y249174I-326J-231D01*
G02X722266Y249176I-1133J826D01*
G03X721611Y249164I-323J-236D01*
G02X719279Y249179I-1161J786D01*
G03X718606Y249173I-335J-219D01*
G37*
G36*
G01X658864Y249391D02*
G02X658783Y251062I-1164J781D01*
G03X659424Y251093I309J254D01*
G02X659505Y249422I1164J-781D01*
G03X658864Y249391I-309J-254D01*
G37*
G36*
G01X1500777Y249858D02*
G02X1500262Y251528I-1305J512D01*
G03X1500860Y251712I226J330D01*
G02X1501375Y250042I1305J-512D01*
G03X1500777Y249858I-226J-330D01*
G37*
G36*
G01X1588322Y250980D02*
G02X1587633Y252491I-1372J287D01*
G03X1588220Y252759I195J349D01*
G02X1588909Y251248I1372J-287D01*
G03X1588322Y250980I-195J-349D01*
G37*
G36*
G01X1440096Y254445D02*
G02X1438370Y253545I-396J-1345D01*
G03X1438104Y254055I-379J127D01*
G02X1437463Y256344I396J1345D01*
G03X1437308Y256987I-296J269D01*
G02X1438837Y257356I492J1313D01*
G03X1438992Y256713I296J-269D01*
G02X1439830Y254955I-492J-1313D01*
G03X1440096Y254445I379J-127D01*
G37*
G36*
G01X1859705Y253139D02*
G02X1859613Y254436I-1285J561D01*
G03X1860320Y254486I340J210D01*
G02X1862690Y254813I1285J-561D01*
G03X1863289Y254791I309J254D01*
G02X1863220Y252937I1016J-966D01*
G03X1862621Y252959I-309J-254D01*
G02X1860412Y253189I-1016J966D01*
G03X1859705Y253139I-340J-210D01*
G37*
G36*
G01X749809Y253142D02*
G02X749663Y255019I-1109J858D01*
G03X750254Y255065I275J291D01*
G02X752491Y255039I1109J-858D01*
G03X753135I322J238D01*
G02Y253375I1128J-832D01*
G03X752491I-322J-238D01*
G02X750400Y253188I-1128J832D01*
G03X749809Y253142I-275J-291D01*
G37*
G36*
G01X1671347Y255991D02*
G02X1669766Y255613I-525J-1300D01*
G03X1669615Y256247I-301J263D01*
G02X1669027Y256694I525J1300D01*
G03X1668478Y256777I-318J-243D01*
G02X1666532Y258743I-811J1144D01*
G03X1666377Y259340I-324J234D01*
G02X1668103Y259788I591J1271D01*
G03X1668258Y259191I324J-234D01*
G02X1668780Y258773I-590J-1272D01*
G03X1669329Y258690I318J243D01*
G02X1671196Y256625I810J-1144D01*
G03X1671347Y255991I301J-263D01*
G37*
G36*
G01X1621068Y255879D02*
G02X1619424Y255874I-819J-1138D01*
G03X1619422Y256522I-236J323D01*
G02X1621066Y256527I819J1138D01*
G03X1621068Y255879I236J-323D01*
G37*
G36*
G01X1309929Y256611D02*
G02X1309831Y254805I1021J-961D01*
G03X1309221Y254839I-319J-241D01*
G02X1306892Y256305I-1021J961D01*
G03X1306534Y256849I-373J144D01*
G02X1307893Y257745I51J1401D01*
G03X1308251Y257201I373J-144D01*
G02X1309319Y256645I-51J-1401D01*
G03X1309929Y256611I319J241D01*
G37*
G36*
G01X1592584Y258161D02*
G02X1590540Y255962I-985J-1133D01*
G03X1589993Y255978I-282J-284D01*
G02X1587974Y256006I-994J1126D01*
G03X1587428Y256005I-272J-293D01*
G02X1585060Y256418I-1029J1094D01*
G03X1584355Y256433I-357J-181D01*
G02X1582112Y258346I-1308J738D01*
G03X1582118Y258967I-249J313D01*
G02X1584464Y260702I960J1155D01*
G03X1585168Y260639I369J155D01*
G02X1587464Y260914I1262J-815D01*
G03X1588011Y260910I276J290D01*
G02X1590007Y260948I1019J-1103D01*
G03X1590553Y260973I260J304D01*
G02X1592590Y258770I1074J-1050D01*
G03X1592584Y258161I256J-307D01*
G37*
G36*
G01X643632Y262228D02*
G02X641968I-832J-1128D01*
G03Y262872I-238J322D01*
G02X642408Y265346I832J1128D01*
G03X642583Y266008I-112J384D01*
G02X642443Y267787I1008J974D01*
G03X642279Y268382I-328J230D01*
G02X644003Y268856I576J1278D01*
G03X644167Y268261I328J-230D01*
G02X643983Y265637I-576J-1278D01*
G03X643808Y264975I112J-384D01*
G02X643632Y262872I-1008J-975D01*
G03Y262228I238J-322D01*
G37*
G36*
G01X445821Y262562D02*
G02X444136Y262342I-698J-1216D01*
G03X444054Y262972I-282J284D01*
G02X443931Y265325I698J1216D01*
G03X443855Y266017I-234J325D01*
G02X445229Y266168I554J1288D01*
G03X445305Y265476I234J-325D01*
G02X445739Y263192I-553J-1288D01*
G03X445821Y262562I282J-284D01*
G37*
G36*
G01X1087133Y263352D02*
G02X1084941Y263301I-1072J-1052D01*
G03X1084928Y263848I-298J267D01*
G02X1087371Y265514I1072J1052D01*
G03X1088039Y265416I365J163D01*
G02X1088053Y265432I1062J-915D01*
G03X1088031Y265987I-299J266D01*
G02X1090047Y266068I969J1013D01*
G03X1090069Y265513I299J-266D01*
G02X1090267Y265277I-969J-1014D01*
G03X1090933I333J222D01*
G02X1091255Y265619I1167J-777D01*
G03X1091299Y266218I-241J319D01*
G02X1093145Y266081I1001J982D01*
G03X1093101Y265482I241J-319D01*
G02X1090933Y263723I-1001J-982D01*
G03X1090267I-333J-222D01*
G02X1087841Y263883I-1167J777D01*
G03X1087170Y263958I-359J-176D01*
G02X1087120Y263899I-1171J941D01*
G03X1087133Y263352I298J-267D01*
G37*
G36*
G01X440857Y264577D02*
G02X439243Y265001I-1093J-878D01*
G03X439407Y265622I-148J371D01*
G02X441021Y265198I1093J878D01*
G03X440857Y264577I148J-371D01*
G37*
G36*
G01X1065189Y265711D02*
G02X1065123Y263768I1111J-1010D01*
G03X1064513Y263788I-313J-249D01*
G02X1062217Y263876I-1111J1011D01*
G03X1061587I-315J-246D01*
G02X1059113Y264028I-1185J923D01*
G03X1058440Y264049I-343J-206D01*
G02X1056017Y263976I-1238J850D01*
G03X1055387I-315J-246D01*
G02Y265822I-1185J923D01*
G03X1056017I315J246D01*
G02X1058491Y265670I1185J-923D01*
G03X1059164Y265649I343J206D01*
G02X1061587Y265722I1238J-850D01*
G03X1062217I315J246D01*
G02X1064579Y265731I1185J-923D01*
G03X1065189Y265711I313J249D01*
G37*
G36*
G01X392061Y264122D02*
G02Y265676I-1167J777D01*
G03X392727I333J222D01*
G02Y264122I1167J-777D01*
G03X392061I-333J-222D01*
G37*
G36*
G01X398561D02*
G02Y265676I-1167J777D01*
G03X399227I333J222D01*
G02Y264122I1167J-777D01*
G03X398561I-333J-222D01*
G37*
G36*
G01X1041669D02*
G02Y265676I-1167J777D01*
G03X1042335I333J222D01*
G02Y264122I1167J-777D01*
G03X1041669I-333J-222D01*
G37*
G36*
G01X1048169D02*
G02Y265676I-1167J777D01*
G03X1048835I333J222D01*
G02Y264122I1167J-777D01*
G03X1048169I-333J-222D01*
G37*
G36*
G01X451230Y266487D02*
G02X450517Y264930I653J-1241D01*
G03X449941Y265194I-390J-90D01*
G02X450654Y266751I-653J1241D01*
G03X451230Y266487I390J90D01*
G37*
G36*
G01X1096538Y267024D02*
G02X1094862I-838J-1124D01*
G03Y267666I-239J321D01*
G02X1096538I838J1124D01*
G03Y267024I239J-321D01*
G37*
G36*
G01X123208Y267857D02*
G02X121491Y268023I-977J-1141D01*
G03X121554Y268675I-197J348D01*
G02X123689Y270773I978J1140D01*
G03X124305I308J255D01*
G02Y268859I1158J-957D01*
G03X123689I-308J-255D01*
G02X123271Y268509I-1157J958D01*
G03X123208Y267857I197J-348D01*
G37*
G36*
G01X186837Y269010D02*
G02X184675Y271095I-1069J1055D01*
G03X184672Y271647I-291J274D01*
G02X184782Y273834I1082J1042D01*
G03X184778Y274447I-259J305D01*
G02X184629Y274587I952J1162D01*
G03X184041I-294J-270D01*
G02X181820Y274597I-1106J1017D01*
G03X181169Y274513I-296J-268D01*
G02X178650Y274281I-1334J691D01*
G03X178020I-315J-246D01*
G02X175650I-1185J923D01*
G03X175020I-315J-246D01*
G02X172739Y276231I-1185J923D01*
G03Y276777I-292J273D01*
G02X175020Y278727I1096J1027D01*
G03X175650I315J246D01*
G02X178020I1185J-923D01*
G03X178650I315J246D01*
G02X180950Y278811I1185J-923D01*
G03X181601Y278895I296J268D01*
G02X184041Y279221I1334J-691D01*
G03X184629I294J270D01*
G02X186833Y279229I1106J-1017D01*
G03X187436Y279249I293J273D01*
G02X189669Y279355I1164J-949D01*
G03X190258Y279376I285J281D01*
G02X190331Y277345I1142J-976D01*
G03X189742Y277324I-285J-281D01*
G02X189633Y277210I-1139J980D01*
G03X189620Y276643I276J-290D01*
G02X189479Y274436I-1085J-1039D01*
G03X189474Y273818I251J-311D01*
G02X189592Y271624I-964J-1152D01*
G03X189585Y271077I288J-277D01*
G02X187406Y269010I-1110J-1012D01*
G03X186837I-285J-281D01*
G37*
G36*
G01X653393Y271818D02*
G02X651851Y271716I-694J-1218D01*
G03X651807Y272382I-242J318D01*
G02X653349Y272484I694J1218D01*
G03X653393Y271818I242J-318D01*
G37*
G36*
G01X710700Y273831D02*
G02X709004Y273683I-751J-1184D01*
G03X708949Y274316I-269J295D01*
G02X708692Y276474I751J1184D01*
G03X708670Y277051I-288J278D01*
G02X708511Y277217I930J1049D01*
G03X707889I-311J-252D01*
G02Y278983I-1089J883D01*
G03X708511I311J252D01*
G02X710608Y277126I1090J-882D01*
G03X710630Y276549I288J-278D01*
G02X710645Y274464I-930J-1049D01*
G03X710700Y273831I269J-295D01*
G37*
G36*
G01X1624564Y272426D02*
G02X1624542Y274148I-1117J847D01*
G03X1625174Y274156I313J249D01*
G02X1625196Y272434I1117J-847D01*
G03X1624564Y272426I-313J-249D01*
G37*
G36*
G01X755577Y274494D02*
G02X754007Y274540I-819J-1138D01*
G03X754027Y275202I-214J338D01*
G02X755597Y275156I819J1138D01*
G03X755577Y274494I214J-338D01*
G37*
G36*
G01X202032Y274010D02*
G02X199964Y276148I-1185J923D01*
G03X199985Y276779I-235J324D01*
G02X199794Y276970I962J1153D01*
G03X199192Y276983I-307J-257D01*
G02X197199Y279210I-1110J1012D01*
G03X197220Y279841I-235J324D01*
G02X199297Y282001I962J1154D01*
G03X199878Y281988I297J268D01*
G02X202180Y281790I1069J-1055D01*
G03X202828Y281778I328J229D01*
G02X204792Y279814I1119J-845D01*
G03X204804Y279166I241J-320D01*
G02X204830Y276718I-857J-1233D01*
G03X204809Y276087I235J-324D01*
G02X202662Y274010I-962J-1153D01*
G03X202032I-315J-246D01*
G37*
G36*
G01X128755Y274876D02*
G02X128442Y276539I-1255J625D01*
G03X129069Y276657I269J296D01*
G02X129382Y274994I1255J-625D01*
G03X128755Y274876I-269J-296D01*
G37*
G36*
G01X116300Y278684D02*
G02X114751Y278669I-763J-1176D01*
G03X114744Y279336I-224J331D01*
G02X116293Y279351I763J1176D01*
G03X116300Y278684I224J-331D01*
G37*
G36*
G01X765908D02*
G02X764359Y278669I-763J-1176D01*
G03X764352Y279336I-224J331D01*
G02X765901Y279351I763J1176D01*
G03X765908Y278684I224J-331D01*
G37*
G36*
G01X750187Y280386D02*
G02X748558Y280793I-1087J-886D01*
G03X748713Y281414I-155J369D01*
G02X750342Y281007I1087J886D01*
G03X750187Y280386I155J-369D01*
G37*
G36*
G01X690825Y282220D02*
G02X689271I-777J-1167D01*
G03Y282886I-222J333D01*
G02X690825I777J1167D01*
G03Y282220I222J-333D01*
G37*
G36*
G01X1495494Y282261D02*
G02X1495450Y280598I1106J-861D01*
G03X1494806Y280615I-328J-229D01*
G02X1494850Y282278I-1106J861D01*
G03X1495494Y282261I328J229D01*
G37*
G36*
G01X1405610Y282190D02*
G02X1402952Y282162I-1324J-461D01*
G03X1402465Y282671I-380J124D01*
G02X1403191Y283152I-373J1351D01*
G03X1403465Y282866I157J-124D01*
G02X1403822Y283052I820J-1138D01*
G03X1404068Y283561I-132J378D01*
G02X1405856Y282699I1324J461D01*
G03X1405610Y282190I132J-378D01*
G37*
G36*
G01X684678Y281366D02*
G02X684620Y282940I-1188J744D01*
G03X685282Y282964I323J236D01*
G02X685340Y281390I1188J-744D01*
G03X684678Y281366I-323J-236D01*
G37*
G36*
G01X59894Y282265D02*
G02X59782Y283892I-1194J735D01*
G03X60431Y283936I309J254D01*
G02X60965Y284438I1194J-735D01*
G03X61026Y285104I-188J353D01*
G02X62560Y284963I874J1096D01*
G03X62499Y284297I188J-353D01*
G02X60543Y282309I-874J-1096D01*
G03X59894Y282265I-309J-254D01*
G37*
G36*
G01X766364Y284716D02*
G02X765442Y285696I-1357J-353D01*
G03X765953Y286177I124J380D01*
G02X765923Y286323I1357J355D01*
G03X765406Y286644I-395J-60D01*
G02X766367Y288187I-426J1336D01*
G03X766884Y287866I395J60D01*
G02X766875Y285197I426J-1336D01*
G03X766364Y284716I-124J-380D01*
G37*
G36*
G01X656121Y285442D02*
G02X654689Y285967I-1121J-842D01*
G03X654921Y286597I-88J390D01*
G02X656353Y286072I1121J842D01*
G03X656121Y285442I88J-390D01*
G37*
G36*
G01X1357775Y285582D02*
G02X1357735Y284295I1225J-682D01*
G03X1357025Y284318I-361J-172D01*
G02X1357065Y285605I-1225J682D01*
G03X1357775Y285582I361J172D01*
G37*
G36*
G01X1116937Y288227D02*
G02X1115684Y287313I62J-1401D01*
G03X1115292Y287851I-375J139D01*
G02X1116545Y288765I-62J1401D01*
G03X1116937Y288227I375J-139D01*
G37*
G36*
G01X465845Y293836D02*
G02X464680Y292661I221J-1384D01*
G03X464221Y293116I-396J60D01*
G02X465386Y294291I-221J1384D01*
G03X465845Y293836I396J-60D01*
G37*
G36*
G01X1455422Y293767D02*
G02X1454196Y293829I-671J-1116D01*
G03X1454231Y294533I-171J361D01*
G02X1455457Y294471I671J1116D01*
G03X1455422Y293767I171J-361D01*
G37*
G36*
G01X391445Y293739D02*
G02X391442Y292074I1249J-835D01*
G03X390777Y292075I-333J-221D01*
G02X390780Y293740I-1249J835D01*
G03X391445Y293739I333J221D01*
G37*
G36*
G01X1019491Y293792D02*
G02X1019487Y292021I1211J-888D01*
G03X1018841Y292022I-323J-236D01*
G02X1018845Y293793I-1211J888D01*
G03X1019491Y293792I323J236D01*
G37*
G36*
G01X1033860Y293749D02*
G02X1033857Y292064I1242J-845D01*
G03X1033195Y292065I-331J-224D01*
G02X1033198Y293750I-1242J845D01*
G03X1033860Y293749I331J224D01*
G37*
G36*
G01X1041074Y293769D02*
G02X1041066Y292051I1228J-865D01*
G03X1040410Y292054I-329J-227D01*
G02X1040418Y293772I-1228J865D01*
G03X1041074Y293769I329J227D01*
G37*
G36*
G01X1048230Y293702D02*
G02X1048227Y292110I1272J-798D01*
G03X1047548Y292112I-340J-211D01*
G02X1047551Y293704I-1272J798D01*
G03X1048230Y293702I340J211D01*
G37*
G36*
G01X1055512Y293821D02*
G02X1055509Y291992I1190J-916D01*
G03X1054874Y291993I-318J-243D01*
G02X1054877Y293822I-1190J916D01*
G03X1055512Y293821I318J243D01*
G37*
G36*
G01X412461Y292127D02*
G02Y293681I-1167J777D01*
G03X413127I333J222D01*
G02Y292127I1167J-777D01*
G03X412461I-333J-222D01*
G37*
G36*
G01X419661D02*
G02Y293681I-1167J777D01*
G03X420327I333J222D01*
G02Y292127I1167J-777D01*
G03X419661I-333J-222D01*
G37*
G36*
G01X426861D02*
G02Y293681I-1167J777D01*
G03X427527I333J222D01*
G02Y292127I1167J-777D01*
G03X426861I-333J-222D01*
G37*
G36*
G01X434061D02*
G02Y293681I-1167J777D01*
G03X434727I333J222D01*
G02Y292127I1167J-777D01*
G03X434061I-333J-222D01*
G37*
G36*
G01X441261D02*
G02Y293681I-1167J777D01*
G03X441927I333J222D01*
G02Y292127I1167J-777D01*
G03X441261I-333J-222D01*
G37*
G36*
G01X1062069D02*
G02Y293681I-1167J777D01*
G03X1062735I333J222D01*
G02Y292127I1167J-777D01*
G03X1062069I-333J-222D01*
G37*
G36*
G01X1069269D02*
G02Y293681I-1167J777D01*
G03X1069935I333J222D01*
G02Y292127I1167J-777D01*
G03X1069269I-333J-222D01*
G37*
G36*
G01X1076469D02*
G02Y293681I-1167J777D01*
G03X1077135I333J222D01*
G02Y292127I1167J-777D01*
G03X1076469I-333J-222D01*
G37*
G36*
G01X1083669D02*
G02Y293681I-1167J777D01*
G03X1084335I333J222D01*
G02Y292127I1167J-777D01*
G03X1083669I-333J-222D01*
G37*
G36*
G01X1090869D02*
G02Y293681I-1167J777D01*
G03X1091535I333J222D01*
G02Y292127I1167J-777D01*
G03X1090869I-333J-222D01*
G37*
G36*
G01X1321162Y296032D02*
G02X1320246Y295063I438J-1332D01*
G03X1319735Y295546I-387J103D01*
G02X1320651Y296515I-438J1332D01*
G03X1321162Y296032I387J-103D01*
G37*
G36*
G01X173985Y294577D02*
G02X171828Y296645I-1185J923D01*
G03Y297255I-259J305D01*
G02X171742Y299466I972J1145D01*
G03Y300034I-282J284D01*
G02X171828Y302245I1058J1066D01*
G03Y302855I-259J305D01*
G02X173985Y304923I972J1145D01*
G03X174615I315J246D01*
G02X176985I1185J-923D01*
G03X177615I315J246D01*
G02X179985I1185J-923D01*
G03X180615I315J246D01*
G02X182985I1185J-923D01*
G03X183615I315J246D01*
G02X185985I1185J-923D01*
G03X186615I315J246D01*
G02X186869Y305179I1186J-922D01*
G03X186890Y305788I-248J313D01*
G02X189000Y307922I1009J1113D01*
G03X189582Y307918I293J273D01*
G02X189689Y308018I1078J-1046D01*
G03X189677Y308331I-130J152D01*
G02X191679Y308526I893J1208D01*
G03X191699Y307966I295J-270D01*
G02X189565Y305855I-1034J-1089D01*
G03X188983Y305859I-293J-273D01*
G02X188831Y305721I-1083J1041D01*
G03X188810Y305112I248J-313D01*
G02X188772Y302855I-1010J-1112D01*
G03Y302245I259J-305D01*
G02X188858Y300034I-972J-1145D01*
G03Y299466I282J-284D01*
G02X188868Y297343I-1058J-1067D01*
G03X188900Y296751I284J-282D01*
G02X189108Y296547I-943J-1169D01*
G03X189706Y296529I307J256D01*
G02X191985Y296423I1094J-1029D01*
G03X192615I315J246D01*
G02X195024Y296370I1185J-923D01*
G03X195688Y296388I326J232D01*
G02X195732Y294713I1268J-805D01*
G03X195068Y294695I-326J-232D01*
G02X192615Y294577I-1268J805D01*
G03X191985I-315J-246D01*
G02X189648Y294536I-1185J923D01*
G03X189050Y294554I-307J-256D01*
G02X186732Y294713I-1094J1029D01*
G03X186068Y294695I-326J-232D01*
G02X183615Y294577I-1268J805D01*
G03X182985I-315J-246D01*
G02X180648Y294536I-1185J923D01*
G03X180050Y294554I-307J-256D01*
G02X177732Y294713I-1094J1029D01*
G03X177068Y294695I-326J-232D01*
G02X174615Y294577I-1268J805D01*
G03X173985I-315J-246D01*
G37*
G36*
G01X823867Y294604D02*
G02X821759Y296712I-1185J923D01*
G03Y297342I-246J315D01*
G02X821624Y299593I923J1185D01*
G03Y300161I-282J284D01*
G02Y302293I1058J1066D01*
G03Y302861I-282J284D01*
G02X823867Y304850I1058J1066D01*
G03X824497I315J246D01*
G02X826867I1185J-923D01*
G03X827497I315J246D01*
G02X829867I1185J-923D01*
G03X830497I315J246D01*
G02X832867I1185J-923D01*
G03X833497I315J246D01*
G02X835906Y304797I1185J-923D01*
G03X836558I326J232D01*
G02X838754Y302782I1224J-870D01*
G03Y302172I259J-305D01*
G02Y299882I-972J-1145D01*
G03Y299272I259J-305D01*
G02X836448Y297436I-972J-1145D01*
G03X835797Y297520I-355J-184D01*
G02X833497Y297604I-1115J1007D01*
G03X832867I-315J-246D01*
G02X830497I-1185J923D01*
G03X829867I-315J-246D01*
G02X827497I-1185J923D01*
G03X826867I-315J-246D01*
G02X826605Y297342I-1185J923D01*
G03Y296712I246J-315D01*
G02X824497Y294604I-923J-1185D01*
G03X823867I-315J-246D01*
G37*
G36*
G01X1115777Y297174D02*
G02X1114706Y295993I319J-1365D01*
G03X1114219Y296435I-397J52D01*
G02X1115290Y297616I-319J1365D01*
G03X1115777Y297174I397J-52D01*
G37*
G36*
G01X59608Y298174D02*
G02X57670Y298249I-1008J-974D01*
G03X57692Y298826I-266J299D01*
G02X57830Y300900I1008J975D01*
G03X57808Y301543I-248J313D01*
G02X59470Y301600I792J1157D01*
G03X59492Y300957I248J-313D01*
G02X59630Y298751I-792J-1157D01*
G03X59608Y298174I266J-299D01*
G37*
G36*
G01X672778Y298889D02*
G02X672637Y297518I1144J-810D01*
G03X671944Y297589I-367J-160D01*
G02X669711Y297517I-1144J811D01*
G03X669089I-311J-252D01*
G02Y299283I-1089J883D01*
G03X669711I311J252D01*
G02X672085Y298960I1089J-883D01*
G03X672778Y298889I367J160D01*
G37*
G36*
G01X776085Y299379D02*
G02X773826Y297921I-914J-1063D01*
G03X773223Y298143I-384J-112D01*
G02X771430Y298253I-823J1257D01*
G03X770807Y298114I-259J-305D01*
G02X768259Y299663I-1368J620D01*
G03X768017Y300303I-315J247D01*
G02X769312Y302881I273J1477D01*
G03X769861Y302885I272J293D01*
G02X772343Y301384I1039J-1085D01*
G03X772659Y300880I384J-110D01*
G02X773112Y300722I-262J-1479D01*
G03X773701Y301101I190J352D01*
G02X776105Y300001I1499J99D01*
G03X776085Y299379I241J-319D01*
G37*
G36*
G01X123318Y299752D02*
G02X121539Y300049I-1087J-1036D01*
G03X121644Y300680I-185J355D01*
G02X123889Y302673I1087J1037D01*
G03X124505I308J255D01*
G02Y300759I1158J-957D01*
G03X123889I-308J-255D01*
G02X123423Y300383I-1157J958D01*
G03X123318Y299752I185J-355D01*
G37*
G36*
G01X4973Y301570D02*
G02Y303124I-1167J777D01*
G03X5639I333J222D01*
G02Y301570I1167J-777D01*
G03X4973I-333J-222D01*
G37*
G36*
G01X1506795Y307781D02*
G02X1505065Y307774I-861J-1107D01*
G03X1505063Y308403I-248J314D01*
G02X1506793Y308410I861J1107D01*
G03X1506795Y307781I248J-314D01*
G37*
G36*
G01X777591Y306631D02*
G02X777150Y308191I-1321J469D01*
G03X777779Y308369I252J311D01*
G02X778220Y306809I1321J-469D01*
G03X777591Y306631I-252J-311D01*
G37*
G36*
G01X128755Y306876D02*
G02X128442Y308539I-1255J625D01*
G03X129069Y308657I269J296D01*
G02X129382Y306994I1255J-625D01*
G03X128755Y306876I-269J-296D01*
G37*
G36*
G01X1104766Y308814D02*
G02X1102437Y307365I-1010J-972D01*
G03X1101882Y307587I-376J-136D01*
G02X1099937Y308365I-626J1254D01*
G03X1099382Y308587I-376J-136D01*
G02X1097553Y309122I-626J1254D01*
G03X1096875Y309136I-343J-205D01*
G02X1094573Y309072I-1173J768D01*
G03X1093919Y309058I-322J-237D01*
G02X1091553Y309122I-1163J783D01*
G03X1090875Y309136I-343J-205D01*
G02X1090905Y310623I-1173J767D01*
G03X1091583Y310609I343J205D01*
G02X1093885Y310673I1173J-768D01*
G03X1094539Y310687I322J237D01*
G02X1096905Y310623I1163J-783D01*
G03X1097583Y310609I343J205D01*
G02X1100075Y310317I1173J-768D01*
G03X1100630Y310095I376J136D01*
G02X1101805Y310131I626J-1254D01*
G03X1102359Y310464I156J368D01*
G02X1104766Y309368I1397J-123D01*
G03Y308814I288J-277D01*
G37*
G36*
G01X116300Y310684D02*
G02X114751Y310669I-763J-1176D01*
G03X114744Y311336I-224J331D01*
G02X116293Y311351I763J1176D01*
G03X116300Y310684I224J-331D01*
G37*
G36*
G01X765908D02*
G02X764359Y310669I-763J-1176D01*
G03X764352Y311336I-224J331D01*
G02X765901Y311351I763J1176D01*
G03X765908Y310684I224J-331D01*
G37*
G36*
G01X1022322Y308938D02*
G02X1022236Y310700I-1257J822D01*
G03X1022883Y310731I312J250D01*
G02X1022969Y308969I1257J-822D01*
G03X1022322Y308938I-312J-250D01*
G37*
G36*
G01X369939Y310602D02*
G02X369911Y309141I1298J-756D01*
G03X369212Y309154I-353J-188D01*
G02X369240Y310615I-1298J756D01*
G03X369939Y310602I353J188D01*
G37*
G36*
G01X391435Y310723D02*
G02X391432Y309089I1259J-819D01*
G03X390761Y309091I-336J-217D01*
G02X390764Y310725I-1259J819D01*
G03X391435Y310723I336J217D01*
G37*
G36*
G01X398638Y310728D02*
G02X398635Y309085I1256J-824D01*
G03X397965Y309086I-335J-218D01*
G02X397968Y310729I-1256J824D01*
G03X398638Y310728I335J218D01*
G37*
G36*
G01X1033923Y310774D02*
G02X1033919Y309039I1224J-870D01*
G03X1033266Y309040I-327J-231D01*
G02X1033270Y310775I-1224J870D01*
G03X1033923Y310774I327J231D01*
G37*
G36*
G01X1055504Y310747D02*
G02X1055500Y309066I1243J-843D01*
G03X1054837Y309067I-332J-223D01*
G02X1054841Y310748I-1243J843D01*
G03X1055504Y310747I332J223D01*
G37*
G36*
G01X441282Y309097D02*
G02Y310585I-1188J744D01*
G03X441960I339J213D01*
G02Y309097I1188J-744D01*
G03X441282I-339J-213D01*
G37*
G36*
G01X412461Y309127D02*
G02Y310681I-1167J777D01*
G03X413127I333J222D01*
G02Y309127I1167J-777D01*
G03X412461I-333J-222D01*
G37*
G36*
G01X419661D02*
G02Y310681I-1167J777D01*
G03X420327I333J222D01*
G02Y309127I1167J-777D01*
G03X419661I-333J-222D01*
G37*
G36*
G01X426861D02*
G02Y310681I-1167J777D01*
G03X427527I333J222D01*
G02Y309127I1167J-777D01*
G03X426861I-333J-222D01*
G37*
G36*
G01X434061D02*
G02Y310681I-1167J777D01*
G03X434727I333J222D01*
G02Y309127I1167J-777D01*
G03X434061I-333J-222D01*
G37*
G36*
G01X1062069D02*
G02Y310681I-1167J777D01*
G03X1062735I333J222D01*
G02Y309127I1167J-777D01*
G03X1062069I-333J-222D01*
G37*
G36*
G01X1069269D02*
G02Y310681I-1167J777D01*
G03X1069935I333J222D01*
G02Y309127I1167J-777D01*
G03X1069269I-333J-222D01*
G37*
G36*
G01X1076469D02*
G02Y310681I-1167J777D01*
G03X1077135I333J222D01*
G02Y309127I1167J-777D01*
G03X1076469I-333J-222D01*
G37*
G36*
G01X1083669D02*
G02Y310681I-1167J777D01*
G03X1084335I333J222D01*
G02Y309127I1167J-777D01*
G03X1083669I-333J-222D01*
G37*
G36*
G01X77011Y310638D02*
G02X74355Y309826I-1385J-221D01*
G03X73684Y309910I-362J-170D01*
G02X73871Y311392I-1084J890D01*
G03X74542Y311308I362J170D01*
G02X75699Y311818I1083J-890D01*
G03X76115Y312280I21J399D01*
G02X76713Y313660I1385J220D01*
G03X76668Y314348I-225J331D01*
G02X78087Y314440I631J1252D01*
G03X78132Y313752I225J-331D01*
G02X77427Y311100I-632J-1252D01*
G03X77011Y310638I-21J-399D01*
G37*
G36*
G01X1494528Y312009D02*
G02X1494517Y310711I1123J-659D01*
G03X1493823Y310717I-349J-196D01*
G02X1493834Y312015I-1123J659D01*
G03X1494528Y312009I349J196D01*
G37*
G36*
G01X1493845Y313933D02*
G02Y315159I-1149J613D01*
G03X1494550I352J188D01*
G02Y313933I1149J-613D01*
G03X1493845I-352J-188D01*
G37*
G36*
G01X766382Y316635D02*
G02X765182Y317754I-1375J-272D01*
G03X765625Y318228I50J397D01*
G02X765973Y319454I1375J272D01*
G03X765913Y320051I-293J272D01*
G02X767759Y320235I819J1138D01*
G03X767819Y319638I293J-272D01*
G02X766825Y317109I-819J-1138D01*
G03X766382Y316635I-50J-397D01*
G37*
G36*
G01X76830Y321972D02*
G02X76259Y320391I770J-1172D01*
G03X75657Y320608I-382J-117D01*
G02X73796Y320899I-770J1172D01*
G03X73178Y320903I-311J-252D01*
G02X73191Y322681I-1078J897D01*
G03X73809Y322677I311J252D01*
G02X76228Y322189I1078J-897D01*
G03X76830Y321972I382J117D01*
G37*
G36*
G01X94042Y324546D02*
G02X93615Y323004I896J-1078D01*
G03X92982Y323179I-377J-132D01*
G02X93409Y324721I-896J1078D01*
G03X94042Y324546I377J132D01*
G37*
G36*
G01X688114Y326341D02*
G02X686563Y326393I-815J-1141D01*
G03X686586Y327059I-210J341D01*
G02X688137Y327007I815J1141D01*
G03X688114Y326341I210J-341D01*
G37*
G36*
G01X637472Y328363D02*
G02X636003Y327816I-329J-1363D01*
G03X635771Y328437I-326J232D01*
G02X636069Y331202I328J1363D01*
G03X636420Y331777I-8J400D01*
G02X637712Y330988I1261J613D01*
G03X637361Y330413I8J-400D01*
G02X637240Y328984I-1261J-613D01*
G03X637472Y328363I326J-232D01*
G37*
G36*
G01X1514594Y328782D02*
G02X1513308Y328680I-545J-1292D01*
G03X1513252Y329388I-211J340D01*
G02X1514538Y329490I545J1292D01*
G03X1514594Y328782I211J-340D01*
G37*
G36*
G01X195977Y326720D02*
G02X193577Y326760I-1185J923D01*
G03X192946Y326781I-324J-235D01*
G02X190491Y326992I-1154J962D01*
G03X189831Y327040I-346J-200D01*
G02X187731Y329158I-1177J933D01*
G03Y329788I-246J315D01*
G02X187696Y332130I923J1185D01*
G03X187691Y332750I-255J308D01*
G02X187445Y333000I940J1171D01*
G03X186815I-315J-246D01*
G02X184579Y334996I-1185J923D01*
G03X184510Y335623I-279J287D01*
G02X184085Y336017I789J1278D01*
G03X183454Y336038I-324J-235D01*
G02X181115Y336077I-1154J962D01*
G03X180485I-315J-246D01*
G02X178115I-1185J923D01*
G03X177485I-315J-246D01*
G02X175115I-1185J923D01*
G03X174485I-315J-246D01*
G02X172328Y338145I-1185J923D01*
G03Y338755I-259J305D01*
G02X174485Y340823I972J1145D01*
G03X175115I315J246D01*
G02X177485I1185J-923D01*
G03X178115I315J246D01*
G02X180485I1185J-923D01*
G03X181115I315J246D01*
G02X183485I1185J-923D01*
G03X184115I315J246D01*
G02X186485I1185J-923D01*
G03X187115I315J246D01*
G02X189515Y340783I1185J-923D01*
G03X190146Y340762I324J235D01*
G02X190085Y338917I1154J-962D01*
G03X189454Y338938I-324J-235D01*
G02X189223Y338715I-1153J963D01*
G03Y338085I246J-315D01*
G02X189351Y335827I-923J-1185D01*
G03X189420Y335200I279J-287D01*
G02X189588Y332766I-790J-1277D01*
G03X189593Y332146I255J-308D01*
G02X189577Y329788I-939J-1173D01*
G03Y329158I246J-315D01*
G02X189955Y328724I-923J-1185D01*
G03X190615Y328676I346J200D01*
G02X193007Y328626I1177J-933D01*
G03X193638Y328605I324J235D01*
G02X195977Y328566I1154J-962D01*
G03X196607I315J246D01*
G02Y326720I1185J-923D01*
G03X195977I-315J-246D01*
G37*
G36*
G01X126275Y331524D02*
G02X124804Y331495I-712J-1208D01*
G03X124779Y332182I-217J336D01*
G02X124256Y332659I722J1317D01*
G03X123673Y332746I-331J-224D01*
G02X123312Y332531I-942J1170D01*
G03X123207Y331858I155J-369D01*
G02X121650Y332101I-976J-1142D01*
G03X121755Y332774I-155J369D01*
G02X123975Y334757I976J1142D01*
G03X124558Y334670I331J224D01*
G02X126272Y332212I942J-1169D01*
G03X126275Y331524I206J-343D01*
G37*
G36*
G01X202100Y331913D02*
G02X200254I-923J-1185D01*
G03Y332543I-246J315D01*
G02Y334913I923J1185D01*
G03Y335543I-246J315D01*
G02X200133Y337808I923J1185D01*
G03X200130Y338386I-278J288D01*
G02X199892Y338675I1031J1092D01*
G03X199252Y338724I-338J-213D01*
G02X197112Y340824I-1134J985D01*
G03X197133Y341396I-269J296D01*
G02X197289Y343607I1090J1034D01*
G03X197292Y344232I-248J314D01*
G02X197048Y344479I939J1172D01*
G03X196418I-315J-246D01*
G02X194376Y346635I-1185J923D01*
G03X194388Y347283I-229J328D01*
G02Y349521I845J1119D01*
G03X194376Y350169I-241J320D01*
G02X196418Y352325I857J1233D01*
G03X197048I315J246D01*
G02X199156Y350217I1185J-923D01*
G03Y349587I246J-315D01*
G02X199326Y349432I-924J-1184D01*
G03X199918Y349442I291J274D01*
G02X201968Y347264I1127J-993D01*
G03Y346634I246J-315D01*
G02X202212Y346395I-922J-1186D01*
G03X202846Y346411I311J252D01*
G02X204983Y344342I1214J-884D01*
G03Y343712I246J-315D01*
G02X204996Y341353I-923J-1185D01*
G03X205018Y340711I249J-313D01*
G02X205207Y338396I-855J-1235D01*
G03X205210Y337818I278J-288D01*
G02X202992Y335805I-1033J-1090D01*
G03X202362I-315J-246D01*
G02X202100Y335543I-1185J923D01*
G03Y334913I246J-315D01*
G02Y332543I-923J-1185D01*
G03Y331913I246J-315D01*
G37*
G36*
G01X1106728Y335132D02*
G02X1104994Y335070I-828J-1132D01*
G03X1104972Y335698I-258J305D01*
G02X1106706Y335760I828J1132D01*
G03X1106728Y335132I258J-305D01*
G37*
G36*
G01X451673Y334540D02*
G02X449473Y334871I-973J1010D01*
G03X448830Y334949I-350J-194D01*
G02X449027Y336579I-1030J951D01*
G03X449670Y336501I350J194D01*
G02X451673Y336560I1030J-951D01*
G03X452227I277J288D01*
G02Y334540I973J-1010D01*
G03X451673I-277J-288D01*
G37*
G36*
G01X69546Y336983D02*
G02X67743Y337379I-1128J-833D01*
G03X67872Y337967I-193J350D01*
G02X67735Y338195I1128J833D01*
G03X67025Y338218I-361J-172D01*
G02X64643Y338108I-1225J682D01*
G03X64000Y338130I-330J-226D01*
G02X64057Y339792I-1100J870D01*
G03X64700Y339770I330J226D01*
G02X67065Y339505I1100J-870D01*
G03X67775Y339482I361J172D01*
G02X70167Y339577I1225J-682D01*
G03X70833I333J222D01*
G02X73073Y339702I1167J-777D01*
G03X73695Y339713I307J257D01*
G02X73727Y337948I1105J-863D01*
G03X73105Y337937I-307J-257D01*
G02X70833Y338023I-1105J863D01*
G03X70167I-333J-222D01*
G02X69675Y337571I-1167J777D01*
G03X69546Y336983I193J-350D01*
G37*
G36*
G01X1409740Y336269D02*
G02X1408622Y337811I-1392J167D01*
G03X1409097Y338155I78J392D01*
G02X1409130Y338332I1392J-168D01*
G03X1408866Y338568I-194J49D01*
G02X1409775Y339789I-490J1314D01*
G03X1410244Y339368I399J-27D01*
G02X1410215Y336613I245J-1380D01*
G03X1409740Y336269I-78J-392D01*
G37*
G36*
G01X1101253Y337632D02*
G02X1101084Y336002I1047J-932D01*
G03X1100438Y336069I-347J-199D01*
G02X1100607Y337699I-1047J932D01*
G03X1101253Y337632I347J199D01*
G37*
G36*
G01X1483734Y337311D02*
G02X1482776Y338273I-1348J-385D01*
G03X1483272Y338767I112J384D01*
G02X1483219Y339088I1348J387D01*
G03X1482768Y339466I-399J-18D01*
G02X1483986Y340920I-183J1390D01*
G03X1484437Y340542I399J18D01*
G02X1484230Y337805I183J-1390D01*
G03X1483734Y337311I-112J-384D01*
G37*
G36*
G01X378052Y351044D02*
X377417D01*
G03X377106Y350392I0J-400D01*
G02X374937Y350403I-1089J-883D01*
G03X374629Y351058I-308J255D01*
G01X373987D01*
X373936Y350934D01*
G02X371338I-1299J526D01*
G01X371287Y351058D01*
X370645D01*
G03X370337Y350403I0J-400D01*
G02X368177I-1080J-894D01*
G03X367869Y351058I-308J255D01*
G01X367227D01*
X367176Y350934D01*
G02X364578I-1299J526D01*
G01X364527Y351058D01*
X363885D01*
G03X363577Y350403I0J-400D01*
G02X361417I-1080J-894D01*
G03X361109Y351058I-308J255D01*
G01X360467D01*
X360416Y350934D01*
G02X357818I-1299J526D01*
G01X357767Y351058D01*
X353707D01*
X353656Y350934D01*
G02X351058I-1299J526D01*
G01X351007Y351058D01*
X346948D01*
X346897Y350934D01*
G02X344299I-1299J526D01*
G01X344248Y351058D01*
X343606D01*
G03X343298Y350403I0J-400D01*
G02X341138I-1080J-894D01*
G03X340830Y351058I-308J255D01*
G01X340192D01*
X337851Y353400D01*
X336871D01*
X336848Y353226D01*
G02X335098Y354764I-1390J183D01*
G03X335278Y355433I-103J386D01*
G01X334849Y355862D01*
X334841D01*
X333316Y357387D01*
X332026D01*
X331353Y358060D01*
G02X332817Y360451I725J1200D01*
G03X333347Y360550I211J340D01*
G02X333694Y360875I1117J-845D01*
G03Y361543I-220J334D01*
G02X333064Y362713I772J1170D01*
G01Y363605D01*
G02X334065Y364948I1402J0D01*
G02Y365270I1393J161D01*
G02X333346Y365769I400J1343D01*
G03X332816Y365868I-319J-241D01*
G02X332817Y368252I-738J1192D01*
G03X333347Y368351I211J340D01*
G02X334065Y368849I1118J-845D01*
G02Y369171I1393J161D01*
G02X333347Y369669I400J1343D01*
G03X332817Y369768I-319J-241D01*
G02Y372151I-739J1191D01*
G03X333347Y372250I211J340D01*
G02X333693Y372575I1119J-844D01*
G03Y373243I-220J334D01*
G02X333346Y373569I772J1170D01*
G03X332816Y373668I-319J-241D01*
G02X332817Y376051I-738J1192D01*
G03X333347Y376150I211J340D01*
G02X334065Y376648I1118J-845D01*
G02Y376970I1393J161D01*
G02X333064Y378313I401J1343D01*
G01Y379205D01*
G02X333694Y380375I1402J0D01*
G03Y381043I-220J334D01*
G02X333064Y382213I772J1170D01*
G01Y383105D01*
G02X333694Y384275I1402J0D01*
G03Y384943I-220J334D01*
G02X333064Y386113I772J1170D01*
G01Y387838D01*
X333836Y388612D01*
X335372Y390148D01*
Y434782D01*
G03X334620Y434971I-400J0D01*
G02Y443375I-7848J4202D01*
G03X335372Y443564I352J189D01*
G01Y471756D01*
X309074Y498053D01*
Y508398D01*
G02X309725Y509580I1402J-2D01*
G02Y510648I1296J534D01*
G02X309074Y511830I751J1184D01*
G01Y513457D01*
X308032Y514499D01*
Y516256D01*
G03X307642Y516655I-400J-1D01*
G02Y519459I33J1402D01*
G03X308032Y519858I-10J400D01*
G01Y527562D01*
X307881Y527600D01*
G02Y530126I317J1263D01*
G01X308032Y530164D01*
Y532546D01*
X308290Y532832D01*
G03Y533368I-298J268D01*
G01X308032Y533654D01*
Y536724D01*
X308063Y536860D01*
X308064Y536865D01*
G03Y537049I-389J92D01*
G01X308063Y537054D01*
X308032Y537190D01*
Y547967D01*
X308063Y548103D01*
X308064Y548108D01*
G03Y548292I-389J92D01*
G01X308063Y548297D01*
X308032Y548433D01*
Y551402D01*
X308367Y551701D01*
G03Y552299I-267J299D01*
G01X308032Y552598D01*
Y554156D01*
G03X307643Y554555I-400J-1D01*
G02Y557159I32J1302D01*
G03X308032Y557558I-11J400D01*
G01Y565429D01*
X307853Y565448D01*
G02Y568038I131J1295D01*
G01X308032Y568057D01*
Y570346D01*
X308290Y570632D01*
G03Y571168I-298J268D01*
G01X308032Y571454D01*
Y574524D01*
X308064Y574661D01*
X308065Y574666D01*
G03X308073Y574808I-390J93D01*
G01X307989Y575395D01*
X311995Y579402D01*
X356777D01*
X358970Y581594D01*
X360075Y582698D01*
X372596D01*
X375114Y580180D01*
X375675D01*
Y580429D01*
X375652Y580473D01*
G02X378228Y580701I1240J654D01*
G03X378609Y580180I381J-121D01*
G01X378776D01*
X380654Y578302D01*
X447805D01*
X448632Y577475D01*
Y575633D01*
X447912Y574914D01*
X447887Y574803D01*
X447885Y574743D01*
X447891Y574695D01*
X447979Y574459D01*
X448894Y573544D01*
Y573065D01*
X448898Y573062D01*
Y569860D01*
X448093Y569578D01*
G03Y568822I133J-378D01*
G01X448898Y568540D01*
Y556329D01*
X448250Y555681D01*
Y550246D01*
X448147Y550011D01*
X448145Y550007D01*
G03Y549679I365J-164D01*
G01X448147Y549675D01*
X448151Y549665D01*
X448159Y549651D01*
G03X448318Y549492I351J192D01*
G01X448323Y549489D01*
X448473Y549405D01*
X449351Y548527D01*
X449904Y547973D01*
Y538853D01*
X449294Y538243D01*
Y537318D01*
X448346Y537114D01*
G03X448177Y536414I86J-391D01*
G02X448274Y534344I-894J-1079D01*
G03X448305Y533750I283J-283D01*
G02X448190Y531491I-884J-1087D01*
G03X448330Y530764I220J-335D01*
G01X448332Y530763D01*
X449294Y530565D01*
Y515972D01*
X448541Y515671D01*
G03X448336Y515117I151J-371D01*
G02X447592Y513168I-1247J-641D01*
G03X447906Y512432I144J-373D01*
G02X449904Y511164I596J-1268D01*
G01Y502796D01*
X417438Y470329D01*
Y375485D01*
X412094Y370142D01*
G03X412193Y369504I283J-283D01*
G02X412518Y367249I-646J-1244D01*
G03Y366671I277J-289D01*
G02X412516Y364647I-971J-1011D01*
G03X412494Y364092I277J-289D01*
G02X410478Y364173I-1047J-932D01*
G03X410500Y364728I-277J289D01*
G02X410576Y366671I1047J932D01*
G03Y367249I-277J289D01*
G02X410303Y367614I971J1011D01*
G03X409665Y367713I-355J-184D01*
G01X407832Y365879D01*
Y357765D01*
X404240Y354174D01*
X404306Y354044D01*
G02X403605Y352119I-1250J-635D01*
G03X403478Y351468I156J-368D01*
G01X404265Y350682D01*
X418785D01*
X419943Y349523D01*
G03X420501Y349516I283J283D01*
G02X421676Y347111I963J-1019D01*
G01X421506Y347085D01*
Y345361D01*
X422378Y344490D01*
X431816D01*
X432900Y343406D01*
Y337196D01*
X431362Y335658D01*
X393925D01*
X386914Y342670D01*
G03X386275Y342570I-283J-283D01*
G02X384388Y344457I-1248J639D01*
G03X384488Y345096I-183J356D01*
G01X379523Y350061D01*
X379437Y350059D01*
G02X378103Y350920I-40J1401D01*
G01X378052Y351044D01*
G37*
G36*
G01X53874Y338591D02*
G02X52942Y338875I-849J-1116D01*
G03X53248Y339502I-23J399D01*
G02X55802Y340299I1152J798D01*
G03X56224Y339900I400J0D01*
G02X57463Y339283I76J-1400D01*
G03X58162Y339350I331J224D01*
G02X58289Y338017I1290J-550D01*
G03X57590Y337950I-331J-224D01*
G02X54898Y338501I-1290J550D01*
G03X54476Y338900I-400J0D01*
G02X54045Y338944I-75J1400D01*
G03X53874Y338591I-50J-194D01*
G37*
G36*
G01X1488712Y338646D02*
G02X1487060Y338620I-808J-1146D01*
G03X1487050Y339266I-240J319D01*
G02X1488702Y339292I808J1146D01*
G03X1488712Y338646I240J-319D01*
G37*
G36*
G01X99363Y339304D02*
G02X97886Y339236I-684J-1224D01*
G03X97855Y339915I-226J330D01*
G02X99332Y339983I684J1224D01*
G03X99363Y339304I226J-330D01*
G37*
G36*
G01X1048923Y337564D02*
G02Y339118I-1167J777D01*
G03X1049589I333J222D01*
G02X1051885Y339173I1167J-777D01*
G03X1052539Y339187I322J237D01*
G02X1054790Y339289I1163J-783D01*
G03X1055456Y339359I310J252D01*
G02X1055594Y337767I1336J-686D01*
G03X1054926Y337720I-319J-242D01*
G02X1052573Y337572I-1224J684D01*
G03X1051919Y337558I-322J-237D01*
G02X1049589Y337564I-1163J783D01*
G03X1048923I-333J-222D01*
G37*
G36*
G01X1078467Y337610D02*
G02Y339456I-1185J923D01*
G03X1079097I315J246D01*
G02X1081382Y339556I1185J-923D01*
G03X1082017Y339620I293J272D01*
G02X1084446Y339813I1284J-779D01*
G03X1085040Y339796I305J259D01*
G02X1084981Y337786I1086J-1038D01*
G03X1084387Y337803I-305J-259D01*
G02X1082201Y337818I-1086J1038D01*
G03X1081566Y337754I-293J-272D01*
G02X1079097Y337610I-1284J779D01*
G03X1078467I-315J-246D01*
G37*
G36*
G01X128370Y338700D02*
G02X127731Y340196I-1370J299D01*
G03X128330Y340452I208J341D01*
G02X128969Y338956I1370J-299D01*
G03X128370Y338700I-208J-341D01*
G37*
G36*
G01X1564167Y340223D02*
G02Y341777I-1167J777D01*
G03X1564833I333J222D01*
G02Y340223I1167J-777D01*
G03X1564167I-333J-222D01*
G37*
G36*
G01X116300Y342684D02*
G02X114751Y342669I-763J-1176D01*
G03X114744Y343336I-224J331D01*
G02X116293Y343351I763J1176D01*
G03X116300Y342684I224J-331D01*
G37*
G36*
G01X765908D02*
G02X764359Y342669I-763J-1176D01*
G03X764352Y343336I-224J331D01*
G02X765901Y343351I763J1176D01*
G03X765908Y342684I224J-331D01*
G37*
G36*
G01X50027Y344982D02*
G02X48007I-1010J-973D01*
G03Y345536I-288J277D01*
G02X48048Y347522I1010J973D01*
G03X48070Y348077I-277J289D01*
G02X48097Y349971I1047J932D01*
G03X48091Y350526I-291J274D01*
G02X48312Y352675I1000J983D01*
G03X48314Y353339I-222J333D01*
G02X49879Y353334I786J1161D01*
G03X49877Y352670I222J-333D01*
G02X50336Y352153I-786J-1161D01*
G03X50960Y352040I355J184D01*
G02X50557Y350596I940J-1041D01*
G03X50207Y350660I-191J-57D01*
G02X50111Y350547I-1115J850D01*
G03X50117Y349992I291J-274D01*
G02X50086Y347996I-1000J-983D01*
G03X50064Y347441I277J-289D01*
G02X50244Y347187I-1047J-933D01*
G03X50889Y347111I350J194D01*
G02X50696Y345486I1034J-947D01*
G03X50051Y345562I-350J-194D01*
G02X50027Y345536I-1042J938D01*
G03Y344982I288J-277D01*
G37*
G36*
G01X102884Y347278D02*
G02X101000Y347391I-1004J-978D01*
G03X101036Y347982I-251J312D01*
G02X101165Y350055I1004J978D01*
G03X101169Y350676I-250J312D01*
G02X101336Y352959I891J1082D01*
G03X101358Y353630I-207J343D01*
G02X102884Y353580I802J1150D01*
G03X102862Y352909I207J-343D01*
G02X102935Y350664I-802J-1150D01*
G03X102931Y350043I250J-312D01*
G02X102920Y347869I-891J-1083D01*
G03X102884Y347278I251J-312D01*
G37*
G36*
G01X1331530Y347307D02*
G02X1331474Y345600I1083J-890D01*
G03X1330840Y345621I-325J-233D01*
G02X1330896Y347328I-1083J890D01*
G03X1331530Y347307I325J233D01*
G37*
G36*
G01X65595Y349131D02*
G02X65121Y347275I755J-1181D01*
G03X64555Y347419I-350J-193D01*
G02X62757Y347664I-755J1181D01*
G03X62113Y347597I-298J-267D01*
G02X61943Y349236I-1213J702D01*
G03X62587Y349303I298J267D01*
G02X65029Y349275I1213J-703D01*
G03X65595Y349131I350J193D01*
G37*
G36*
G01X1644113Y349711D02*
G02X1642615Y349988I-963J-1019D01*
G03X1642737Y350648I-153J370D01*
G02X1644235Y350371I963J1019D01*
G03X1644113Y349711I153J-370D01*
G37*
G36*
G01X1338882Y350962D02*
G02X1338203Y349606I715J-1206D01*
G03X1337601Y349907I-398J-43D01*
G02X1338280Y351263I-715J1206D01*
G03X1338882Y350962I398J43D01*
G37*
G36*
G01X1588979Y351651D02*
G02X1588978Y350340I1239J-656D01*
G03X1588271I-354J-187D01*
G02X1588272Y351651I-1239J656D01*
G03X1588979I354J187D01*
G37*
G36*
G01X1063416Y377535D02*
Y376085D01*
G02X1063317Y375569I-1402J1D01*
G01X1063302Y375533D01*
Y368733D01*
G03X1063851Y368362I400J0D01*
G02X1063086Y366498I520J-1302D01*
G03X1062437Y366621I-366J-160D01*
G01X1061041Y365225D01*
G03X1061264Y364546I283J-283D01*
G02X1059669Y362951I-209J-1386D01*
G03X1058990Y363174I-396J-60D01*
G01X1057205Y361388D01*
X1054068D01*
X1054066Y361191D01*
G02X1051262I-1402J18D01*
G01X1051260Y361388D01*
X1047308D01*
X1047306Y361191D01*
G02X1044502I-1402J18D01*
G01X1044500Y361388D01*
X1040549D01*
X1040547Y361191D01*
G02X1037743I-1402J18D01*
G01X1037741Y361388D01*
X1035885D01*
X1033369Y358873D01*
G03X1033371Y358306I283J-283D01*
G02X1031388Y356323I-986J-997D01*
G03X1030821Y356325I-284J-281D01*
G01X1030330Y355833D01*
X1030359Y355722D01*
G02X1028643Y354006I-1354J-362D01*
G01X1028532Y354035D01*
X1026125Y351628D01*
X1023651D01*
X1023647Y351432D01*
G02X1020843Y351443I-1402J28D01*
G01X1020841Y351640D01*
X1016889D01*
X1016887Y351443D01*
G02X1014083I-1402J17D01*
G01X1014081Y351640D01*
X1010129D01*
X1010127Y351443D01*
G02X1007323I-1402J17D01*
G01X1007321Y351640D01*
X1003369D01*
X1003367Y351443D01*
G02X1000563I-1402J17D01*
G01X1000561Y351640D01*
X996610D01*
X996608Y351443D01*
G02X993804I-1402J17D01*
G01X993802Y351640D01*
X990382D01*
X989130Y352892D01*
Y356055D01*
G02X989526Y357031I1402J0D01*
G03Y357587I-287J278D01*
G02X989130Y358563I1006J976D01*
G01Y359955D01*
G02X989526Y360930I1401J-1D01*
G03Y361487I-287J278D01*
G02X989296Y361801I1005J977D01*
G03X989036Y361888I-176J-94D01*
G02X987182Y363767I-590J1272D01*
G01X987244Y363895D01*
X986876Y364263D01*
X986806Y364332D01*
G03X986200Y364285I-283J-283D01*
G02X984326Y366300I-1134J824D01*
G03X984483Y366798I-211J340D01*
G02X984430Y367761I1287J554D01*
G02X983864Y369732I636J1249D01*
G02X983540Y370143I919J1058D01*
G03X982852Y370181I-355J-184D01*
G02Y371738I-1166J778D01*
G03X983539Y371775I333J222D01*
G02X985003Y372513I1244J-646D01*
G03Y373305I63J396D01*
G02X983539Y374043I-220J1384D01*
G03X982852Y374081I-355J-184D01*
G02Y375638I-1166J778D01*
G03X983540Y375676I333J222D01*
G02X983864Y376087I1243J-647D01*
G02Y377531I1202J722D01*
G02X983382Y378588I920J1058D01*
G01Y378930D01*
G02X985003Y380313I1401J-1D01*
G03Y381105I63J396D01*
G02X983382Y382488I-220J1384D01*
G01Y382830D01*
G02X985003Y384213I1401J-1D01*
G03Y385005I63J396D01*
G02X983382Y386388I-220J1384D01*
G01Y399897D01*
X983914Y400430D01*
X984972Y401489D01*
Y434771D01*
G03X984220Y434960I-400J0D01*
G02Y443386I-7842J4213D01*
G03X984972Y443575I352J189D01*
G01Y471756D01*
X957266Y499463D01*
Y512107D01*
X957948Y512433D01*
G03X957949Y513154I-174J361D01*
G01X957266Y513478D01*
Y516644D01*
X957093Y516668D01*
G02X957094Y519446I190J1389D01*
G01X957266Y519470D01*
Y527672D01*
X957165Y527730D01*
G02Y529996I641J1133D01*
G01X957266Y530054D01*
Y532463D01*
X957791Y532748D01*
G03Y533452I-191J352D01*
G01X957266Y533737D01*
Y536378D01*
X957564Y536672D01*
G03Y537242I-281J285D01*
G01X957266Y537536D01*
Y547621D01*
X957564Y547915D01*
G03Y548485I-281J285D01*
G01X957266Y548779D01*
Y551305D01*
X957892Y551648D01*
X957893D01*
G03Y552352I-192J352D01*
G01X957892D01*
X957266Y552695D01*
Y554544D01*
X957095Y554569D01*
G02Y557145I188J1288D01*
G01X957266Y557170D01*
Y565475D01*
X957136Y565523D01*
G02Y567963I456J1220D01*
G01X957266Y568011D01*
Y570263D01*
X957791Y570548D01*
G03Y571252I-191J352D01*
G01X957266Y571537D01*
Y574178D01*
X957564Y574472D01*
G03Y575042I-281J285D01*
G01X957266Y575336D01*
Y577806D01*
X957799Y578340D01*
X958860Y579402D01*
X1007898D01*
X1010744Y582248D01*
X1022496D01*
X1026388Y578356D01*
X1026124Y577637D01*
G03X1026888Y577399I377J-136D01*
G01X1027117Y578302D01*
X1096025D01*
X1098425Y575901D01*
X1097612Y575051D01*
X1097611D01*
G03X1097763Y574396I288J-278D01*
G01X1097765D01*
X1098558Y574107D01*
Y569847D01*
X1097715Y569582D01*
G03Y568818I119J-382D01*
G01X1098558Y568553D01*
Y553734D01*
X1098087Y553440D01*
G03Y552760I213J-340D01*
G01X1098558Y552466D01*
Y550540D01*
X1097931Y550196D01*
X1097928Y550195D01*
G03Y549491I190J-352D01*
G01X1097931Y549490D01*
X1098558Y549146D01*
Y537411D01*
X1097870Y537086D01*
X1097869Y537085D01*
G03Y536361I171J-362D01*
G01X1097870Y536360D01*
X1098558Y536035D01*
Y534443D01*
X1097988Y534170D01*
G03X1097874Y533529I172J-361D01*
G02X1097763Y531465I-1001J-981D01*
G03X1097852Y530791I255J-309D01*
G01X1098558Y530472D01*
Y517317D01*
X1098571Y517282D01*
G02X1098070Y515628I-1306J-507D01*
G03X1097944Y515117I230J-328D01*
G02X1097200Y513168I-1247J-641D01*
G03X1097501Y512427I142J-374D01*
G02X1099458Y511141I555J-1287D01*
G01Y502750D01*
X1067038Y470329D01*
Y405885D01*
X1065370Y404217D01*
Y399117D01*
X1063416Y397163D01*
Y395584D01*
G02X1063041Y394631I-1402J1D01*
G03Y394087I293J-272D01*
G02X1063416Y393134I-1027J-954D01*
G01Y391685D01*
G02X1063041Y390732I-1402J1D01*
G03Y390188I293J-272D01*
G02X1063416Y389235I-1027J-954D01*
G01Y387785D01*
G02X1063041Y386832I-1402J1D01*
G03Y386288I293J-272D01*
G02X1063416Y385335I-1027J-954D01*
G01Y383885D01*
G02X1063041Y382932I-1402J1D01*
G03Y382388I293J-272D01*
G02X1063416Y381435I-1027J-954D01*
G01Y379985D01*
G02X1063041Y379032I-1402J1D01*
G03Y378488I293J-272D01*
G02X1063416Y377535I-1027J-954D01*
G37*
G36*
G01X1508004Y354215D02*
G02X1506340Y354241I-850J-1115D01*
G03X1506350Y354885I-232J326D01*
G02X1506271Y357050I850J1115D01*
G03Y357650I-265J300D01*
G02X1508129I929J1050D01*
G03Y357050I265J-300D01*
G02X1508014Y354859I-929J-1050D01*
G03X1508004Y354215I232J-326D01*
G37*
G36*
G01X1539469Y360376D02*
G02X1537451Y360293I-969J-1013D01*
G03X1537428Y360848I-299J266D01*
G02X1537462Y362906I969J1013D01*
G03X1537418Y363536I-267J298D01*
G02X1539135Y363655I782J1164D01*
G03X1539179Y363025I267J-298D01*
G02X1539446Y360931I-782J-1164D01*
G03X1539469Y360376I299J-266D01*
G37*
G36*
G01X1343883Y360683D02*
G02X1343419Y359074I848J-1116D01*
G03X1342802Y359252I-375J-141D01*
G02X1343266Y360861I-848J1116D01*
G03X1343883Y360683I375J141D01*
G37*
G36*
G01X102517Y361294D02*
G02X100999Y361304I-767J-1174D01*
G03X101003Y361976I-215J337D01*
G02X102521Y361966I767J1174D01*
G03X102517Y361294I215J-337D01*
G37*
G36*
G01X1357712Y360037D02*
G02X1357659Y361417I-1246J643D01*
G03X1358354Y361443I340J210D01*
G02X1358407Y360063I1246J-643D01*
G03X1357712Y360037I-340J-210D01*
G37*
G36*
G01X1608786Y360618D02*
G02X1608339Y361947I-1374J277D01*
G03X1608996Y362167I265J300D01*
G02X1609443Y360838I1374J-277D01*
G03X1608786Y360618I-265J-300D01*
G37*
G36*
G01X60254Y363533D02*
G02X59542Y362141I680J-1226D01*
G03X58951Y362443I-397J-48D01*
G02X59663Y363835I-680J1226D01*
G03X60254Y363533I397J48D01*
G37*
G36*
G01X126608Y363251D02*
G02X124265Y361785I-1045J-935D01*
G03X123566Y361861I-370J-151D01*
G02X121424Y363913I-1235J855D01*
G03X121481Y364499I-241J319D01*
G02X123960Y366138I1119J1002D01*
G03X124590Y366012I362J170D01*
G02X126631Y363808I1010J-1112D01*
G03X126608Y363251I275J-290D01*
G37*
G36*
G01X776095Y363370D02*
G02X774172Y363300I-924J-1054D01*
G03X774136Y363894I-285J281D01*
G02X773991Y364025I932J1178D01*
G03X773406Y364015I-288J-278D01*
G02X771506Y363739I-1116J1005D01*
G03X770906Y363485I-209J-341D01*
G02X768332Y364824I-1466J325D01*
G03X768319Y365377I-295J270D01*
G02X770875Y366588I1061J1063D01*
G03X771487Y366289I398J39D01*
G02X773369Y366065I803J-1269D01*
G03X773954Y366075I288J278D01*
G02X776088Y363965I1116J-1006D01*
G03X776095Y363370I271J-294D01*
G37*
G36*
G01X679038Y364209D02*
G02X677514Y363539I-308J-1368D01*
G03X677255Y364128I-347J199D01*
G02X678779Y364798I308J1368D01*
G03X679038Y364209I347J-199D01*
G37*
G36*
G01X1381129Y371450D02*
G02X1379271I-929J-1050D01*
G03Y372050I-265J300D01*
G02X1378921Y372526I929J1050D01*
G03X1378233Y372599I-365J-164D01*
G02X1377889Y372267I-1131J828D01*
G03X1377862Y371625I224J-331D01*
G02X1375667Y370041I-883J-1089D01*
G03X1375083Y370239I-374J-142D01*
G02X1373459Y372518I-739J1191D01*
G03X1373442Y373152I-252J310D01*
G02X1375602Y374716I826J1133D01*
G03X1376231Y374526I380J123D01*
G02X1378382Y374002I872J-1098D01*
G03X1379070Y373929I365J164D01*
G02X1381129Y372050I1131J-829D01*
G03Y371450I265J-300D01*
G37*
G36*
G01X128750Y371148D02*
G02X128552Y372417I-1330J442D01*
G03X129255Y372527I323J236D01*
G02X129453Y371258I1330J-442D01*
G03X128750Y371148I-323J-236D01*
G37*
G36*
G01X764923Y374919D02*
G02X763374Y374904I-763J-1176D01*
G03X763367Y375571I-224J331D01*
G02X764916Y375586I763J1176D01*
G03X764923Y374919I224J-331D01*
G37*
G36*
G01X1333536Y375536D02*
G02X1331725Y375503I-886J-1086D01*
G03X1331714Y376114I-264J301D01*
G02X1331623Y376195I886J1087D01*
G03X1331090Y376217I-279J-287D01*
G02X1329151Y376370I-890J1083D01*
G03X1328574Y376392I-299J-266D01*
G02X1326551Y376470I-974J1008D01*
G03X1325974Y376492I-299J-266D01*
G02X1323787Y376797I-974J1008D01*
G03X1323143Y376864I-346J-200D01*
G02X1320807Y377258I-1043J936D01*
G03X1320186Y377413I-369J-155D01*
G02X1320673Y378784I-886J1087D01*
G03X1321022Y378697I196J41D01*
G02X1321181Y378859I1077J-898D01*
G03X1321171Y379471I-262J302D01*
G02X1323113Y381479I883J1089D01*
G03X1323738Y381506I302J263D01*
G02X1324095Y381849I1135J-824D01*
G03Y382515I-222J333D01*
G02X1326062Y384424I777J1167D01*
G03X1326711Y384384I339J212D01*
G02X1328875Y384400I1089J-884D01*
G03X1329531Y384464I306J257D01*
G02X1329981Y384952I1226J-679D01*
G03Y385618I-222J333D01*
G02Y387952I777J1167D01*
G03Y388618I-222J333D01*
G02X1331535I777J1167D01*
G03Y387952I222J-333D01*
G02Y385618I-777J-1167D01*
G03Y384952I222J-333D01*
G02X1329683Y382885I-777J-1167D01*
G03X1329027Y382821I-306J-257D01*
G02X1328475Y382271I-1227J679D01*
G03X1328453Y381583I192J-351D01*
G02X1328666Y381416I-755J-1182D01*
G03X1329219Y381417I276J290D01*
G02X1331148Y381430I971J-1011D01*
G03X1331715Y381451I273J292D01*
G02X1331790Y379479I1033J-948D01*
G03X1331223Y379458I-273J-292D01*
G02X1330905Y379200I-1033J948D01*
G03X1330907Y378511I204J-344D01*
G02X1331177Y378305I-709J-1209D01*
G03X1331710Y378283I279J287D01*
G02X1333525Y376147I890J-1083D01*
G03X1333536Y375536I264J-301D01*
G37*
G36*
G01X1446261Y374114D02*
G02X1446234Y375724I-1161J786D01*
G03X1446889Y375736I323J236D01*
G02X1446916Y374126I1161J-786D01*
G03X1446261Y374114I-323J-236D01*
G37*
G36*
G01X1631819Y376659D02*
G02X1629911Y376593I-919J-1059D01*
G03X1629862Y377201I-283J283D01*
G02X1629557Y379511I938J1299D01*
G03X1629414Y380126I-310J252D01*
G02X1631156Y380607I586J1274D01*
G03X1631349Y380005I330J-226D01*
G02X1631825Y377269I-549J-1505D01*
G03X1631819Y376659I256J-308D01*
G37*
G36*
G01X752570Y380608D02*
G02X752514Y379226I1304J-745D01*
G03X751804Y379255I-363J-169D01*
G02X751860Y380637I-1304J745D01*
G03X752570Y380608I363J169D01*
G37*
G36*
G01X766290Y380798D02*
G02X764936Y381765I-1333J-435D01*
G03X765310Y382289I-6J400D01*
G02X766009Y383974I1333J435D01*
G03X766122Y384602I-181J357D01*
G02X767789Y384300I1033J948D01*
G03X767676Y383672I181J-357D01*
G02X766664Y381322I-1033J-948D01*
G03X766290Y380798I6J-400D01*
G37*
G36*
G01X117981Y382436D02*
G02X117232Y381078I648J-1243D01*
G03X116648Y381400I-399J-33D01*
G02X115528Y383963I-649J1243D01*
G03X115764Y384490I-135J377D01*
G02X117535Y383696I1299J526D01*
G03X117299Y383169I135J-377D01*
G02X117397Y382758I-1299J-527D01*
G03X117981Y382436I399J33D01*
G37*
G36*
G01X701444Y383162D02*
G02X699108Y385037I-1240J848D01*
G03Y385583I-292J273D01*
G02X699427Y387896I1096J1027D01*
G03X699467Y388553I-207J342D01*
G02X699381Y390849I924J1184D01*
G03X699360Y391458I-269J296D01*
G02X699373Y393826I931J1179D01*
G03X699408Y394429I-244J317D01*
G02X701347Y396714I1050J1075D01*
G03X701917Y396815I237J322D01*
G02X704303Y396971I1252J-829D01*
G03X704933Y397004I302J262D01*
G02X707263Y397167I1231J-861D01*
G03X707854Y397174I292J273D01*
G02X710012Y397261I1121J-1000D01*
G03X710558Y397256I276J289D01*
G02X712498Y394965I1017J-1106D01*
G03Y394335I246J-315D01*
G02Y391965I-923J-1185D01*
G03Y391335I246J-315D01*
G02X712244Y388805I-923J-1185D01*
G03X712159Y388145I178J-358D01*
G02X712231Y385946I-986J-1133D01*
G03Y385378I282J-284D01*
G02X710031Y383336I-1059J-1066D01*
G03X709442Y383357I-304J-260D01*
G02X707307Y383354I-1069J1055D01*
G03X706739I-284J-282D01*
G02X704607I-1066J1058D01*
G03X704039I-284J-282D01*
G02X702026Y383246I-1066J1058D01*
G03X701444Y383162I-252J-310D01*
G37*
G36*
G01X1457707Y385768D02*
G02X1456192Y385728I-726J-1199D01*
G03X1456174Y386401I-225J331D01*
G02X1457689Y386441I726J1199D01*
G03X1457707Y385768I225J-331D01*
G37*
G36*
G01X680301Y386975D02*
G02X678638Y386895I-777J-1167D01*
G03X678607Y387538I-253J310D01*
G02X680270Y387618I777J1167D01*
G03X680301Y386975I253J-310D01*
G37*
G36*
G01X1381928Y391468D02*
G02Y393132I-1128J832D01*
G03X1382572I322J238D01*
G02Y391468I1128J-832D01*
G03X1381928I-322J-238D01*
G37*
G36*
G01X1470953Y393463D02*
G02X1469582Y393653I-853J-1113D01*
G03X1469737Y394285I-148J371D01*
G02X1469538Y395811I1063J915D01*
G03X1469332Y396354I-360J174D01*
G02X1468706Y396871I542J1293D01*
G03X1468040I-333J-222D01*
G02X1465862Y396677I-1167J777D01*
G03X1465284I-289J-277D01*
G02Y398619I-1011J971D01*
G03X1465862I289J277D01*
G02X1468040Y398425I1011J-971D01*
G03X1468706I333J222D01*
G02X1471135Y397037I1167J-777D01*
G03X1471341Y396494I360J-174D01*
G02X1472183Y395433I-541J-1294D01*
G03X1472689Y395116I394J67D01*
G02X1471700Y393537I394J-1346D01*
G03X1471194Y393854I-394J-67D01*
G02X1471040Y393819I-387J1348D01*
G03X1470953Y393463I34J-197D01*
G37*
G36*
G01X189179Y394187D02*
G02X188651Y392603I921J-1187D01*
G03X188021Y392813I-385J-106D01*
G02X188549Y394397I-921J1187D01*
G03X189179Y394187I385J106D01*
G37*
G36*
G01X776165Y395252D02*
G02X774299Y395452I-1044J-936D01*
G03X774350Y396056I-235J324D01*
G02X774323Y396084I1068J1056D01*
G03X773760Y396105I-292J-273D01*
G02X771863Y395991I-1018J1104D01*
G03X771238Y395752I-234J-324D01*
G02X768565Y395174I-1468J318D01*
G03X767953Y395210I-321J-239D01*
G02X768065Y397136I-1093J1030D01*
G03X768677Y397100I321J239D01*
G02X770649Y397288I1093J-1030D01*
G03X771274Y397527I234J324D01*
G02X773839Y398235I1468J-318D01*
G03X774402Y398214I292J273D01*
G02X776243Y395854I1019J-1103D01*
G03X776165Y395252I219J-334D01*
G37*
G36*
G01X123112Y395933D02*
G02X121168Y395777I-881J-1217D01*
G03X121119Y396383I-283J282D01*
G02X123280Y398385I881J1217D01*
G03X123974Y398406I341J209D01*
G02X124020Y396915I1326J-705D01*
G03X123326Y396894I-341J-209D01*
G02X123063Y396539I-1325J707D01*
G03X123112Y395933I283J-282D01*
G37*
G36*
G01X1631023Y396730D02*
G02X1629663Y396770I-723J-1430D01*
G03X1629703Y397484I-159J367D01*
G02X1629491Y399767I697J1216D01*
G03X1629524Y400344I-260J304D01*
G02X1631459Y400233I1026J956D01*
G03X1631426Y399656I260J-304D01*
G02X1631025Y397445I-1026J-956D01*
G03X1631023Y396730I178J-358D01*
G37*
G36*
G01X1244795Y398467D02*
G02X1244034Y399589I-1396J-128D01*
G03X1244614Y399982I182J356D01*
G02X1245375Y398860I1396J128D01*
G03X1244795Y398467I-182J-356D01*
G37*
G36*
G01X1332810Y400430D02*
G02X1330695Y398590I-1039J-941D01*
G03X1330094Y398605I-307J-256D01*
G02X1327897Y398779I-1030J951D01*
G03X1327231I-333J-222D01*
G02X1324897I-1167J777D01*
G03X1324231I-333J-222D01*
G02X1322028Y398611I-1167J777D01*
G03X1321442Y398616I-295J-270D01*
G02X1319229Y398844I-1019J963D01*
G03X1318644Y398952I-341J-209D01*
G02X1316778Y401035I-857J1110D01*
G03Y401589I-288J277D01*
G02X1319048Y403176I1010J973D01*
G03X1319361Y403113I180J87D01*
G02X1319442Y403180I933J-1046D01*
G03X1319456Y403487I-121J159D01*
G02X1321567Y405301I944J1037D01*
G03X1322233I333J222D01*
G02X1324567I1167J-777D01*
G03X1325233I333J222D01*
G02X1327567I1167J-777D01*
G03X1328233I333J222D01*
G02X1330380Y405527I1167J-777D01*
G03X1330951Y405539I280J286D01*
G02X1332902Y403530I1022J-959D01*
G03X1332876Y402956I265J-300D01*
G02X1332829Y400986I-1020J-961D01*
G03X1332810Y400430I278J-288D01*
G37*
G36*
G01X1466215Y401593D02*
G02Y403147I-1167J777D01*
G03X1466881I333J222D01*
G02Y401593I1167J-777D01*
G03X1466215I-333J-222D01*
G37*
G36*
G01X175831Y403321D02*
G02X175784Y404774I-1222J688D01*
G03X176467Y404797I335J219D01*
G02X178913Y404794I1222J-688D01*
G03X179603Y404780I349J195D01*
G02X179575Y403364I1196J-732D01*
G03X178885Y403378I-349J-195D01*
G02X176514Y403344I-1196J731D01*
G03X175831Y403321I-335J-219D01*
G37*
G36*
G01X1198437Y406752D02*
G02X1196898Y406240I-408J-1341D01*
G03X1196692Y406859I-323J236D01*
G02X1198231Y407371I408J1341D01*
G03X1198437Y406752I323J-236D01*
G37*
G36*
G01X105766Y407114D02*
G02X104251Y407757I-1248J-835D01*
G03X104512Y408373I-71J394D01*
G02X106070Y410678I1249J835D01*
G03X106543Y411155I83J391D01*
G02X107701Y410009I1467J324D01*
G03X107228Y409532I-83J-391D01*
G02X106027Y407730I-1467J-324D01*
G03X105766Y407114I71J-394D01*
G37*
G36*
G01X1467549Y405996D02*
G02Y407550I-1167J777D01*
G03X1468215I333J222D01*
G02Y405996I1167J-777D01*
G03X1467549I-333J-222D01*
G37*
G36*
G01X1513552Y408921D02*
G02X1511886Y408561I-598J-1268D01*
G03X1511752Y409182I-305J259D01*
G02X1511125Y409769I599J1268D01*
G03X1510425I-350J-194D01*
G02Y411131I-1225J681D01*
G03X1511125I350J194D01*
G02X1513418Y409542I1226J-680D01*
G03X1513552Y408921I305J-259D01*
G37*
G36*
G01X1613554Y410172D02*
G02X1611843Y409975I-729J-1198D01*
G03X1611771Y410602I-280J286D01*
G02X1613482Y410799I729J1198D01*
G03X1613554Y410172I280J-286D01*
G37*
G36*
G01X1440497Y410646D02*
G02X1439003Y410566I-684J-1224D01*
G03X1438967Y411242I-231J327D01*
G02X1440461Y411322I684J1224D01*
G03X1440497Y410646I231J-327D01*
G37*
G36*
G01X798376Y410593D02*
G02X797035Y411222I-1176J-763D01*
G03X797324Y411837I-47J397D01*
G02X798834Y413962I1176J763D01*
G03X799302Y414494I95J388D01*
G02X800276Y413638I1308J506D01*
G03X799808Y413106I-95J-388D01*
G02X798665Y411208I-1308J-506D01*
G03X798376Y410593I47J-397D01*
G37*
G36*
G01X1395067Y411723D02*
G02X1392890Y413473I-1167J778D01*
G03Y414027I-288J277D01*
G02X1393952Y416401I1010J973D01*
G03X1394357Y416888I14J400D01*
G02X1397076Y416819I1368J305D01*
G03X1397337Y416332I386J-107D01*
G02X1397910Y414027I-437J-1332D01*
G03Y413473I288J-277D01*
G02X1395733Y411723I-1010J-972D01*
G03X1395067I-333J-222D01*
G37*
G36*
G01X1535647Y412859D02*
G02X1535604Y414219I-1247J641D01*
G03X1536303Y414241I343J205D01*
G02X1536869Y414825I1246J-642D01*
G03Y415525I-194J350D01*
G02X1536325Y416069I681J1225D01*
G03X1535625I-350J-194D01*
G02Y417431I-1225J681D01*
G03X1536325I350J194D01*
G02X1538775I1225J-681D01*
G03X1539475I350J194D01*
G02X1541925I1225J-681D01*
G03X1542625I350J194D01*
G02X1545075I1225J-681D01*
G03X1545775I350J194D01*
G02Y416069I1225J-681D01*
G03X1545075I-350J-194D01*
G02X1544531Y415525I-1225J681D01*
G03Y414825I194J-350D01*
G02X1542625Y412919I-681J-1225D01*
G03X1541925I-350J-194D01*
G02X1539475I-1225J681D01*
G03X1538775I-350J-194D01*
G02X1536346Y412881I-1225J681D01*
G03X1535647Y412859I-343J-205D01*
G37*
G36*
G01X1516725Y412919D02*
G02Y414281I-1225J681D01*
G03X1517425I350J194D01*
G02X1517969Y414825I1225J-681D01*
G03Y415525I-194J350D01*
G02X1519331I681J1225D01*
G03Y414825I194J-350D01*
G02X1517425Y412919I-681J-1225D01*
G03X1516725I-350J-194D01*
G37*
G36*
G01X1526197Y412959D02*
G02X1524289Y414836I-1247J641D01*
G03X1524300Y415535I-189J353D01*
G02X1525661Y415514I699J1215D01*
G03X1525650Y414815I189J-353D01*
G02X1526154Y414319I-700J-1215D01*
G03X1526853Y414341I343J205D01*
G02X1526896Y412981I1247J-641D01*
G03X1526197Y412959I-343J-205D01*
G37*
G36*
G01X149308Y415575D02*
G02X147577Y415801I-1008J-975D01*
G03X147658Y416422I-206J343D01*
G02X149389Y416196I1008J975D01*
G03X149308Y415575I206J-343D01*
G37*
G36*
G01X621202Y416175D02*
G02X620188Y417547I-1402J25D01*
G03X620698Y417925I110J385D01*
G02X620711Y418092I1402J-25D01*
G03X620412Y418292I-198J28D01*
G02X618977Y420701I-712J1208D01*
G03X618973Y421389I-206J343D01*
G02X621066Y422810I707J1211D01*
G03X621537Y422477I396J60D01*
G02X622612Y422243I263J-1377D01*
G03X622924Y422368I116J163D01*
G02X622969Y422540I1376J-268D01*
G03X622794Y422802I-190J63D01*
G02X623345Y425530I107J1398D01*
G03X623855Y425796I127J379D01*
G02X626596Y425274I1345J-396D01*
G03X626996Y424838I398J-36D01*
G02X627621Y424693I4J-1402D01*
G03X628199Y425062I178J358D01*
G02X628979Y423843I1401J38D01*
G03X628401Y423474I-178J-358D01*
G02X627920Y422378I-1401J-39D01*
G03X627862Y421837I262J-302D01*
G02X626470Y419624I-1125J-837D01*
G03X625996Y419268I-76J-393D01*
G02X624051Y418110I-1396J132D01*
G03X623497Y417777I-156J-368D01*
G02X621712Y416553I-1397J123D01*
G03X621202Y416175I-110J-385D01*
G37*
G36*
G01X52868Y415596D02*
G02X52769Y417119I-1223J685D01*
G03X53439Y417163I321J239D01*
G02X53538Y415640I1223J-685D01*
G03X52868Y415596I-321J-239D01*
G37*
G36*
G01X1510425Y416069D02*
G02X1508519Y417975I-1225J681D01*
G03Y418675I-194J350D01*
G02Y421125I681J1225D01*
G03Y421825I-194J350D01*
G02Y424275I681J1225D01*
G03Y424975I-194J350D01*
G02Y427425I681J1225D01*
G03Y428125I-194J350D01*
G02X1508000Y428625I680J1226D01*
G03X1507303Y428602I-342J-207D01*
G02X1507259Y429974I-1244J647D01*
G03X1507956Y429997I342J207D01*
G02X1510425Y430031I1244J-647D01*
G03X1511125I350J194D01*
G02X1513575I1225J-681D01*
G03X1514275I350J194D01*
G02X1516725I1225J-681D01*
G03X1517425I350J194D01*
G02X1519331Y428125I1225J-681D01*
G03Y427425I194J-350D01*
G02Y424975I-681J-1225D01*
G03Y424275I194J-350D01*
G02X1517425Y422369I-681J-1225D01*
G03X1516725I-350J-194D01*
G02X1516181Y421825I-1225J681D01*
G03Y421125I194J-350D01*
G02X1514275Y419219I-681J-1225D01*
G03X1513575I-350J-194D01*
G02X1513031Y418675I-1225J681D01*
G03Y417975I194J-350D01*
G02X1511125Y416069I-681J-1225D01*
G03X1510425I-350J-194D01*
G37*
G36*
G01X1317793Y417890D02*
G02X1315810Y419873I-973J1010D01*
G03Y420427I-288J277D01*
G02X1317830I1010J973D01*
G03Y419873I288J-277D01*
G02X1317914Y419777I-1012J-970D01*
G03X1318226I156J125D01*
G02X1320417Y419773I1094J-877D01*
G03X1321060Y419796I313J249D01*
G02X1321233Y420003I1157J-791D01*
G03X1321267Y420535I-281J285D01*
G02X1323322Y422429I1104J864D01*
G03X1323881Y422445I271J294D01*
G02X1325879Y422462I1007J-975D01*
G03X1326434Y422453I282J284D01*
G02X1328372Y422426I955J-1027D01*
G03X1328927Y422420I281J285D01*
G02X1330862Y422410I962J-1020D01*
G03X1331416I277J288D01*
G02X1333362I973J-1010D01*
G03X1333916I277J288D01*
G02X1335965Y420501I973J-1010D01*
G03X1335982Y419968I306J-257D01*
G02X1333904Y418087I-1014J-968D01*
G03X1333297Y418088I-304J-260D01*
G02X1331263Y417994I-1062J916D01*
G03X1330709I-277J-288D01*
G02X1328753Y418004I-973J1010D01*
G03X1328198Y418010I-281J-285D01*
G02X1326246Y418038I-962J1020D01*
G03X1325691Y418047I-282J-284D01*
G02X1323784Y418045I-955J1027D01*
G03X1323225Y418029I-271J-294D01*
G02X1321120Y418131I-1008J975D01*
G03X1320477Y418108I-313J-249D01*
G02X1318347Y417890I-1157J792D01*
G03X1317793I-277J-288D01*
G37*
G36*
G01X123483Y419851D02*
G02X121934Y420567I-1241J-652D01*
G03X122200Y421143I-88J390D01*
G02X123749Y420427I1241J652D01*
G03X123483Y419851I88J-390D01*
G37*
G36*
G01X1468429Y419934D02*
G02Y421488I-1167J777D01*
G03X1469095I333J222D01*
G02Y419934I1167J-777D01*
G03X1468429I-333J-222D01*
G37*
G36*
G01X1525631Y424275D02*
G02X1524269I-681J-1225D01*
G03Y424975I-194J350D01*
G02Y427425I681J1225D01*
G03Y428125I-194J350D01*
G02X1525631I681J1225D01*
G03Y427425I194J-350D01*
G02Y424975I-681J-1225D01*
G03Y424275I194J-350D01*
G37*
G36*
G01X1532475Y422369D02*
G02X1530569Y424275I-1225J681D01*
G03Y424975I-194J350D01*
G02Y427425I681J1225D01*
G03Y428125I-194J350D01*
G02X1532475Y430031I681J1225D01*
G03X1533175I350J194D01*
G02X1535625I1225J-681D01*
G03X1536325I350J194D01*
G02X1538775I1225J-681D01*
G03X1539475I350J194D01*
G02X1541381Y428125I1225J-681D01*
G03Y427425I194J-350D01*
G02Y424975I-681J-1225D01*
G03Y424275I194J-350D01*
G02X1539475Y422369I-681J-1225D01*
G03X1538775I-350J-194D01*
G02X1536325I-1225J681D01*
G03X1535625I-350J-194D01*
G02X1533175I-1225J681D01*
G03X1532475I-350J-194D01*
G37*
G36*
G01X1668413Y425845D02*
G02X1667107Y425878I-684J-1224D01*
G03X1667125Y426585I-177J358D01*
G02X1666997Y428952I684J1224D01*
G03X1666962Y429627I-231J326D01*
G02X1668461Y429706I687J1222D01*
G03X1668496Y429031I231J-326D01*
G02X1668431Y426552I-687J-1222D01*
G03X1668413Y425845I177J-358D01*
G37*
G36*
G01X1612829Y430595D02*
G02X1611286Y430758I-894J-1080D01*
G03X1611356Y431420I-185J354D01*
G02X1611473Y433667I894J1080D01*
G03Y434333I-222J333D01*
G02X1613027I777J1167D01*
G03Y433667I222J-333D01*
G02X1612899Y431257I-777J-1167D01*
G03X1612829Y430595I185J-354D01*
G37*
G36*
G01X746945Y431271D02*
G02X745331Y431282I-815J-1141D01*
G03X745336Y431936I-228J329D01*
G02X746950Y431925I815J1141D01*
G03X746945Y431271I228J-329D01*
G37*
G36*
G01X1510425Y434969D02*
G02X1508519Y436875I-1225J681D01*
G03Y437575I-194J350D01*
G02Y440025I681J1225D01*
G03Y440725I-194J350D01*
G02X1510425Y442631I681J1225D01*
G03X1511125I350J194D01*
G02X1513575I1225J-681D01*
G03X1514275I350J194D01*
G02X1516181Y440725I1225J-681D01*
G03Y440025I194J-350D01*
G02X1516725Y439481I-681J-1225D01*
G03X1517425I350J194D01*
G02X1519331Y437575I1225J-681D01*
G03Y436875I194J-350D01*
G02X1517425Y434969I-681J-1225D01*
G03X1516725I-350J-194D01*
G02X1514275I-1225J681D01*
G03X1513575I-350J-194D01*
G02X1511125I-1225J681D01*
G03X1510425I-350J-194D01*
G37*
G36*
G01X1525631Y436875D02*
G02X1524269I-681J-1225D01*
G03Y437575I-194J350D01*
G02X1525631I681J1225D01*
G03Y436875I194J-350D01*
G37*
G36*
G01X1532475Y434969D02*
G02X1530569Y436875I-1225J681D01*
G03Y437575I-194J350D01*
G02X1532475Y439481I681J1225D01*
G03X1533175I350J194D01*
G02X1535625I1225J-681D01*
G03X1536325I350J194D01*
G02X1538775I1225J-681D01*
G03X1539475I350J194D01*
G02X1541381Y437575I1225J-681D01*
G03Y436875I194J-350D01*
G02X1540019I-681J-1225D01*
G03Y437575I-194J350D01*
G02X1539475Y438119I681J1225D01*
G03X1538775I-350J-194D01*
G02X1536325I-1225J681D01*
G03X1535625I-350J-194D01*
G02X1535081Y437575I-1225J681D01*
G03Y436875I194J-350D01*
G02X1533175Y434969I-681J-1225D01*
G03X1532475I-350J-194D01*
G37*
G36*
G01X1665691Y439085D02*
G02X1663833I-929J-1050D01*
G03Y439685I-265J300D01*
G02X1663985Y441902I929J1050D01*
G03Y442568I-222J333D01*
G02X1665539I777J1167D01*
G03Y441902I222J-333D01*
G02X1665812Y441664I-777J-1167D01*
G03X1666412I300J265D01*
G02X1668435Y441745I1050J-929D01*
G03X1668989I277J288D01*
G02X1670527Y439452I973J-1010D01*
G03X1670330Y438907I161J-366D01*
G02X1667769Y438789I-1254J-626D01*
G03X1667411Y439334I-373J145D01*
G02X1666412Y439806I51J1401D01*
G03X1665812I-300J-265D01*
G02X1665691Y439685I-1050J929D01*
G03Y439085I265J-300D01*
G37*
G36*
G01X1544591Y440047D02*
G02X1543231Y440004I-641J-1247D01*
G03X1543209Y440703I-205J343D01*
G02X1543169Y443175I641J1247D01*
G03Y443875I-194J350D01*
G02X1542625Y444419I681J1225D01*
G03X1541925I-350J-194D01*
G02X1539475I-1225J681D01*
G03X1538775I-350J-194D01*
G02X1536325I-1225J681D01*
G03X1535625I-350J-194D01*
G02X1533175I-1225J681D01*
G03X1532475I-350J-194D01*
G02X1530569Y446325I-1225J681D01*
G03Y447025I-194J350D01*
G02X1532475Y448931I681J1225D01*
G03X1533175I350J194D01*
G02X1535625I1225J-681D01*
G03X1536325I350J194D01*
G02X1538775I1225J-681D01*
G03X1539475I350J194D01*
G02X1541381Y447025I1225J-681D01*
G03Y446325I194J-350D01*
G02X1541925Y445781I-681J-1225D01*
G03X1542625I350J194D01*
G02X1544531Y443875I1225J-681D01*
G03Y443175I194J-350D01*
G02X1544569Y440746I-681J-1225D01*
G03X1544591Y440047I205J-343D01*
G37*
G36*
G01X1286805Y441007D02*
G02X1285559Y441448I-1036J-945D01*
G03X1285795Y442113I-60J395D01*
G02X1286911Y444458I1036J945D01*
G03X1287320Y444964I24J399D01*
G02X1288591Y443938I1351J374D01*
G03X1288182Y443432I-24J-399D01*
G02X1287041Y441672I-1351J-374D01*
G03X1286805Y441007I60J-395D01*
G37*
G36*
G01X1725270Y442675D02*
G02X1723640Y442799I-901J-1074D01*
G03X1723689Y443447I-208J342D01*
G02X1723579Y443550I902J1073D01*
G03X1723001I-289J-277D01*
G02Y445492I-1011J971D01*
G03X1723579I289J277D01*
G02X1725804Y445222I1011J-971D01*
G03X1726476Y445191I346J201D01*
G02X1726406Y443679I1144J-811D01*
G03X1725734Y443710I-346J-201D01*
G02X1725319Y443323I-1144J811D01*
G03X1725270Y442675I208J-342D01*
G37*
G36*
G01X1602290Y445654D02*
G02X1601199Y444330I310J-1367D01*
G03X1600710Y444733I-400J13D01*
G02X1601801Y446057I-310J1367D01*
G03X1602290Y445654I400J-13D01*
G37*
G36*
G01X1523025Y444419D02*
G02Y445781I-1225J681D01*
G03X1523725I350J194D01*
G02X1524269Y446325I1225J-681D01*
G03Y447025I-194J350D01*
G02X1525631I681J1225D01*
G03Y446325I194J-350D01*
G02X1523725Y444419I-681J-1225D01*
G03X1523025I-350J-194D01*
G37*
G36*
G01X1504495Y446629D02*
G02X1503769Y448171I-1370J297D01*
G03X1504344Y448442I184J355D01*
G02X1505070Y446900I1370J-297D01*
G03X1504495Y446629I-184J-355D01*
G37*
G36*
G01X1887393Y446949D02*
G02X1887357Y449106I-1063J1061D01*
G03X1887913Y449115I273J292D01*
G02X1890220Y448896I1063J-1061D01*
G03X1890882I331J224D01*
G02X1893369Y448897I1244J-842D01*
G03X1894032I332J224D01*
G02Y447211I1243J-843D01*
G03X1893369I-331J-224D01*
G02X1890882Y447212I-1243J843D01*
G03X1890220I-331J-224D01*
G02X1887949Y446958I-1244J842D01*
G03X1887393Y446949I-273J-292D01*
G37*
G36*
G01X1918547Y447249D02*
G02X1916039Y447364I-1225J681D01*
G03X1915340Y447424I-366J-162D01*
G02X1915456Y448766I-1167J777D01*
G03X1916155Y448706I366J162D01*
G02X1918547Y448611I1167J-776D01*
G03X1919247I350J194D01*
G02Y447249I1225J-681D01*
G03X1918547I-350J-194D01*
G37*
G36*
G01X1516725Y447569D02*
G02X1514777Y449451I-1225J681D01*
G03X1514753Y450151I-205J343D01*
G02X1516112Y450199I636J1249D01*
G03X1516136Y449499I205J-343D01*
G02X1516725Y448931I-636J-1249D01*
G03X1517425I350J194D01*
G02X1517996Y449490I1225J-681D01*
G03X1518002Y450195I-186J354D01*
G02X1519896Y452114I673J1230D01*
G03X1520590Y452108I349J196D01*
G02X1520579Y450711I1210J-708D01*
G03X1519885Y450717I-349J-196D01*
G02X1519329Y450185I-1210J708D01*
G03X1519323Y449480I186J-354D01*
G02X1517425Y447569I-673J-1230D01*
G03X1516725I-350J-194D01*
G37*
G36*
G01X1933562Y449612D02*
G02X1933835Y451960I-3243J1567D01*
G03X1934464Y451726I390J87D01*
G02X1934228Y449696I836J-1126D01*
G03X1933562Y449612I-306J-258D01*
G37*
G36*
G01X1887331Y453292D02*
G02X1887255Y455349I-1131J988D01*
G03X1887837Y455371I281J285D01*
G02X1890212Y455225I1131J-988D01*
G03X1890874I331J224D01*
G02Y453541I1244J-842D01*
G03X1890212I-331J-224D01*
G02X1887913Y453314I-1244J842D01*
G03X1887331Y453292I-281J-285D01*
G37*
G36*
G01X1842797Y453544D02*
G02Y455098I-1167J777D01*
G03X1843463I333J222D01*
G02Y453544I1167J-777D01*
G03X1842797I-333J-222D01*
G37*
G36*
G01X22025Y453470D02*
G02X20075Y455751I-1027J1096D01*
G03Y456381I-246J315D01*
G02X20300Y458896I923J1185D01*
G03X20326Y459590I-185J354D01*
G02X22145Y461962I792J1276D01*
G03X22691I273J292D01*
G02X24745I1027J-1096D01*
G03X25291I273J292D01*
G02X27368Y461940I1027J-1096D01*
G03X27930Y461942I280J286D01*
G02X29686Y459546I1058J-1066D01*
G03X29660Y458852I185J-354D01*
G02X29791Y456391I-792J-1276D01*
G03Y455761I246J-315D01*
G02X27818Y453502I-923J-1185D01*
G03X27256Y453500I-280J-286D01*
G02X25171Y453470I-1058J1066D01*
G03X24625I-273J-292D01*
G02X22571I-1027J1096D01*
G03X22025I-273J-292D01*
G37*
G36*
G01X620740Y465350D02*
G02X619173Y464668I-340J-1360D01*
G03X618920Y465250I-350J194D01*
G02X618450Y467754I340J1360D01*
G03X618479Y468385I-231J327D01*
G02X620200Y468306I911J1065D01*
G03X620171Y467675I231J-327D01*
G02X620487Y465932I-911J-1065D01*
G03X620740Y465350I350J-194D01*
G37*
G36*
G01X-5187Y465904D02*
G02X-6694Y466110I-913J-1064D01*
G03X-6603Y466776I-169J362D01*
G02X-5096Y466570I913J1064D01*
G03X-5187Y465904I169J-362D01*
G37*
G36*
G01X1916064Y467856D02*
G02Y466143I1234J-857D01*
G03X1915407I-329J-228D01*
G02X1912920Y466172I-1234J857D01*
G03X1912252I-334J-220D01*
G02Y467828I-1253J828D01*
G03X1912920I334J220D01*
G02X1915407Y467856I1253J-828D01*
G03X1916064I328J228D01*
G37*
G36*
G01X635060Y468734D02*
G02X633769Y469117I-1027J-1096D01*
G03X633980Y469794I-71J393D01*
G02X635277Y472157I987J996D01*
G03X635761Y472605I88J390D01*
G02X636838Y471442I1387J204D01*
G03X636354Y470994I-88J-390D01*
G02X635252Y469417I-1387J-204D01*
G03X635060Y468734I82J-391D01*
G37*
G36*
G01X1617774Y469168D02*
G02Y470722I-1167J777D01*
G03X1618440I333J222D01*
G02Y469168I1167J-777D01*
G03X1617774I-333J-222D01*
G37*
G36*
G01X1911277Y473167D02*
G02X1909723I-777J-1167D01*
G03Y473833I-222J333D01*
G02X1911277I777J1167D01*
G03Y473167I222J-333D01*
G37*
G36*
G01X607004Y472635D02*
G02X604816Y474367I-1179J759D01*
G03Y474921I-288J277D01*
G02X606836I1010J973D01*
G03Y474367I288J-277D01*
G02X606961Y474216I-1015J-967D01*
G03X607622Y474234I324J235D01*
G02X607665Y472653I1178J-759D01*
G03X607004Y472635I-324J-235D01*
G37*
G36*
G01X66784Y476042D02*
G02X65693Y476991I-1334J-432D01*
G03X66143Y477508I70J394D01*
G02X67234Y476559I1334J432D01*
G03X66784Y476042I-70J-394D01*
G37*
G36*
G01X1841917Y474947D02*
G02Y476501I-1167J777D01*
G03X1842583I333J222D01*
G02Y474947I1167J-777D01*
G03X1841917I-333J-222D01*
G37*
G36*
G01X4127Y479339D02*
G02X3786Y477842I973J-1009D01*
G03X3133Y477991I-375J-139D01*
G02X931Y478326I-973J1009D01*
G03X229I-351J-192D01*
G02Y479674I-1229J674D01*
G03X931I351J192D01*
G02X1566Y480270I1229J-674D01*
G03X1661Y480932I-170J362D01*
G02X3795Y482698I928J1051D01*
G03X4483I344J204D01*
G02Y481268I1206J-715D01*
G03X3795I-344J-204D01*
G02X3183Y480713I-1206J715D01*
G03X3088Y480051I170J-362D01*
G02X3474Y479488I-928J-1050D01*
G03X4127Y479339I375J139D01*
G37*
G36*
G01X90883Y478991D02*
G02X90312Y480342I-1386J210D01*
G03X90940Y480608I232J325D01*
G02X93029Y481611I1386J-210D01*
G03X93622Y481881I200J346D01*
G02X94295Y480399I1376J-269D01*
G03X93702Y480129I-200J-346D01*
G02X91511Y479257I-1376J269D01*
G03X90883Y478991I-232J-325D01*
G37*
G36*
G01X1599811Y478370D02*
G02Y480080I-1111J855D01*
G03X1600446I317J243D01*
G02Y478370I1111J-855D01*
G03X1599811I-317J-243D01*
G37*
G36*
G01X1570800Y480997D02*
G02X1569699Y482101I-1375J-271D01*
G03X1570170Y482571I78J392D01*
G02X1571271Y481467I1375J271D01*
G03X1570800Y480997I-78J-392D01*
G37*
G36*
G01X626879Y481069D02*
G02X626695Y482403I-1310J499D01*
G03X627390Y482499I321J239D01*
G02X627574Y481165I1310J-499D01*
G03X626879Y481069I-321J-239D01*
G37*
G36*
G01X32607Y481958D02*
G02X32544Y483698I-1130J830D01*
G03X33170Y483720I304J259D01*
G02X33233Y481980I1130J-830D01*
G03X32607Y481958I-304J-259D01*
G37*
G36*
G01X1688120Y485257D02*
G02X1686836Y485235I-621J-1257D01*
G03X1686823Y485946I-190J352D01*
G02X1688416Y488213I620J1257D01*
G03X1688970I277J288D01*
G02X1690893Y488234I973J-1010D01*
G03X1691448Y488247I271J294D01*
G02X1691493Y486228I995J-988D01*
G03X1690938Y486215I-271J-294D01*
G02X1688970Y486193I-995J988D01*
G03X1688416I-277J-288D01*
G02X1688107Y485968I-972J1010D01*
G03X1688120Y485257I190J-352D01*
G37*
G36*
G01X1457304Y487077D02*
G02X1455890Y487072I-703J-1213D01*
G03X1455888Y487763I-203J345D01*
G02X1457302Y487768I703J1213D01*
G03X1457304Y487077I203J-345D01*
G37*
G36*
G01X657051Y487930D02*
G02X655110Y487893I-951J-1030D01*
G03X655099Y488470I-282J283D01*
G02X657402Y489870I951J1030D01*
G03X658073Y489694I386J105D01*
G02X657718Y488339I997J-985D01*
G03X657047Y488515I-386J-105D01*
G02X657040Y488507I-1056J917D01*
G03X657051Y487930I282J-283D01*
G37*
G36*
G01X1642122Y488168D02*
G02X1641073Y489131I-1341J-408D01*
G03X1641539Y489639I83J391D01*
G02X1642588Y488676I1341J408D01*
G03X1642122Y488168I-83J-391D01*
G37*
G36*
G01X729744Y488062D02*
G02X729310Y489399I-1371J294D01*
G03X729968Y489613I267J298D01*
G02X730402Y488276I1371J-294D01*
G03X729744Y488062I-267J-298D01*
G37*
G36*
G01X1641064Y497040D02*
G02X1640645Y495487I899J-1076D01*
G03X1640012Y495658I-376J-136D01*
G02X1640431Y497211I-899J1076D01*
G03X1641064Y497040I376J136D01*
G37*
G36*
G01X1590192Y495198D02*
G02Y496752I-1167J777D01*
G03X1590858I333J222D01*
G02Y495198I1167J-777D01*
G03X1590192I-333J-222D01*
G37*
G36*
G01X1268014Y497007D02*
G02X1267785Y495327I992J-991D01*
G03X1267154Y495413I-348J-197D01*
G02X1267383Y497093I-992J991D01*
G03X1268014Y497007I348J197D01*
G37*
G36*
G01X1279705Y497522D02*
G02X1279311Y495877I890J-1083D01*
G03X1278690Y496025I-366J-161D01*
G02X1279084Y497670I-890J1083D01*
G03X1279705Y497522I366J161D01*
G37*
G36*
G01X1789242Y495925D02*
G02X1786803Y496003I-1197J729D01*
G03X1786100Y496014I-354J-185D01*
G02X1786120Y497352I-1222J687D01*
G03X1786823Y497341I354J185D01*
G02X1789235Y497396I1222J-687D01*
G03X1789916Y497399I340J211D01*
G02X1789923Y495928I1197J-730D01*
G03X1789242Y495925I-340J-211D01*
G37*
G36*
G01X1728638Y501596D02*
X1733639D01*
G02X1735150Y500095I0J-1511D01*
G01Y500000D01*
X1735141Y499916D01*
G02X1733639Y498574I-1502J169D01*
G01X1729462D01*
G03X1729184Y497886I0J-400D01*
G02X1726963Y495872I-1046J-1078D01*
G03X1726422Y495952I-313J-249D01*
G02X1724064Y497224I-856J1234D01*
G03X1723649Y497634I-400J11D01*
G02X1723676Y500635I-58J1501D01*
G03X1724098Y501027I22J399D01*
G02X1727036Y501439I1502J-27D01*
G03X1727674Y501248I383J117D01*
G02X1728638Y501596I965J-1163D01*
G37*
G36*
G01X689432Y497063D02*
G02X689149Y498770I-1230J673D01*
G03X689770Y498873I270J295D01*
G02X690053Y497166I1230J-673D01*
G03X689432Y497063I-270J-295D01*
G37*
G36*
G01X1616058Y497784D02*
G02X1615976Y499474I-1158J791D01*
G03X1616613Y499505I307J256D01*
G02X1616695Y497815I1158J-791D01*
G03X1616058Y497784I-307J-256D01*
G37*
G36*
G01X55164Y501438D02*
G02X53088Y503514I-1264J812D01*
G03Y504186I-216J336D01*
G02X55164Y506262I812J1264D01*
G03X55836I336J216D01*
G02X58364I1264J-812D01*
G03X59036I336J216D01*
G02X61112Y504186I1264J-812D01*
G03Y503514I216J-336D01*
G02X59036Y501438I-812J-1264D01*
G03X58364I-336J-216D01*
G02X55836I-1264J812D01*
G03X55164I-336J-216D01*
G37*
G36*
G01X1565777Y504496D02*
G02X1564223I-777J-1167D01*
G03Y505162I-222J333D01*
G02X1565777I777J1167D01*
G03Y504496I222J-333D01*
G37*
G36*
G01X680274Y503064D02*
G02X680159Y504602I-1225J682D01*
G03X680825Y504652I317J245D01*
G02X680940Y503114I1225J-682D01*
G03X680274Y503064I-317J-245D01*
G37*
G36*
G01X1689443Y505238D02*
G02X1688723Y503689I648J-1243D01*
G03X1688148Y503957I-391J-87D01*
G02X1686391Y504342I-648J1243D01*
G03X1685759I-316J-245D01*
G02Y506058I-1109J858D01*
G03X1686391I316J245D01*
G02X1688868Y505506I1109J-858D01*
G03X1689443Y505238I391J87D01*
G37*
G36*
G01X1333988Y506103D02*
G02X1331680Y507358I-1388J197D01*
G03X1331658Y507979I-263J302D01*
G02X1333892Y509263I842J1121D01*
G03X1334470Y508952I398J46D01*
G02X1334543Y506413I630J-1252D01*
G03X1333988Y506103I-159J-367D01*
G37*
G36*
G01X1534568Y510040D02*
G02X1532953Y510276I-972J-1010D01*
G03X1533047Y510920I-183J356D01*
G02X1534662Y510684I972J1010D01*
G03X1534568Y510040I183J-356D01*
G37*
G36*
G01X1401610Y509379D02*
G02X1401229Y511321I-1165J780D01*
G03X1401785Y511430I224J332D01*
G02X1404117Y511427I1165J-780D01*
G03X1404783I333J222D01*
G02X1406073Y512047I1167J-777D01*
G03X1406502Y512513I35J398D01*
G02X1407761Y511354I1382J238D01*
G03X1407332Y510888I-35J-398D01*
G02X1404783Y509873I-1382J-238D01*
G03X1404117I-333J-222D01*
G02X1402166Y509488I-1167J777D01*
G03X1401610Y509379I-224J-332D01*
G37*
G36*
G01X1910967Y509923D02*
G02Y511477I-1167J777D01*
G03X1911633I333J222D01*
G02Y509923I1167J-777D01*
G03X1910967I-333J-222D01*
G37*
G36*
G01X1296853Y509800D02*
G02X1294958Y511866I-973J1010D01*
G03X1294975Y512452I-263J301D01*
G02X1295183Y514617I985J998D01*
G03Y515283I-222J333D01*
G02Y517617I777J1167D01*
G03Y518283I-222J333D01*
G02X1296933Y520460I778J1167D01*
G03X1297487I277J288D01*
G02X1299237Y518283I972J-1010D01*
G03Y517617I222J-333D01*
G02Y515283I-777J-1167D01*
G03Y514617I222J-333D01*
G02X1299382Y512394I-777J-1167D01*
G03X1299365Y511808I263J-301D01*
G02X1297407Y509800I-985J-998D01*
G03X1296853I-277J-288D01*
G37*
G36*
G01X713293Y511963D02*
G02X713170Y513605I-1193J736D01*
G03X713816Y513654I305J259D01*
G02X713939Y512012I1193J-736D01*
G03X713293Y511963I-305J-259D01*
G37*
G36*
G01X1828753Y514383D02*
G02X1826598Y513175I-753J-1183D01*
G03X1826088Y513553I-400J-7D01*
G02X1826184Y516216I-388J1347D01*
G03X1826716Y516527I137J375D01*
G02X1827212Y517385I1384J-227D01*
G03X1827234Y517984I-254J309D01*
G02X1829088Y517915I966J1016D01*
G03X1829066Y517316I254J-309D01*
G02X1828775Y515071I-966J-1016D01*
G03X1828753Y514383I192J-351D01*
G37*
G36*
G01X1797553Y514117D02*
G02X1796878Y515400I-1400J83D01*
G03X1797483Y515719I206J343D01*
G02X1799952Y516543I1400J-83D01*
G03X1800555Y516535I305J259D01*
G02X1800531Y514693I1045J-935D01*
G03X1799928Y514701I-305J-259D01*
G02X1798158Y514436I-1045J935D01*
G03X1797553Y514117I-206J-343D01*
G37*
G36*
G01X1340419Y516938D02*
G02X1339015Y517074I-819J-1138D01*
G03X1339081Y517762I-167J363D01*
G02X1340485Y517626I819J1138D01*
G03X1340419Y516938I167J-363D01*
G37*
G36*
G01X1861057Y521367D02*
G02X1859312Y521214I-777J-1167D01*
G03X1859126Y521894I-276J290D01*
G02X1861122Y522069I728J3169D01*
G03X1861057Y521367I156J-368D01*
G37*
G36*
G01X41429Y521343D02*
G02X40279Y522116I-1318J-720D01*
G03X40675Y522705I45J397D01*
G02X41825Y521932I1318J720D01*
G03X41429Y521343I-45J-397D01*
G37*
G36*
G01X1804213Y522569D02*
G02X1802541Y526180I-3227J698D01*
G03X1803122Y526459I188J353D01*
G02X1803575Y527253I1378J-260D01*
G03X1803409Y527942I-264J301D01*
G02X1804677Y528248I343J1359D01*
G03X1804843Y527559I264J-301D01*
G02X1805726Y525521I-343J-1359D01*
G03X1806076Y524927I350J-194D01*
G02X1804931Y522716I0J-1402D01*
G03X1804213Y522569I-327J-231D01*
G37*
G36*
G01X1415993Y520663D02*
G02X1415941Y522214I-1193J736D01*
G03X1416607Y522237I325J233D01*
G02X1416659Y520686I1193J-736D01*
G03X1415993Y520663I-325J-233D01*
G37*
G36*
G01X90674Y523007D02*
G02X90451Y521273I976J-1007D01*
G03X89831Y521352I-342J-208D01*
G02X90054Y523086I-976J1007D01*
G03X90674Y523007I342J208D01*
G37*
G36*
G01X47646Y524933D02*
G02X46049Y525384I-1139J-980D01*
G03X46230Y526025I-122J381D01*
G02X47827Y525574I1139J980D01*
G03X47646Y524933I122J-381D01*
G37*
G36*
G01X1437747Y525335D02*
G02X1436550Y526531I-1389J-193D01*
G03X1437001Y526982I55J396D01*
G02X1438198Y525786I1389J193D01*
G03X1437747Y525335I-55J-396D01*
G37*
G36*
G01X717110Y526173D02*
G02X715090I-1010J-973D01*
G03Y526727I-288J277D01*
G02X715006Y526823I1012J970D01*
G03X714694I-156J-125D01*
G02X713488Y526302I-1094J877D01*
G03X713067Y525810I-32J-399D01*
G02X711816Y526881I-1363J-327D01*
G03X712237Y527373I32J399D01*
G02X712590Y528673I1363J328D01*
G03Y529227I-288J277D01*
G02Y531173I1010J973D01*
G03Y531727I-288J277D01*
G02X714573Y533710I1010J973D01*
G03X715127I277J288D01*
G02X717110Y531727I973J-1010D01*
G03Y531173I288J-277D01*
G02Y529227I-1010J-973D01*
G03Y528673I288J-277D01*
G02Y526727I-1010J-973D01*
G03Y526173I288J-277D01*
G37*
G36*
G01X1296749Y526817D02*
G02X1294883Y528867I-1089J883D01*
G03Y529533I-222J333D01*
G02Y531867I777J1167D01*
G03Y532533I-222J333D01*
G02Y534867I777J1167D01*
G03Y535533I-222J333D01*
G02X1296749Y537583I777J1167D01*
G03X1297371I311J252D01*
G02X1299237Y535533I1089J-883D01*
G03Y534867I222J-333D01*
G02Y532533I-777J-1167D01*
G03Y531867I222J-333D01*
G02Y529533I-777J-1167D01*
G03Y528867I222J-333D01*
G02X1297371Y526817I-777J-1167D01*
G03X1296749I-311J-252D01*
G37*
G36*
G01X686650Y529153D02*
G02X685186Y528521I-275J-1375D01*
G03X684925Y529125I-339J212D01*
G02X683958Y531151I275J1375D01*
G03X683803Y531684I-354J186D01*
G02X685742Y532249I697J1216D01*
G03X685897Y531716I354J-186D01*
G02X686389Y529757I-697J-1216D01*
G03X686650Y529153I339J-212D01*
G37*
G36*
G01X652317Y529423D02*
G02X650121Y531152I-1167J777D01*
G03X650110Y531707I-293J272D01*
G02X652283Y533453I991J992D01*
G03X652971Y533475I337J214D01*
G02X655151Y531770I1229J-675D01*
G03X655140Y531193I271J-294D01*
G02X652983Y529423I-990J-993D01*
G03X652317I-333J-222D01*
G37*
G36*
G01X658223Y530290D02*
G02X656473Y532467I-972J1010D01*
G03Y533133I-222J333D01*
G02X658223Y535310I778J1167D01*
G03X658777I277J288D01*
G02X660527Y533133I972J-1010D01*
G03Y532467I222J-333D01*
G02X658777Y530290I-778J-1167D01*
G03X658223I-277J-288D01*
G37*
G36*
G01X1460414Y532386D02*
G02X1460352Y530695I1086J-886D01*
G03X1459715Y530718I-327J-230D01*
G02X1459777Y532409I-1086J886D01*
G03X1460414Y532386I327J230D01*
G37*
G36*
G01X726180Y532943D02*
G02X726154Y534496I-1180J757D01*
G03X726820Y534507I329J227D01*
G02X726846Y532954I1180J-757D01*
G03X726180Y532943I-329J-227D01*
G37*
G36*
G01X63667Y534723D02*
G02Y536277I-1167J777D01*
G03X64333I333J222D01*
G02X66667I1167J-777D01*
G03X67333I333J222D01*
G02Y534723I1167J-777D01*
G03X66667I-333J-222D01*
G02X64333I-1167J777D01*
G03X63667I-333J-222D01*
G37*
G36*
G01X1385303Y534550D02*
G02X1383533Y536707I-993J990D01*
G03Y537373I-222J333D01*
G02Y539707I777J1167D01*
G03Y540373I-222J333D01*
G02X1382961Y541923I777J1167D01*
G03X1382522Y542429I-384J110D01*
G02X1383680Y543435I-191J1389D01*
G03X1384119Y542929I384J-110D01*
G02X1385295Y542538I191J-1389D01*
G03X1385848Y542529I281J284D01*
G02X1386507Y542871I952J-1029D01*
G03X1386753Y543490I-83J391D01*
G02X1388200Y542915I1154J796D01*
G03X1387954Y542296I83J-391D01*
G02X1387577Y540333I-1154J-796D01*
G03Y539667I222J-333D01*
G02X1387632Y537372I-777J-1167D01*
G03Y536728I238J-322D01*
G02X1385856Y534564I-832J-1128D01*
G03X1385303Y534550I-269J-296D01*
G37*
G36*
G01X71506Y537405D02*
G02X69730Y539561I-984J999D01*
G03X69725Y540224I-226J330D01*
G02X71455Y542419I774J1169D01*
G03X72012Y542430I273J292D01*
G02X73953Y542481I997J-986D01*
G03X74497Y542486I269J296D01*
G02X76433Y542478I964J-1018D01*
G03X76988I277J288D01*
G02X78905Y542504I972J-1010D01*
G03X79444I270J295D01*
G02X81166Y540301I944J-1036D01*
G03Y539635I222J-333D01*
G02X79444Y537432I-778J-1167D01*
G03X78905I-270J-295D01*
G02X76988Y537458I-945J1036D01*
G03X76433I-277J-288D01*
G02X74517Y537431I-972J1010D01*
G03X73973Y537426I-269J-296D01*
G02X72058Y537414I-964J1018D01*
G03X71506Y537405I-271J-294D01*
G37*
G36*
G01X646927Y541517D02*
G02X645373I-777J-1167D01*
G03Y542183I-222J333D01*
G02Y544517I777J1167D01*
G03Y545183I-222J333D01*
G02X646927I777J1167D01*
G03Y544517I222J-333D01*
G02Y542183I-777J-1167D01*
G03Y541517I222J-333D01*
G37*
G36*
G01X1940620Y541958D02*
G02X1938484Y540203I-920J-1058D01*
G03X1937951Y540358I-347J-199D01*
G02X1938516Y542297I-651J1242D01*
G03X1939049Y542142I347J199D01*
G02X1939064Y542150I667J-1233D01*
G03X1939077Y542499I-91J178D01*
G02X1938408Y543537I723J1201D01*
G03X1937830Y543848I-398J-46D01*
G02X1937855Y546340I-630J1252D01*
G03X1938432Y546606I187J354D01*
G02X1940771Y545289I1368J-306D01*
G03Y544711I277J-289D01*
G02X1940642Y542579I-971J-1011D01*
G03X1940620Y541958I241J-319D01*
G37*
G36*
G01X1922965Y544767D02*
G02X1921424Y545028I-965J-1017D01*
G03X1921535Y545683I-164J365D01*
G02X1923076Y545422I965J1017D01*
G03X1922965Y544767I164J-365D01*
G37*
G36*
G01X1915609Y545971D02*
G02X1914125Y546118I-859J-1108D01*
G03X1914191Y546792I-179J358D01*
G02X1915675Y546645I859J1108D01*
G03X1915609Y545971I179J-358D01*
G37*
G36*
G01X1453744Y545652D02*
G02X1450890Y544963I-1352J-654D01*
G03X1450364Y545334I-400J-9D01*
G02X1448818Y545799I-443J1330D01*
G03X1448175Y545780I-314J-247D01*
G02X1448126Y547443I-1153J798D01*
G03X1448769Y547462I314J247D01*
G02X1451312Y546480I1153J-798D01*
G03X1451614Y546283I198J-26D01*
G02X1451651Y546305I786J-1280D01*
G03X1451814Y546827I-197J348D01*
G02X1454297Y548469I1352J654D01*
G03X1454910Y548482I301J263D01*
G02X1454949Y546552I1170J-942D01*
G03X1454336Y546539I-301J-263D01*
G02X1453907Y546174I-1171J941D01*
G03X1453744Y545652I197J-348D01*
G37*
G36*
G01X1811291Y544448D02*
G02X1811069Y546068I-1239J655D01*
G03X1811713Y546156I290J275D01*
G02X1811935Y544536I1239J-655D01*
G03X1811291Y544448I-290J-275D01*
G37*
G36*
G01X1278982Y546573D02*
G02X1277957Y545548I336J-1361D01*
G03X1277473Y546032I-389J95D01*
G02X1278498Y547057I-336J1361D01*
G03X1278982Y546573I389J-95D01*
G37*
G36*
G01X1899954Y546114D02*
G02X1898485Y546604I-1104J-864D01*
G03X1898696Y547236I-104J386D01*
G02X1898565Y547436I1103J865D01*
G03X1898010Y547591I-352J-190D01*
G02X1898535Y549464I-710J1209D01*
G03X1899090Y549309I352J190D01*
G02X1900165Y546746I710J-1209D01*
G03X1899954Y546114I104J-386D01*
G37*
G36*
G01X1857125Y548275D02*
G02X1855432Y549365I-1375J-275D01*
G03X1855733Y549833I-91J389D01*
G02X1856137Y551119I1375J275D01*
G03Y551697I-277J289D01*
G02X1856097Y551737I971J1011D01*
G03X1855519I-289J-277D01*
G02X1853146Y553039I-1011J971D01*
G03X1852678Y553526I-389J95D01*
G02X1853762Y554569I-278J1374D01*
G03X1854230Y554082I389J-95D01*
G02X1855519Y553679I278J-1374D01*
G03X1856097I289J277D01*
G02X1858119I1011J-971D01*
G03X1858697I289J277D01*
G02Y551737I1011J-971D01*
G03X1858119I-289J-277D01*
G02X1858079Y551697I-1011J971D01*
G03Y551119I277J-289D01*
G02X1857426Y548743I-971J-1011D01*
G03X1857125Y548275I91J-389D01*
G37*
G36*
G01X1849505Y549465D02*
G02X1848218Y549425I-605J-1265D01*
G03X1848195Y550135I-195J349D01*
G02X1849482Y550175I605J1265D01*
G03X1849505Y549465I195J-349D01*
G37*
G36*
G01X1836978Y550660D02*
G02X1836688Y549207I1022J-959D01*
G03X1836022Y549340I-374J-141D01*
G02X1836312Y550793I-1022J959D01*
G03X1836978Y550660I374J141D01*
G37*
G36*
G01X730541Y549008D02*
G02X728773Y551167I-991J992D01*
G03Y551833I-222J333D01*
G02Y554167I777J1167D01*
G03Y554833I-222J333D01*
G02X730541Y556992I777J1167D01*
G03X731107I283J282D01*
G02X732875Y554833I991J-992D01*
G03Y554167I222J-333D01*
G02Y551833I-777J-1167D01*
G03Y551167I222J-333D01*
G02X731107Y549008I-777J-1167D01*
G03X730541I-283J-282D01*
G37*
G36*
G01X1816995Y551606D02*
G02X1815565I-715J-1206D01*
G03Y552294I-204J344D01*
G02X1816995I715J1206D01*
G03Y551606I204J-344D01*
G37*
G36*
G01X1300777Y553567D02*
G02X1299223I-777J-1167D01*
G03Y554233I-222J333D01*
G02Y556567I777J1167D01*
G03Y557233I-222J333D01*
G02X1300777I777J1167D01*
G03Y556567I222J-333D01*
G02Y554233I-777J-1167D01*
G03Y553567I222J-333D01*
G37*
G36*
G01X1318667Y551623D02*
G02X1316723Y553567I-1167J777D01*
G03Y554233I-222J333D01*
G02Y556567I777J1167D01*
G03Y557233I-222J333D01*
G02X1318667Y559177I777J1167D01*
G03X1319333I333J222D01*
G02X1321667I1167J-777D01*
G03X1322333I333J222D01*
G02X1324277Y557233I1167J-777D01*
G03Y556567I222J-333D01*
G02Y554233I-777J-1167D01*
G03Y553567I222J-333D01*
G02X1322333Y551623I-777J-1167D01*
G03X1321667I-333J-222D01*
G02X1319333I-1167J777D01*
G03X1318667I-333J-222D01*
G37*
G36*
G01X658306Y551785D02*
G02Y553215I-1206J715D01*
G03X658994I344J204D01*
G02Y551785I1206J-715D01*
G03X658306I-344J-204D01*
G37*
G36*
G01X1755319Y553024D02*
G02X1754626Y554754I-1319J476D01*
G03X1755181Y554976I179J358D01*
G02X1757667Y555277I1319J-476D01*
G03X1758333I333J222D01*
G02Y553723I1167J-777D01*
G03X1757667I-333J-222D01*
G02X1755874Y553246I-1167J777D01*
G03X1755319Y553024I-179J-358D01*
G37*
G36*
G01X64667Y553723D02*
G02X62723Y555667I-1167J777D01*
G03Y556333I-222J333D01*
G02X64667Y558277I777J1167D01*
G03X65333I333J222D01*
G02X67667I1167J-777D01*
G03X68333I333J222D01*
G02X70667I1167J-777D01*
G03X71333I333J222D01*
G02X73667I1167J-777D01*
G03X74333I333J222D01*
G02X76667I1167J-777D01*
G03X77333I333J222D01*
G02X79667I1167J-777D01*
G03X80333I333J222D01*
G02X82277Y556333I1167J-777D01*
G03Y555667I222J-333D01*
G02X80333Y553723I-777J-1167D01*
G03X79667I-333J-222D01*
G02X77333I-1167J777D01*
G03X76667I-333J-222D01*
G02X74333I-1167J777D01*
G03X73667I-333J-222D01*
G02X71333I-1167J777D01*
G03X70667I-333J-222D01*
G02X68333I-1167J777D01*
G03X67667I-333J-222D01*
G02X65333I-1167J777D01*
G03X64667I-333J-222D01*
G37*
G36*
G01X1913006Y556655D02*
G02X1912416Y555278I794J-1155D01*
G03X1911794Y555545I-395J-63D01*
G02X1912384Y556922I-794J1155D01*
G03X1913006Y556655I395J63D01*
G37*
G36*
G01X1536158Y560624D02*
G02X1533730Y558862I-1261J-817D01*
G03X1533118Y558873I-311J-252D01*
G02X1530920Y558802I-1132J987D01*
G03X1530352I-284J-282D01*
G02X1528220I-1066J1058D01*
G03X1527652I-284J-282D01*
G02X1525145Y560284I-1066J1058D01*
G03X1524714Y560794I-384J113D01*
G02X1525585Y563363I-176J1492D01*
G03X1526163Y563384I279J287D01*
G02X1528351Y563444I1122J-998D01*
G03X1528919I284J282D01*
G02X1531051I1066J-1058D01*
G03X1531619I284J282D01*
G02X1533751I1066J-1058D01*
G03X1534319I284J282D01*
G02X1536210Y563641I1066J-1058D01*
G03X1536830Y563962I220J334D01*
G02X1539013Y565251I1501J-49D01*
G03X1539591Y565660I182J356D01*
G02X1542265Y566782I1489J199D01*
G03X1542895I315J246D01*
G02X1543157Y567044I1185J-923D01*
G03Y567674I-246J315D01*
G02X1545193Y569867I922J1185D01*
G03X1545741Y569824I297J268D01*
G02X1547617Y569834I944J-1168D01*
G03X1548164Y569881I249J313D01*
G02X1550407Y567883I1121J-1000D01*
G03X1550437Y567321I299J-266D01*
G02X1550483Y565145I-1012J-1110D01*
G03X1550477Y564583I282J-284D01*
G02X1548463Y562363I-1081J-1042D01*
G03X1547916Y562316I-249J-313D01*
G02X1545725Y562262I-1121J1000D01*
G03X1545130Y562235I-285J-280D01*
G02X1542901Y562127I-1163J950D01*
G03X1542333I-284J-282D01*
G02X1539806Y562838I-1066J1058D01*
G03X1539461Y562923I-194J-47D01*
G02X1539307Y562772I-1126J994D01*
G03X1539319Y562154I260J-304D01*
G02X1536915Y561289I-934J-1176D01*
G03X1536563Y561454I-196J41D01*
G02X1536261Y561166I-1178J932D01*
G03X1536158Y560624I233J-325D01*
G37*
G36*
G01X1377031Y560781D02*
G02X1375025Y560694I-961J-1021D01*
G03X1375000Y561252I-299J266D01*
G02X1377314Y562642I961J1021D01*
G03X1377988Y562470I386J105D01*
G02X1377599Y561559I1012J-971D01*
G03X1377220Y561656I-200J9D01*
G02X1377006Y561339I-1258J619D01*
G03X1377031Y560781I299J-266D01*
G37*
G36*
G01X1286743Y560598D02*
G02X1286157Y562180I-1343J402D01*
G03X1286757Y562402I217J336D01*
G02X1288885Y563162I1343J-402D01*
G03X1289506Y563450I224J332D01*
G02X1290115Y562138I1394J-150D01*
G03X1289494Y561850I-224J-332D01*
G02X1287343Y560820I-1394J150D01*
G03X1286743Y560598I-217J-336D01*
G37*
G36*
G01X64667Y560723D02*
G02Y562277I-1167J777D01*
G03X65333I333J222D01*
G02X67667I1167J-777D01*
G03X68333I333J222D01*
G02X70667I1167J-777D01*
G03X71333I333J222D01*
G02X73667I1167J-777D01*
G03X74333I333J222D01*
G02X76667I1167J-777D01*
G03X77333I333J222D01*
G02X79667I1167J-777D01*
G03X80333I333J222D01*
G02Y560723I1167J-777D01*
G03X79667I-333J-222D01*
G02X77333I-1167J777D01*
G03X76667I-333J-222D01*
G02X74333I-1167J777D01*
G03X73667I-333J-222D01*
G02X71333I-1167J777D01*
G03X70667I-333J-222D01*
G02X68333I-1167J777D01*
G03X67667I-333J-222D01*
G02X65333I-1167J777D01*
G03X64667I-333J-222D01*
G37*
G36*
G01X1744116Y562666D02*
G02X1742395Y562912I-1016J-966D01*
G03X1742484Y563534I-201J346D01*
G02X1742513Y565496I1016J966D01*
G03X1742447Y566118I-281J285D01*
G02X1742199Y568282I753J1183D01*
G03X1742155Y568881I-285J280D01*
G02X1744001Y569018I845J1119D01*
G03X1744045Y568419I285J-280D01*
G02X1744187Y566304I-845J-1119D01*
G03X1744253Y565682I281J-285D01*
G02X1744205Y563288I-753J-1182D01*
G03X1744116Y562666I201J-346D01*
G37*
G36*
G01X1934521Y563300D02*
G02X1933278Y562368I79J-1400D01*
G03X1932879Y562900I-377J133D01*
G02X1934122Y563832I-79J1400D01*
G03X1934521Y563300I377J-133D01*
G37*
G36*
G01X1417391Y563595D02*
G02X1417219Y561871I1011J-971D01*
G03X1416593Y561933I-337J-215D01*
G02X1416765Y563657I-1011J971D01*
G03X1417391Y563595I337J215D01*
G37*
G36*
G01X1324551Y564312D02*
G02X1322613Y562358I-778J-1167D01*
G03X1321998Y562415I-331J-224D01*
G02X1319833Y562623I-998J985D01*
G03X1319167I-333J-222D01*
G02X1316833I-1167J777D01*
G03X1316167I-333J-222D01*
G02X1313833I-1167J777D01*
G03X1313167I-333J-222D01*
G02X1310833I-1167J777D01*
G03X1310167I-333J-222D01*
G02X1307833I-1167J777D01*
G03X1307167I-333J-222D01*
G02X1304833I-1167J777D01*
G03X1304167I-333J-222D01*
G02X1301990Y564373I-1167J778D01*
G03Y564927I-288J277D01*
G02X1302223Y567067I1010J973D01*
G03Y567733I-222J333D01*
G02X1301990Y569873I777J1167D01*
G03Y570427I-288J277D01*
G02X1304167Y572177I1010J972D01*
G03X1304833I333J222D01*
G02X1307167I1167J-777D01*
G03X1307833I333J222D01*
G02X1310167I1167J-777D01*
G03X1310833I333J222D01*
G02X1313167I1167J-777D01*
G03X1313833I333J222D01*
G02X1316167I1167J-777D01*
G03X1316833I333J222D01*
G02X1319167I1167J-777D01*
G03X1319833I333J222D01*
G02X1322167I1167J-777D01*
G03X1322833I333J222D01*
G02X1325010Y570427I1167J-778D01*
G03Y569873I288J-277D01*
G02X1324809Y567755I-1010J-973D01*
G03X1324758Y567143I230J-327D01*
G02X1324551Y564978I-984J-998D01*
G03Y564312I222J-333D01*
G37*
G36*
G01X645967Y562523D02*
G02Y564077I-1167J777D01*
G03X646633I333J222D01*
G02X648967I1167J-777D01*
G03X649633I333J222D01*
G02X651967I1167J-777D01*
G03X652633I333J222D01*
G02Y562523I1167J-777D01*
G03X651967I-333J-222D01*
G02X649633I-1167J777D01*
G03X648967I-333J-222D01*
G02X646633I-1167J777D01*
G03X645967I-333J-222D01*
G37*
G36*
G01X1781547Y566291D02*
G02X1780064Y566043I-546J-1291D01*
G03X1779953Y566709I-267J298D01*
G02X1779579Y569057I547J1291D01*
G03Y569661I-262J302D01*
G02X1781421I921J1057D01*
G03Y569057I262J-302D01*
G02X1781436Y566957I-921J-1057D01*
G03X1781547Y566291I267J-298D01*
G37*
G36*
G01X1291833Y574879D02*
G02X1290274Y576083I-4430J-4124D01*
G03X1290847Y576550I190J352D01*
G02X1290798Y577116I1343J401D01*
G03X1290376Y577563I-397J48D01*
G02X1291684Y578798I-84J1399D01*
G03X1292106Y578351I397J-48D01*
G02X1292140Y575551I84J-1399D01*
G03X1291833Y574879I-14J-400D01*
G37*
G36*
G01X1936343Y569287D02*
G02X1935512Y567803I557J-1287D01*
G03X1934957Y568113I-396J-57D01*
G02X1935788Y569597I-557J1287D01*
G03X1936343Y569287I396J57D01*
G37*
G36*
G01X1726471Y569981D02*
G02X1724917I-777J-1167D01*
G03Y570647I-222J333D01*
G02X1726471I777J1167D01*
G03Y569981I222J-333D01*
G37*
G36*
G01X1467630Y570975D02*
G02X1467374Y569429I1019J-963D01*
G03X1466719Y569537I-364J-166D01*
G02X1466975Y571083I-1019J963D01*
G03X1467630Y570975I364J166D01*
G37*
G36*
G01X1808834Y571292D02*
G02X1807280I-777J-1167D01*
G03Y571958I-222J333D01*
G02X1808834I777J1167D01*
G03Y571292I222J-333D01*
G37*
G36*
G01X1418208Y569756D02*
G02X1416196Y569715I-1026J955D01*
G03X1415654Y569735I-282J-284D01*
G02X1413758Y571797I-910J1066D01*
G03X1413757Y572366I-282J284D01*
G02X1415676Y574409I986J996D01*
G03X1416233Y574433I266J299D01*
G02X1416588Y574705I1019J-963D01*
G03X1416596Y575405I-190J352D01*
G02X1416340Y575591I691J1220D01*
G03X1415799I-270J-295D01*
G02Y577657I-948J1033D01*
G03X1416340I271J295D01*
G02X1418229Y577663I948J-1033D01*
G03X1418789Y577685I269J296D01*
G02X1420825Y577689I1020J-962D01*
G03X1421424Y577711I290J276D01*
G02X1423286Y575656I1085J-888D01*
G03Y574990I222J-333D01*
G02Y572656I-777J-1167D01*
G03Y571990I222J-333D01*
G02X1421493Y569857I-777J-1167D01*
G03X1420894Y569835I-290J-276D01*
G02X1418791Y569759I-1085J888D01*
G03X1418208Y569756I-290J-276D01*
G37*
G36*
G01X1764596Y575913D02*
G02X1763899Y574647I704J-1213D01*
G03X1763299Y574978I-400J-15D01*
G02X1763996Y576244I-704J1213D01*
G03X1764596Y575913I400J15D01*
G37*
G36*
G01X1386444Y573872D02*
G02X1384021Y574167I-1128J833D01*
G03X1383396Y574322I-370J-153D01*
G02X1383795Y575938I-896J1078D01*
G03X1384420Y575783I370J153D01*
G02X1386266Y575736I896J-1078D01*
G03X1386858Y575793I270J295D01*
G02X1387036Y573929I1128J-833D01*
G03X1386444Y573872I-270J-295D01*
G37*
G36*
G01X72667Y574223D02*
G02X70723Y576167I-1167J777D01*
G03Y576833I-222J333D01*
G02X72667Y578777I777J1167D01*
G03X73333I333J222D01*
G02X75277Y576833I1167J-777D01*
G03Y576167I222J-333D01*
G02X73333Y574223I-777J-1167D01*
G03X72667I-333J-222D01*
G37*
G36*
G01X79667D02*
G02X77723Y576167I-1167J777D01*
G03Y576833I-222J333D01*
G02X79667Y578777I777J1167D01*
G03X80333I333J222D01*
G02X82277Y576833I1167J-777D01*
G03Y576167I222J-333D01*
G02X80333Y574223I-777J-1167D01*
G03X79667I-333J-222D01*
G37*
G36*
G01X1304167Y575223D02*
G02X1302223Y577167I-1167J777D01*
G03Y577833I-222J333D01*
G02X1304167Y579777I777J1167D01*
G03X1304833I333J222D01*
G02X1306777Y577833I1167J-777D01*
G03Y577167I222J-333D01*
G02X1304833Y575223I-777J-1167D01*
G03X1304167I-333J-222D01*
G37*
G36*
G01X1935503Y577183D02*
G02X1935270Y578606I-1303J517D01*
G03X1935947Y578717I305J259D01*
G02X1936180Y577294I1303J-517D01*
G03X1935503Y577183I-305J-259D01*
G37*
G36*
G01X1383529Y580052D02*
G02X1381918Y580375I-1029J-952D01*
G03X1382045Y581011I-166J364D01*
G02X1383656Y580688I1029J952D01*
G03X1383529Y580052I166J-364D01*
G37*
G36*
G01X1780237Y580693D02*
G02X1778686Y580641I-736J-1193D01*
G03X1778663Y581307I-233J325D01*
G02X1778490Y583566I737J1193D01*
G03X1778401Y584232I-260J304D01*
G02X1778223Y586667I599J1268D01*
G03Y587333I-222J333D01*
G02X1779777I777J1167D01*
G03Y586667I222J-333D01*
G02X1779910Y584434I-777J-1167D01*
G03X1779999Y583768I260J-304D01*
G02X1780214Y581359I-599J-1268D01*
G03X1780237Y580693I233J-325D01*
G37*
G36*
G01X1431862Y580346D02*
G02X1429326Y580244I-1292J544D01*
G03X1428644Y580290I-355J-185D01*
G02X1428744Y581746I-1144J810D01*
G03X1429426Y581700I355J185D01*
G02X1431246Y582118I1144J-810D01*
G03X1431808Y582314I193J350D01*
G02X1432046Y582695I1293J-543D01*
G03X1431933Y583312I-301J264D01*
G02X1433644Y583625I658J1238D01*
G03X1433757Y583008I301J-264D01*
G02X1432424Y580542I-657J-1238D01*
G03X1431862Y580346I-193J-350D01*
G37*
G36*
G01X723628Y580068D02*
G02Y581732I-1128J832D01*
G03X724272I322J238D01*
G02Y580068I1128J-832D01*
G03X723628I-322J-238D01*
G37*
G36*
G01X1283571Y582011D02*
G02X1281629I-971J-1011D01*
G03Y582589I-277J289D01*
G02X1282579Y585002I971J1011D01*
G03X1282872Y585667I-6J400D01*
G02X1284548Y584343I4531J4012D01*
G03X1283969Y583904I-188J-353D01*
G02X1283571Y582589I-1369J-303D01*
G03Y582011I277J-289D01*
G37*
G36*
G01X72667Y581223D02*
G02Y582777I-1167J777D01*
G03X73333I333J222D01*
G02Y581223I1167J-777D01*
G03X72667I-333J-222D01*
G37*
G36*
G01X79667D02*
G02Y582777I-1167J777D01*
G03X80333I333J222D01*
G02Y581223I1167J-777D01*
G03X79667I-333J-222D01*
G37*
G36*
G01X1793330Y584687D02*
G02X1792007Y585292I-1160J-787D01*
G03X1792292Y585914I-46J398D01*
G02X1793615Y585309I1160J787D01*
G03X1793330Y584687I46J-398D01*
G37*
G36*
G01X1857775Y587634D02*
G02X1856700Y586776I225J-1384D01*
G03X1856265Y587320I-371J149D01*
G02X1857340Y588178I-225J1384D01*
G03X1857775Y587634I371J-149D01*
G37*
G36*
G01X1739937Y587832D02*
G02X1738234Y587102I-437J-1332D01*
G03X1737997Y587654I-361J172D01*
G02X1737778Y587747I437J1332D01*
G03X1737239Y587582I-186J-354D01*
G02X1736659Y589483I-1236J662D01*
G03X1737198Y589648I186J354D01*
G02X1738077Y590342I1236J-662D01*
G03X1738243Y591026I-101J387D01*
G02X1738719Y593394I936J1044D01*
G03X1738961Y593916I-131J378D01*
G02X1738950Y594891I1309J502D01*
G03X1738715Y595400I-377J135D01*
G02X1740531Y596239I496J1311D01*
G03X1740766Y595730I377J-135D01*
G02X1740730Y593095I-496J-1311D01*
G03X1740488Y592573I131J-378D01*
G02X1739536Y590714I-1309J-503D01*
G03X1739370Y590030I101J-387D01*
G02X1739700Y588384I-936J-1044D01*
G03X1739937Y587832I361J-172D01*
G37*
G36*
G01X1399147Y586309D02*
G02X1397189Y588243I-1167J777D01*
G03X1397195Y588899I-226J330D01*
G02X1396711Y589513I815J1141D01*
G03X1396056Y589644I-371J-151D01*
G02X1396359Y591157I-996J986D01*
G03X1397014Y591026I371J151D01*
G02X1399282Y590629I996J-986D01*
G03X1399942Y590528I363J168D01*
G02X1401990Y588613I1038J-942D01*
G03Y588059I288J-277D01*
G02X1399813Y586309I-1010J-972D01*
G03X1399147I-333J-222D01*
G37*
G36*
G01X1821030Y593534D02*
G02X1820316Y595039I-1376J269D01*
G03X1820897Y595315I189J353D01*
G02X1821611Y593810I1376J-269D01*
G03X1821030Y593534I-189J-353D01*
G37*
G36*
G01X1938781Y595545D02*
G02X1937060Y595624I-911J-1065D01*
G03X1937089Y596255I-231J327D01*
G02X1938810Y596176I911J1065D01*
G03X1938781Y595545I231J-327D01*
G37*
G36*
G01X1444034Y596099D02*
G02X1442396Y595368I-380J-1350D01*
G03X1442145Y595929I-359J176D01*
G02X1442075Y598607I380J1350D01*
G03X1442286Y599198I-128J379D01*
G02X1443923Y598616I1187J746D01*
G03X1443712Y598025I128J-379D01*
G02X1443783Y596660I-1187J-746D01*
G03X1444034Y596099I359J-176D01*
G37*
G36*
G01X64667Y595223D02*
G02X62723Y597167I-1167J777D01*
G03Y597833I-222J333D01*
G02Y600167I777J1167D01*
G03Y600833I-222J333D01*
G02X64667Y602777I777J1167D01*
G03X65333I333J222D01*
G02X67667I1167J-777D01*
G03X68333I333J222D01*
G02X70667I1167J-777D01*
G03X71333I333J222D01*
G02X73667I1167J-777D01*
G03X74333I333J222D01*
G02X76667I1167J-777D01*
G03X77333I333J222D01*
G02X79667I1167J-777D01*
G03X80333I333J222D01*
G02X82277Y600833I1167J-777D01*
G03Y600167I222J-333D01*
G02Y597833I-777J-1167D01*
G03Y597167I222J-333D01*
G02X80333Y595223I-777J-1167D01*
G03X79667I-333J-222D01*
G02X77333I-1167J777D01*
G03X76667I-333J-222D01*
G02X74333I-1167J777D01*
G03X73667I-333J-222D01*
G02X71333I-1167J777D01*
G03X70667I-333J-222D01*
G02X68333I-1167J777D01*
G03X67667I-333J-222D01*
G02X65333I-1167J777D01*
G03X64667I-333J-222D01*
G37*
G36*
G01X1310267Y597723D02*
G02X1308090Y599473I-1167J778D01*
G03Y600027I-288J277D01*
G02X1310267Y601777I1010J972D01*
G03X1310933I333J222D01*
G02X1313267I1167J-777D01*
G03X1313933I333J222D01*
G02X1316267I1167J-777D01*
G03X1316933I333J222D01*
G02X1319267I1167J-777D01*
G03X1319933I333J222D01*
G02X1322110Y600027I1167J-778D01*
G03Y599473I288J-277D01*
G02X1319933Y597723I-1010J-972D01*
G03X1319267I-333J-222D01*
G02X1316933I-1167J777D01*
G03X1316267I-333J-222D01*
G02X1313933I-1167J777D01*
G03X1313267I-333J-222D01*
G02X1310933I-1167J777D01*
G03X1310267I-333J-222D01*
G37*
G36*
G01X1385675Y603929D02*
G02X1384126Y603796I-675J-1229D01*
G03X1384069Y604460I-249J313D01*
G02X1383529Y604989I675J1229D01*
G03X1382964Y605125I-347J-199D01*
G02X1383415Y607000I-764J1175D01*
G03X1383980Y606864I347J199D01*
G02X1385618Y604593I764J-1175D01*
G03X1385675Y603929I249J-313D01*
G37*
G36*
G01X1454689Y602452D02*
G02X1452656Y604378I-1061J916D01*
G03X1452616Y604988I-278J288D01*
G02X1452404Y605181I833J1128D01*
G03X1451798Y605171I-299J-266D01*
G02X1449720Y605084I-1078J896D01*
G03X1449132Y605065I-285J-280D01*
G02X1447003Y605073I-1061J916D01*
G03X1446354Y605016I-304J-259D01*
G02X1446213Y606635I-1209J710D01*
G03X1446862Y606692I304J259D01*
G02X1449071Y606964I1209J-711D01*
G03X1449659Y606983I285J280D01*
G02X1451767Y607000I1061J-916D01*
G03X1452373Y607010I299J266D01*
G02X1454451Y607097I1078J-896D01*
G03X1455039Y607116I285J280D01*
G02X1457072Y605190I1061J-916D01*
G03X1457112Y604580I278J-288D01*
G02X1455277Y602471I-835J-1126D01*
G03X1454689Y602452I-285J-280D01*
G37*
G36*
G01X713077Y605061D02*
G02X711135I-971J-1011D01*
G03Y605639I-277J289D01*
G02X711703Y607993I971J1011D01*
G03X711931Y608582I-115J383D01*
G02X714356Y609989I1201J724D01*
G03X715016Y609932I349J195D01*
G02X714882Y608367I1090J-882D01*
G03X714222Y608424I-349J-195D01*
G02X713535Y607963I-1090J882D01*
G03X713307Y607374I115J-383D01*
G02X713077Y605639I-1201J-724D01*
G03Y605061I277J-289D01*
G37*
G36*
G01X1758833Y605723D02*
G02X1757309Y605002I-283J-1373D01*
G03X1757036Y605580I-354J186D01*
G02X1758560Y606301I283J1373D01*
G03X1758833Y605723I354J-186D01*
G37*
G36*
G01X1921759Y605264D02*
G02X1921707Y603713I1141J-815D01*
G03X1921041Y603736I-341J-210D01*
G02X1921093Y605287I-1141J815D01*
G03X1921759Y605264I341J210D01*
G37*
G36*
G01X1019465D02*
G02X1019460Y603946I1235J-664D01*
G03X1018754Y603950I-354J-186D01*
G02X1018759Y605268I-1235J664D01*
G03X1019465Y605264I354J186D01*
G37*
G36*
G01X1470066Y608965D02*
G02X1468457Y608910I-765J-1175D01*
G03X1468435Y609564I-241J319D01*
G02X1470044Y609619I765J1175D01*
G03X1470066Y608965I241J-319D01*
G37*
G36*
G01X1498208Y611341D02*
G02X1496845Y611026I-408J-1341D01*
G03X1496689Y611702I-272J293D01*
G02X1495870Y612364I407J1342D01*
G03X1495205Y612417I-350J-193D01*
G02X1493487Y612019I-1105J863D01*
G03X1492913Y611675I-174J-360D01*
G02X1492125Y612993I-1401J57D01*
G03X1492699Y613337I174J360D01*
G02X1492859Y613932I1401J-58D01*
G03X1492559Y614514I-354J186D01*
G02X1493991Y615251I191J1389D01*
G03X1494291Y614669I354J-186D01*
G02X1495327Y613959I-191J-1389D01*
G03X1495992Y613906I350J193D01*
G02X1498052Y612017I1105J-862D01*
G03X1498208Y611341I272J-293D01*
G37*
G36*
G01X730778Y610078D02*
G02X728540Y609964I-1162J785D01*
G03X727928Y609966I-307J-256D01*
G02X727933Y611770I-1071J905D01*
G03X728545Y611768I307J256D01*
G02X730698Y611754I1071J-905D01*
G03X731338Y611785I308J255D01*
G02X731418Y610109I1162J-784D01*
G03X730778Y610078I-308J-255D01*
G37*
G36*
G01X1701138Y618388D02*
G02X1700272Y616314I4633J-3152D01*
G03X1699708Y616752I-392J77D01*
G02X1700430Y618481I-602J1266D01*
G03X1701138Y618388I377J132D01*
G37*
G36*
G01X79667Y611223D02*
G02Y612777I-1167J777D01*
G03X80333I333J222D01*
G02Y611223I1167J-777D01*
G03X79667I-333J-222D01*
G37*
G36*
G01X70667Y614723D02*
G02Y616277I-1167J777D01*
G03X71333I333J222D01*
G02X73667I1167J-777D01*
G03X74333I333J222D01*
G02X76667I1167J-777D01*
G03X77333I333J222D01*
G02X79667I1167J-777D01*
G03X80333I333J222D01*
G02Y614723I1167J-777D01*
G03X79667I-333J-222D01*
G02X77333I-1167J777D01*
G03X76667I-333J-222D01*
G02X74333I-1167J777D01*
G03X73667I-333J-222D01*
G02X71333I-1167J777D01*
G03X70667I-333J-222D01*
G37*
G36*
G01X1471710Y617638D02*
G02X1469044Y617506I-1354J362D01*
G03X1468485Y617720I-374J-141D01*
G02X1469151Y619458I-646J1244D01*
G03X1469710Y619244I374J141D01*
G02X1471006Y619242I646J-1244D01*
G03X1471578Y619493I185J355D01*
G02X1474057Y619968I1354J-362D01*
G03X1474712Y619987I321J239D01*
G02X1476871Y620212I1171J-770D01*
G03X1477451Y620231I281J284D01*
G02X1479164Y620535I1049J-931D01*
G03X1479714Y620712I190J352D01*
G02X1482272Y620633I1261J-612D01*
G03X1482783Y620411I370J152D01*
G02X1481982Y618567I496J-1311D01*
G03X1481471Y618789I-370J-152D01*
G02X1480311Y618865I-497J1311D01*
G03X1479761Y618688I-190J-352D01*
G02X1477512Y618305I-1261J612D01*
G03X1476932Y618286I-281J-284D01*
G02X1474758Y618380I-1049J931D01*
G03X1474103Y618361I-321J-239D01*
G02X1472282Y617889I-1171J770D01*
G03X1471710Y617638I-185J-355D01*
G37*
G36*
G01X92682Y618956D02*
G02X92719Y617218I1118J-846D01*
G03X92131Y617249I-308J-255D01*
G02X89762Y618451I-981J1001D01*
G03X89365Y618908I-396J57D01*
G02X88156Y619592I-5J1402D01*
G03X87461Y619579I-344J-205D01*
G02X87434Y620968I-1231J671D01*
G03X88129Y620981I344J205D01*
G02X90158Y621463I1231J-671D01*
G03X90734Y621594I228J328D01*
G02X92499Y619609I1218J-694D01*
G03X92321Y619021I156J-368D01*
G02X92351Y618974I-1167J-778D01*
G03X92682Y618956I172J103D01*
G37*
G36*
G01X1778267Y620296D02*
G02X1777054Y619294I133J-1396D01*
G03X1776633Y619804I-384J112D01*
G02X1777846Y620806I-133J1396D01*
G03X1778267Y620296I384J-112D01*
G37*
G36*
G01X1517373Y618790D02*
G02X1515315Y618912I-973J1010D01*
G03X1514716Y618934I-309J-254D01*
G02X1512666Y618953I-1016J966D01*
G03X1512112Y618988I-295J-270D01*
G02X1510259Y619021I-908J1068D01*
G03X1509670Y618966I-269J-296D01*
G02X1507346Y619092I-1120J844D01*
G03X1506708Y619159I-344J-204D01*
G02X1506883Y620829I-1029J952D01*
G03X1507521Y620762I344J204D01*
G02X1509495Y620845I1029J-952D01*
G03X1510084Y620900I269J296D01*
G02X1512238Y621003I1120J-844D01*
G03X1512792Y620968I295J270D01*
G02X1514785Y620788I908J-1068D01*
G03X1515384Y620766I309J254D01*
G02X1517373Y620810I1016J-966D01*
G03X1517927I277J288D01*
G02Y618790I973J-1010D01*
G03X1517373I-277J-288D01*
G37*
G36*
G01X1322260Y281218D02*
X1318751D01*
G02Y284242I0J1512D01*
G01X1322261D01*
G02X1323772Y282740I-1J-1512D01*
G01Y282645D01*
X1323762Y282561D01*
G02X1323058Y281447I-1502J170D01*
G03X1323004Y281396I108J-168D01*
G02X1322837Y281316I-160J120D01*
G03X1322763Y281305I-8J-200D01*
G02X1322260Y281218I-505J1425D01*
G37*
G36*
G01X1323733Y281174D02*
X1327244D01*
G02X1328422Y280609I0J-1511D01*
G03X1329023Y280584I311J251D01*
G02X1328993Y278685I1016J-966D01*
G03X1328390Y278679I-299J-266D01*
G02X1327243Y278152I-1147J984D01*
G01X1323734D01*
G02X1322936Y280946I0J1511D01*
G03X1322990Y280997I-108J168D01*
G02X1323157Y281077I160J-120D01*
G03X1323231Y281088I8J200D01*
G02X1323733Y281174I503J-1425D01*
G37*
G36*
G01X1498944Y114388D02*
G02X1501966Y114398I1511J0D01*
G01Y110848D01*
X1501957Y110764D01*
G02X1500456Y109422I-1502J169D01*
G03X1500091Y108859I1J-400D01*
G02X1498755Y109691I-1281J-569D01*
G03X1499098Y110267I-16J400D01*
G02X1498944Y110930I1357J665D01*
G01Y114388D01*
G37*
G36*
G01X1464743Y358094D02*
G02X1462744Y358356I-1126J-835D01*
G03X1462816Y358907I-249J313D01*
G02X1462742Y359017I1125J837D01*
G03X1462092Y359067I-343J-206D01*
G02X1461366Y361323I-1076J898D01*
G03X1461851Y361819I100J387D01*
G02X1464431Y361528I1349J381D01*
G03X1464595Y360983I351J-192D01*
G02X1464815Y358645I-653J-1241D01*
G03X1464743Y358094I249J-313D01*
G37*
G36*
G01X1559790Y361274D02*
G02X1558147Y361257I-810J-1144D01*
G03X1558140Y361906I-238J322D01*
G02X1559783Y361923I810J1144D01*
G03X1559790Y361274I238J-322D01*
G37*
G36*
G01X110785Y128096D02*
G02X110826Y129597I-1163J783D01*
G03X111501Y129578I344J205D01*
G02X111460Y128077I1163J-783D01*
G03X110785Y128096I-344J-205D01*
G37*
G36*
G01X118581Y133842D02*
G03X119128Y133859I264J300D01*
G02X121151Y131918I989J-994D01*
G03X121155Y131373I295J-270D01*
G02X119191Y129374I-1017J-965D01*
G03X118646Y129369I-270J-295D01*
G02X116626Y131310I-964J1018D01*
G03X116620Y131843I-301J263D01*
G02X118581Y133842I1032J949D01*
G37*
G54D87*
X1950000Y220787D03*
Y228661D03*
G54D50*
X1037797Y608555D03*
Y589679D03*
Y13078D03*
Y-5822D03*
X388187Y608555D03*
Y589679D03*
Y13078D03*
Y-5822D03*
G54D66*
X44050Y504383D03*
X38389Y523748D03*
X27280Y510420D03*
X47550Y504367D03*
X98633Y78481D03*
X95041Y78451D03*
X91536Y78481D03*
X50500Y205696D03*
X108174Y164127D03*
X123624Y164600D03*
X234501Y270392D03*
X224390Y258920D03*
X230800Y265200D03*
X219500Y254500D03*
X195300Y229250D03*
X219000Y335900D03*
X229100Y325900D03*
X224000Y330900D03*
X234000Y320900D03*
X214000Y340900D03*
X378577Y309795D03*
X374994Y309910D03*
X378294Y292904D03*
X605176Y487581D03*
X628589Y463649D03*
X641107Y471989D03*
X632771Y473269D03*
X629359Y469583D03*
X695790Y351300D03*
X747000Y386000D03*
X743500D03*
X750500D03*
X754000D03*
X743500Y374000D03*
X747000D03*
X754000D03*
X750500D03*
X743500Y380000D03*
X747000D03*
X818960Y202230D03*
X814849Y205001D03*
X808165Y203529D03*
X803134Y202969D03*
X792514Y201290D03*
X844400Y280500D03*
X845050Y229400D03*
X844350Y344000D03*
X844300Y312450D03*
X889586Y274278D03*
X884586Y269278D03*
X879586Y264278D03*
X874586Y259278D03*
X869586Y254278D03*
X877008Y326100D03*
X867008Y336100D03*
X872008Y331100D03*
X862008Y341100D03*
X1028136Y309815D03*
X1017083Y309910D03*
X1431664Y190213D03*
X1463369Y561763D03*
X1567425Y144373D03*
X1570020Y295340D03*
X1608099Y197125D03*
X1608280Y249234D03*
X1681586Y141438D03*
X1693586Y142438D03*
X1689785Y161180D03*
X1688207Y168972D03*
X1758324Y232657D03*
X1758000Y250000D03*
X1828390Y165600D03*
X1832000Y165800D03*
X1852654Y164624D03*
X1847654D03*
X1882669Y454368D03*
X1954271Y80449D03*
X1908400Y101010D03*
G54D80*
X1643803Y570630D03*
X1646756Y565118D03*
Y580079D03*
Y610000D03*
X1643803Y600551D03*
Y615512D03*
X1691047Y570630D03*
X1694000Y565118D03*
Y580079D03*
Y610000D03*
X1691047Y600551D03*
Y615512D03*
G54D69*
X85609Y385234D03*
X710800Y7100D03*
X705250Y8600D03*
X1301240Y476228D03*
X1490821Y73750D03*
X1573121Y120649D03*
X1591865Y237407D03*
X1569926Y308064D03*
X1576074Y359600D03*
X1590530Y610620D03*
X1598028Y256422D03*
X1600552Y261281D03*
X1640001Y370790D03*
X1644856Y604930D03*
X1640921Y605334D03*
X1680139Y99073D03*
X1695734Y164676D03*
X1663566Y213009D03*
X1687741Y466988D03*
X1759093Y9310D03*
X1761872Y-7220D03*
X1734875Y9238D03*
X1777000Y115750D03*
X1778000Y120000D03*
X1723189Y176012D03*
X1789356Y38286D03*
X1780720Y153850D03*
X1784750Y124000D03*
X1836396Y481349D03*
X1847000Y198600D03*
X1949389Y152083D03*
X1963092Y167936D03*
X1944550Y176450D03*
X1950981Y168064D03*
X1966700Y152400D03*
X251213Y646784D03*
Y652784D03*
X261125Y646784D03*
Y652784D03*
X389473Y646508D03*
Y652508D03*
X379561Y646508D03*
Y652508D03*
X448593Y652514D03*
Y646514D03*
X438681D03*
Y652514D03*
X567029Y652238D03*
Y646238D03*
X576941D03*
Y652238D03*
X951795Y652234D03*
Y646234D03*
X941883D03*
Y652234D03*
X1196198Y652206D03*
Y646206D03*
X1206110D03*
Y652206D03*
X1265293Y652264D03*
Y646264D03*
X1255381D03*
Y652264D03*
X1509696Y652236D03*
Y646236D03*
X1519608D03*
Y652236D03*
G54D89*
X1912406Y518328D03*
X1904532D03*
G54D63*
X10512Y467244D03*
X20512D03*
X50512D03*
X1884100Y493000D03*
X1894100D03*
X1891086Y592105D03*
Y612105D03*
Y602105D03*
X1904100Y493000D03*
G54D82*
X1779504Y-15000D03*
G54D74*
X1392264Y23976D03*
X1513918D03*
G54D71*
X307675Y17057D03*
X321061D03*
X327754Y9114D03*
X324407Y17057D03*
Y9114D03*
X314368Y17057D03*
X311021Y9114D03*
X334446D03*
X331100Y17057D03*
X354526D03*
X354525Y9122D03*
X351179Y17057D03*
X347833Y9122D03*
X344486D03*
Y17057D03*
X337793Y9114D03*
X341140Y17057D03*
X334447D03*
X317714Y9114D03*
X327754Y585714D03*
X324407D03*
X311021D03*
X334446D03*
X347833Y585722D03*
X344486D03*
X337793Y585714D03*
X317714D03*
X307675Y593657D03*
X321061D03*
X324407D03*
X314368D03*
X331100D03*
X351179D03*
X344486D03*
X341140D03*
X334447D03*
X404723Y17057D03*
X401376Y9121D03*
X414762Y17058D03*
X398029Y17042D03*
X404722Y9121D03*
X414763Y9122D03*
X408069Y17042D03*
X411416Y9122D03*
X401377Y585722D03*
X404723D03*
X414763D03*
X411416D03*
X404723Y593657D03*
X414763D03*
X398029Y593642D03*
X408069D03*
X421455Y9121D03*
X438187Y9120D03*
X431494Y17042D03*
X444880Y17059D03*
Y9122D03*
X428147Y9120D03*
X421456Y17057D03*
X434840Y9120D03*
X424801Y17042D03*
X438187Y17059D03*
X421456Y585722D03*
X438189D03*
X444880D03*
X428149D03*
X434842D03*
X431494Y593642D03*
X444880Y593659D03*
X421456Y593657D03*
X424801Y593642D03*
X438187Y593659D03*
X957283Y17057D03*
X970669D03*
X974015D03*
Y9114D03*
X963976Y17057D03*
X960629Y9114D03*
X967322D03*
X974015Y585714D03*
X960629D03*
X967322D03*
X957283Y593657D03*
X970669D03*
X974015D03*
X963976D03*
X977362Y9114D03*
X984054D03*
X980708Y17057D03*
X1004134D03*
X1004133Y9122D03*
X1000787Y17057D03*
X997441Y9122D03*
X994094D03*
Y17057D03*
X987401Y9114D03*
X990748Y17057D03*
X984055D03*
X977362Y585714D03*
X984054D03*
X997441Y585722D03*
X994094D03*
X987401Y585714D03*
X980708Y593657D03*
X1000787D03*
X994094D03*
X990748D03*
X984055D03*
X1071064Y9122D03*
X1054331Y17057D03*
X1050985Y9122D03*
X1087797D03*
X1064371Y17057D03*
X1081102Y17042D03*
X1094488Y17059D03*
Y9122D03*
X1054331D03*
X1077757D03*
X1064371D03*
X1071064Y17057D03*
X1057677Y17042D03*
X1084450Y9122D03*
X1074409Y17042D03*
X1087795Y17059D03*
X1061024Y9122D03*
X1071064Y585722D03*
X1050985D03*
X1087797D03*
X1094488D03*
X1054331D03*
X1077757D03*
X1064371D03*
X1084450D03*
X1061024D03*
X1054331Y593657D03*
X1064371D03*
X1081102Y593642D03*
X1094488Y593659D03*
X1047637Y593642D03*
X1071064Y593657D03*
X1057677Y593642D03*
X1087795Y593659D03*
X1454902Y273603D03*
X1451754Y283053D03*
X1442304Y273603D03*
X1448603Y276753D03*
X1445454Y279902D03*
X1464351D03*
X1461300Y270400D03*
X1442303Y270454D03*
Y267303D03*
X1454902Y276753D03*
X1451753Y279902D03*
X1464351Y283052D03*
X1448603Y267304D03*
Y270454D03*
X1451753Y273603D03*
X1445454D03*
X1461202D03*
Y279902D03*
X1464351Y276753D03*
X1448603Y279902D03*
X1461202Y276753D03*
X1451753Y270454D03*
X1458052Y279902D03*
X1454902Y283052D03*
X1461400Y264700D03*
X1442304Y279902D03*
X1445454Y276753D03*
X1458052D03*
Y273603D03*
X1458102Y270402D03*
X1461202Y283052D03*
X1445454Y267304D03*
X1464424Y273676D03*
X1454902Y270454D03*
X1448603Y283053D03*
X1442304Y305098D03*
X1445454Y308247D03*
X1451753Y286202D03*
X1448603D03*
Y314546D03*
X1454928Y317723D03*
X1445427Y292526D03*
X1461202Y305098D03*
X1440910Y316693D03*
X1458052Y298798D03*
X1451753Y317696D03*
X1458052Y305098D03*
X1448603Y317696D03*
X1458400Y318500D03*
X1445454Y305098D03*
X1448603D03*
X1454902Y308247D03*
X1451753Y305098D03*
X1464351Y298798D03*
X1461202D03*
Y295649D03*
X1445528Y317772D03*
X1461202Y286202D03*
X1464351D03*
X1461202Y289351D03*
X1442303Y298799D03*
X1454902Y301948D03*
X1461202D03*
Y314546D03*
X1464350Y308247D03*
X1458052Y289351D03*
X1448603D03*
X1442304Y292499D03*
X1445427Y295624D03*
X1448577D03*
X1451751Y295649D03*
X1454902Y286202D03*
Y314546D03*
Y311397D03*
X1463610Y321329D03*
X1451753Y301948D03*
X1445454D03*
X1464351Y311397D03*
X1461202D03*
X1458052Y308247D03*
X1454902Y289351D03*
X1458052Y286202D03*
X1464351Y301948D03*
X1451753Y298798D03*
X1458052Y311397D03*
X1442304Y289350D03*
X1445454Y311397D03*
X1442304D03*
X1454902Y298798D03*
X1464351Y305098D03*
X1458052Y295649D03*
X1448603Y301948D03*
X1442304Y308247D03*
X1448603Y298798D03*
X1445454D03*
X1451753Y289351D03*
X1445454D03*
X1451753Y311397D03*
X1458052Y314546D03*
X1462776Y318200D03*
X1451753Y314546D03*
X1448603Y308247D03*
X1473798Y273603D03*
X1496030Y267665D03*
X1486397Y283052D03*
X1470649Y273603D03*
X1486574Y267127D03*
X1476948Y276753D03*
X1480098D03*
X1483247Y279902D03*
X1473798D03*
X1480098Y283052D03*
X1476948Y279902D03*
X1483247Y267304D03*
X1486397Y270454D03*
X1480098Y273603D03*
X1473798Y283052D03*
X1483247D03*
X1469829Y266909D03*
X1473798Y270454D03*
X1476948D03*
X1480098Y267304D03*
X1470649Y276753D03*
X1476948Y273603D03*
X1470649Y270454D03*
Y283052D03*
Y279902D03*
X1473798Y276753D03*
X1489546Y279902D03*
X1483247Y270454D03*
Y273603D03*
X1480098Y270454D03*
X1473798Y305098D03*
X1480098Y301948D03*
Y298798D03*
X1493400Y300800D03*
X1486397Y298798D03*
X1480098Y295649D03*
X1476948Y298798D03*
X1486397Y305098D03*
X1470649Y298798D03*
Y286202D03*
X1473798Y295649D03*
X1483247Y305098D03*
X1480098Y308247D03*
X1473798Y298798D03*
Y289351D03*
Y286202D03*
Y308247D03*
X1476948Y305098D03*
X1497509Y303120D03*
X1489546Y308247D03*
X1476948Y289351D03*
X1480098Y286202D03*
X1476948Y311397D03*
X1480098Y314546D03*
X1486397Y286202D03*
X1489546D03*
Y317696D03*
X1470649Y305098D03*
X1486397Y295649D03*
Y308247D03*
X1483247Y298798D03*
X1473798Y301948D03*
X1476948Y295649D03*
X1486396Y317696D03*
X1483247Y289351D03*
X1476948Y308247D03*
X1470649Y311397D03*
X1473798Y314546D03*
X1470649Y301948D03*
X1483247Y314546D03*
X1489546Y301948D03*
Y311397D03*
X1483247Y286202D03*
X1470649Y308247D03*
X1486397Y314546D03*
X1483247Y311397D03*
X1495300Y297300D03*
X1478524Y318900D03*
X1480098Y311397D03*
X1483247Y301948D03*
X1473798Y311397D03*
X1493500Y304400D03*
X1486397Y301948D03*
X1470649Y314546D03*
X1476948Y286202D03*
X1588176Y157600D03*
X1591950Y158250D03*
X1590569Y152464D03*
X1604000Y93925D03*
X1607442Y159585D03*
X1616891Y150137D03*
X1654686Y109191D03*
X1613741Y146987D03*
X1648387Y159585D03*
X1651536D03*
X1632574Y106107D03*
X1620100Y153300D03*
X1613741Y121790D03*
X1610591D03*
X1629489Y115491D03*
X1632615Y109215D03*
X1632638Y112341D03*
Y115491D03*
X1616890Y112341D03*
X1616848Y115449D03*
X1654673Y118628D03*
X1654685Y112341D03*
X1613741Y153286D03*
X1648387Y115491D03*
X1651536D03*
X1610591Y112341D03*
X1607441Y115491D03*
X1610591Y118640D03*
X1607441Y112341D03*
X1616891Y128089D03*
X1620040Y134388D03*
Y128089D03*
X1629489Y153286D03*
X1613741Y118640D03*
X1610645Y143783D03*
X1600148Y142262D03*
X1610591Y159585D03*
X1604292Y150137D03*
X1607401Y146947D03*
X1600182Y148562D03*
X1600148Y151711D03*
X1596427Y157975D03*
X1600490Y158010D03*
X1610591Y156436D03*
X1604169Y156407D03*
X1610591Y153286D03*
X1607441Y156436D03*
X1651536Y156435D03*
X1613741Y106042D03*
Y109191D03*
X1616890Y118641D03*
X1638938Y159585D03*
X1616900Y143880D03*
X1653111Y102240D03*
X1645237Y115491D03*
X1641770Y112340D03*
X1607441Y134389D03*
X1610591Y140688D03*
Y137538D03*
Y124939D03*
Y150137D03*
X1613741Y159585D03*
Y137538D03*
X1607441Y153286D03*
X1600900Y131900D03*
X1595390Y151778D03*
X1629489Y159585D03*
X1635788D03*
X1642087D03*
X1610591Y134389D03*
X1613741Y140688D03*
X1613690Y124990D03*
X1613741Y134389D03*
X1608000Y99400D03*
X1607441Y143837D03*
X1610591Y146987D03*
X1645237Y112341D03*
X1607441Y106042D03*
X1654638Y159685D03*
X1613741Y150137D03*
Y156436D03*
X1626339Y115491D03*
X1613741Y128089D03*
X1620040Y159585D03*
X1626339Y118651D03*
Y109191D03*
X1626300Y112300D03*
X1651536Y112341D03*
X1623200Y153100D03*
X1607441Y124939D03*
X1654685Y143837D03*
X1651536Y146988D03*
X1654686Y150138D03*
X1654685Y140687D03*
X1654686Y124940D03*
Y134389D03*
X1654685Y131239D03*
X1654686Y153288D03*
X1651536Y128089D03*
X1635750Y128240D03*
X1642087Y143837D03*
X1623190Y124940D03*
Y128089D03*
Y134388D03*
Y140687D03*
Y146987D03*
X1635788Y153286D03*
X1626339Y150136D03*
X1637363Y149484D03*
X1645237Y124940D03*
X1642087D03*
X1651536Y134388D03*
Y131239D03*
Y124939D03*
Y140687D03*
Y143837D03*
X1626364Y121765D03*
X1635788Y118640D03*
X1632639D03*
X1642150Y118660D03*
X1645237Y118640D03*
X1626313Y153312D03*
X1642087Y153286D03*
X1632638D03*
X1620100Y150200D03*
X1620040Y146987D03*
Y140687D03*
X1632639Y124940D03*
X1648393Y153280D03*
X1651532Y137534D03*
X1626339Y124940D03*
X1645237Y159585D03*
X1607441Y121790D03*
X1604292Y137538D03*
X1607239Y131358D03*
X1626339Y159585D03*
X1623189D03*
X1629400Y106131D03*
X1629487Y109280D03*
X1642084Y115494D03*
X1629489Y112341D03*
X1648387D03*
Y109191D03*
X1651536D03*
X1607441Y137538D03*
X1604292Y134388D03*
X1616890Y159585D03*
X1610591Y128089D03*
X1654686Y156436D03*
X1610591Y115491D03*
X1648386Y156435D03*
X1645237Y109191D03*
X1594565Y148720D03*
X1613741Y162735D03*
X1607441D03*
X1645237Y165884D03*
X1626339Y162735D03*
X1623276Y165798D03*
X1600490Y167459D03*
X1629489Y162735D03*
X1624966Y172936D03*
X1621942Y173237D03*
X1629489Y165884D03*
X1645151Y162649D03*
X1642101Y162749D03*
X1610591Y162735D03*
X1651536Y165884D03*
X1622217Y177809D03*
X1654685Y162735D03*
X1613741Y165885D03*
X1616891D03*
X1638938Y162735D03*
X1635788Y165885D03*
X1642088D03*
X1638938Y165884D03*
X1608731Y180819D03*
X1620006Y168956D03*
X1620041Y165885D03*
X1616890Y162735D03*
X1651536D03*
X1610591Y165885D03*
X1648320Y172690D03*
X1648326Y162674D03*
X1648386Y165885D03*
X1623250Y162611D03*
X1626339Y165884D03*
X1635788Y162735D03*
X1643662Y172609D03*
X1660985Y159585D03*
X1657835Y115491D03*
Y109191D03*
X1660985D03*
X1670434Y115491D03*
X1667284D03*
X1660985D03*
X1664135Y118640D03*
X1657835Y112341D03*
X1660985D03*
X1667238Y112387D03*
X1660985Y156435D03*
X1660986Y137538D03*
X1657835Y143837D03*
X1664186Y147038D03*
X1657835Y146987D03*
X1660985Y150137D03*
X1657836Y153288D03*
X1664135Y153286D03*
X1660985Y143837D03*
X1664136Y137538D03*
X1695236Y138938D03*
Y135788D03*
X1664135Y121790D03*
X1660985Y128089D03*
Y121790D03*
X1657835D03*
X1667284Y131239D03*
X1664135Y128089D03*
X1660985Y131239D03*
Y124939D03*
X1677386Y132788D03*
Y129638D03*
X1676886Y120038D03*
Y123188D03*
X1660985Y146987D03*
X1657836Y137538D03*
Y140688D03*
X1660985D03*
X1664134Y156436D03*
X1667348Y156500D03*
X1664135Y112341D03*
Y115491D03*
X1660985Y118640D03*
X1657835D03*
Y159585D03*
Y165884D03*
Y162735D03*
X1665063Y172608D03*
X1660985Y165885D03*
Y162735D03*
X1723314Y98550D03*
X1717014Y97550D03*
X1735914Y139500D03*
X1723314Y142650D03*
X1735989Y133250D03*
X1739064Y145800D03*
X1728789Y136250D03*
X1723264Y145850D03*
X1735989Y149050D03*
X1726539Y139450D03*
X1734989Y142750D03*
X1720164Y139500D03*
X1739064Y142650D03*
X1720164Y145800D03*
X1742214D03*
X1726464D03*
X1739064Y139500D03*
X1723314D03*
X1739064Y136350D03*
Y126900D03*
X1723314Y130050D03*
Y126900D03*
X1726464Y133200D03*
Y111150D03*
X1739064Y120600D03*
X1735914Y104850D03*
X1723314D03*
X1720164Y108000D03*
X1735914D03*
X1723314D03*
X1739064Y123750D03*
X1726464Y120600D03*
X1742214D03*
X1723314Y120601D03*
X1735912Y123750D03*
X1726464D03*
X1720164Y104850D03*
X1739064Y117450D03*
X1735914D03*
X1723314Y101700D03*
X1731789Y139450D03*
X1717014Y142650D03*
X1739064Y130050D03*
X1746189Y153250D03*
X1723314Y133200D03*
X1742214Y142650D03*
X1746189Y134777D03*
X1742214Y130050D03*
X1745768Y111743D03*
X1745363Y108004D03*
X1735914Y101700D03*
X1742214Y114300D03*
Y123750D03*
X1745364D03*
X1723314D03*
X1720164D03*
Y117451D03*
X1726464Y117450D03*
X1745364Y142650D03*
X1746189Y131624D03*
X1745364Y117450D03*
X1717014Y133200D03*
Y111150D03*
Y104850D03*
X1745500Y104500D03*
G54D60*
X-10236Y116969D03*
X-4725D03*
X23228Y124843D03*
X17716D03*
X-10236Y132717D03*
X-4725D03*
X6299D03*
X11811D03*
X17716Y140591D03*
X23228D03*
X-10236Y373110D03*
X-4725D03*
X23228Y380984D03*
X17716D03*
X-10236Y388858D03*
X-4725D03*
X6299D03*
X11811D03*
X17716Y396732D03*
X23228D03*
G54D76*
X1527844Y80791D03*
X1724606Y235430D03*
G54D72*
X476672Y220096D03*
X480052Y210346D03*
Y225947D03*
X476672Y235696D03*
X483432Y216196D03*
X531871Y202547D03*
X525111D03*
X483432Y212296D03*
Y231797D03*
Y239596D03*
X501452Y337096D03*
X531871Y331247D03*
X525111Y323446D03*
X531871D03*
X525111Y327347D03*
X528491Y333196D03*
X521731Y329296D03*
X518352Y335147D03*
X521731Y340996D03*
X525111Y319547D03*
X528491Y321496D03*
Y325396D03*
Y329296D03*
X525111Y331247D03*
X521731Y333196D03*
Y337096D03*
X535251Y344896D03*
X542011D03*
Y340996D03*
Y337096D03*
X538631Y331247D03*
Y327347D03*
X535251Y340996D03*
X538631Y342947D03*
X542011Y333196D03*
Y329296D03*
Y325396D03*
X538631Y323446D03*
X535251Y337096D03*
X528491Y340996D03*
X531871Y339047D03*
Y342947D03*
X528491Y344896D03*
X491312Y342947D03*
X484552Y389747D03*
X494692Y399496D03*
X491312Y393647D03*
X487932Y383896D03*
X484552Y374146D03*
X511592Y362447D03*
X514972Y368296D03*
X508212Y364396D03*
X498072Y378047D03*
X494692Y379996D03*
Y387796D03*
X518352Y350747D03*
Y354647D03*
X511592Y358547D03*
X514972Y360496D03*
Y364396D03*
X511592Y366347D03*
X508212Y368296D03*
Y372197D03*
X504832Y374146D03*
X501452Y376096D03*
X498072Y381947D03*
X494692Y383896D03*
X518352Y346847D03*
X521731Y352696D03*
X511592Y354647D03*
X498072Y374146D03*
X528491Y387796D03*
X521731D03*
Y391696D03*
X518352Y393647D03*
X514972Y395597D03*
X511592Y389747D03*
X528491Y379996D03*
Y383896D03*
X525111Y385847D03*
X521731Y383896D03*
X525111Y389747D03*
X521731Y395597D03*
X514972Y391696D03*
Y387796D03*
X528491Y376096D03*
X531871Y381947D03*
X535251Y348796D03*
X538631Y346847D03*
Y354647D03*
Y358547D03*
Y362447D03*
X531871D03*
Y366347D03*
X535251Y372197D03*
Y379996D03*
X538631Y350747D03*
X542011Y356596D03*
X535251Y360496D03*
X531871Y358547D03*
X535251Y364396D03*
Y368296D03*
X538631Y374146D03*
X531871Y378047D03*
X525111Y346847D03*
X528491Y348796D03*
Y352696D03*
X487932Y356596D03*
X491312Y354647D03*
X511592Y401447D03*
X508212Y383896D03*
X514972Y376096D03*
X504832Y401446D03*
X552151Y331247D03*
Y335147D03*
Y342947D03*
X548771Y344896D03*
Y333196D03*
X552151Y339047D03*
X555531Y340996D03*
X545391Y327347D03*
Y339047D03*
X562591Y340996D03*
X558911Y339047D03*
X555531Y344896D03*
X562591Y337096D03*
X555531D03*
X552151Y346847D03*
X548771Y387796D03*
X552151Y385847D03*
X555531Y352696D03*
Y348796D03*
X552151Y354647D03*
X558911Y350747D03*
X559211Y366347D03*
X555531Y379996D03*
X552151Y381947D03*
X558911Y354647D03*
X552151Y362447D03*
X545391Y350747D03*
X548771Y348796D03*
X947887Y324160D03*
X937747Y322209D03*
X930987D03*
X941127Y324160D03*
G54D86*
X1892720Y525415D03*
X1900595D03*
X1894689Y518328D03*
X1908469Y525415D03*
X1916343D03*
X1924217D03*
G54D77*
X1627642Y-14488D03*
X1647327Y-315D03*
X1667012Y-14488D03*
X1969291Y486064D03*
Y497874D03*
G54D47*
X1630386Y413942D03*
X1634400Y412900D03*
X1630120Y418887D03*
X1621347Y415297D03*
X1603000Y422971D03*
X1611418D03*
X1673800Y201070D03*
X1681352Y196092D03*
X1469000Y345850D03*
X-19210Y162529D03*
X-17014Y455604D03*
X-17200Y510800D03*
X-17302Y506798D03*
X-13500Y486400D03*
X-14800Y526100D03*
X-18160Y522609D03*
X-19802Y476738D03*
X-19783Y481286D03*
X-16186Y519304D03*
X-12600Y578900D03*
X-14971Y540000D03*
X-17500Y574000D03*
X8660Y27274D03*
X43960Y20572D03*
X-3560Y34620D03*
X-10850Y30800D03*
X2871Y22791D03*
X19964Y18793D03*
X2934Y26933D03*
X16550Y18300D03*
X602Y30502D03*
X25827Y-16958D03*
X8988Y58267D03*
X-1750Y43320D03*
X-1920Y47290D03*
X11925Y74867D03*
X11864Y71294D03*
X11539Y39927D03*
X11500Y43400D03*
X-1470Y63910D03*
X37037Y138425D03*
X39109Y154901D03*
X5120Y276058D03*
X2269Y273532D03*
X48550Y301650D03*
X1500Y295000D03*
X47100Y327000D03*
X49200Y340650D03*
X10365Y461602D03*
X37550Y425400D03*
X40965Y429434D03*
X2450Y460000D03*
X-9600Y526100D03*
X-6650Y487800D03*
X-5680Y524570D03*
X47800Y487600D03*
X3354Y517143D03*
X6748Y517021D03*
X-6200Y505400D03*
X-6676Y501800D03*
X10932Y523601D03*
X14700Y517000D03*
X-9900Y486400D03*
X-2430Y524340D03*
X-7360Y512000D03*
X-6712Y515731D03*
X-2083Y513704D03*
X-4350Y482100D03*
X-900Y482300D03*
X22491Y500618D03*
X2350Y469650D03*
X-8318Y542216D03*
X-8200Y578600D03*
X-3100Y533991D03*
X-2500Y569500D03*
X-10947Y544117D03*
X-4300Y558400D03*
X-4100Y554400D03*
X1439Y546583D03*
X1539Y550183D03*
Y586183D03*
X1439Y582583D03*
X-9287Y531604D03*
X-6566Y568363D03*
X-9291Y535201D03*
X-9283Y571324D03*
X-4500Y594000D03*
X93500Y-18000D03*
X82300Y-16600D03*
X53382Y-1173D03*
X52744Y-4368D03*
X74386Y-18439D03*
X71172Y-18486D03*
X87091Y-16391D03*
X106000Y17260D03*
X52389Y-14258D03*
X60035Y7508D03*
X51090Y8080D03*
X54307Y-8051D03*
X104500Y-1850D03*
X76106Y89337D03*
X86600Y94000D03*
X70980Y97166D03*
X105898Y55194D03*
X82046Y90043D03*
X98420Y112198D03*
X99250Y160370D03*
X104424Y110833D03*
X87200Y152374D03*
X91913Y121318D03*
X77790Y121030D03*
X79670Y132300D03*
X75660Y152380D03*
X78950Y152810D03*
X91306Y157194D03*
X61800Y191600D03*
X76143Y183019D03*
X61356Y181000D03*
X61256Y186000D03*
X90831Y184982D03*
X86731Y189148D03*
X107700Y211040D03*
X104820Y202100D03*
X102507Y211047D03*
X79300Y272300D03*
X84000Y272500D03*
X99500Y223800D03*
X97200Y265000D03*
X99758Y240300D03*
X91600Y278700D03*
X70700Y330349D03*
X93500Y289000D03*
X71500Y298000D03*
X66000Y292700D03*
X76800Y298000D03*
X76900Y292600D03*
X66500Y303400D03*
X76800D03*
X58400Y314600D03*
X53000Y323500D03*
X52804Y333247D03*
X61300Y328600D03*
X93500Y285000D03*
X93400Y296000D03*
X53400Y298100D03*
X79410Y331636D03*
X84000Y324542D03*
X53100Y327000D03*
X64700Y310525D03*
X69125Y310625D03*
X84300Y305700D03*
Y310700D03*
X66300Y285850D03*
X72904Y284898D03*
X84300Y289000D03*
X82050Y283951D03*
X77103Y283900D03*
X88000Y343900D03*
X88600Y302997D03*
X94360Y335210D03*
X82500Y341400D03*
X103500Y304700D03*
X104600Y316602D03*
X103500Y308500D03*
X84866Y294213D03*
X79400Y325400D03*
X84300Y299000D03*
X87400Y337200D03*
X103200Y330190D03*
X88840Y324740D03*
X53100Y315000D03*
X53250Y302800D03*
X102322Y295478D03*
X66900Y322000D03*
X60400Y355750D03*
X57395Y366795D03*
X55500Y371700D03*
X109500Y370000D03*
X61914Y368731D03*
X57800Y376100D03*
X60565Y380131D03*
X65000Y383000D03*
X74800Y379700D03*
X80200D03*
X62600Y375100D03*
X87900Y347500D03*
X93712Y380507D03*
X97472Y380934D03*
X90518Y388828D03*
X54900Y389400D03*
X110452Y407092D03*
X79100Y347000D03*
X61041Y351737D03*
X74800Y383114D03*
X66016Y468350D03*
X106392Y527413D03*
X59731Y480066D03*
X71050Y478670D03*
X86100Y505200D03*
X105392Y566000D03*
X102236Y614167D03*
X106192Y604600D03*
X132959Y33700D03*
X163391D03*
X160431Y27899D03*
X130313D03*
X157084Y34100D03*
X153738Y27899D03*
X126580Y33700D03*
X123620Y27899D03*
X150391Y34100D03*
X147045Y27899D03*
X169770Y33700D03*
X167124Y27899D03*
X132959Y-4100D03*
X130313Y17157D03*
X163391Y-4100D03*
X160431Y17157D03*
Y-9901D03*
X163477Y12114D03*
X130313Y-9901D03*
X132959Y12114D03*
X157084Y-3700D03*
X153738Y17157D03*
Y-9901D03*
X157084Y12114D03*
X126580Y-4100D03*
X123620Y17157D03*
Y-9901D03*
X126666Y12114D03*
X147045Y17157D03*
X150391Y-3700D03*
X147045Y-9901D03*
X150391Y12114D03*
X169770Y-4100D03*
X167124Y17157D03*
Y-9901D03*
X169770Y12114D03*
X114680Y17320D03*
X120273Y9157D03*
X116070Y35780D03*
X114050Y21320D03*
X116692Y-1800D03*
X116300Y-9460D03*
X132959Y71500D03*
X130313Y92757D03*
X163391Y71500D03*
X160431Y92757D03*
Y65699D03*
X163477Y87714D03*
X130313Y65699D03*
X132959Y87714D03*
X157084Y71900D03*
X153738Y92757D03*
Y65699D03*
X157084Y87714D03*
X126580Y71500D03*
X123620Y92757D03*
Y65699D03*
X126666Y87714D03*
X150391Y71900D03*
X147045Y92757D03*
Y65699D03*
X150391Y87714D03*
X169770Y71500D03*
X167124Y92757D03*
Y65699D03*
X169770Y87714D03*
X130313Y54957D03*
X160431D03*
X163477Y49914D03*
X132959D03*
X153738Y54957D03*
X157084Y49914D03*
X123620Y54957D03*
X126666Y49914D03*
X147045Y54957D03*
X150391Y49914D03*
X167124Y54957D03*
X169770Y49914D03*
X119892Y84700D03*
X120273Y46957D03*
X116200Y70387D03*
X115980Y73680D03*
X117600Y193805D03*
X122542Y214019D03*
X150000Y194850D03*
Y199850D03*
X162800Y195600D03*
X162788Y200650D03*
X124340Y197750D03*
X122203Y246675D03*
X122400Y278671D03*
X125563Y234316D03*
X125663Y230716D03*
X125563Y227116D03*
Y259116D03*
X125663Y262716D03*
X125563Y266316D03*
X122361Y342649D03*
X122493Y310633D03*
X125663Y294716D03*
X125563Y298316D03*
Y291116D03*
Y323116D03*
X125663Y326716D03*
X122473Y374716D03*
X153392Y404000D03*
X167640Y404842D03*
X118220Y360500D03*
X125563Y355116D03*
X125663Y358716D03*
Y390716D03*
X125563Y387116D03*
Y394316D03*
X151909Y413267D03*
X148409Y422239D03*
X153392Y407500D03*
X167680Y408440D03*
X157862Y416012D03*
X150650Y409860D03*
X130313Y518157D03*
X160431D03*
X163477Y513114D03*
X160431Y528899D03*
X132959Y513114D03*
X130313Y528899D03*
X153738Y518157D03*
Y528899D03*
X157084Y513114D03*
X123620Y518157D03*
Y528899D03*
X126666Y513114D03*
X147045Y518157D03*
X150391Y513114D03*
X147045Y528899D03*
X167124Y518157D03*
Y528899D03*
X169770Y513114D03*
X119892Y510100D03*
X116927Y517900D03*
X132959Y534700D03*
X163391D03*
X157084Y535100D03*
X126580Y534700D03*
X150391Y535100D03*
X169770Y534700D03*
X130313Y555957D03*
X132959Y572500D03*
X160431Y555957D03*
X163391Y572500D03*
X163477Y550914D03*
X160431Y566699D03*
X132959Y550914D03*
X130313Y566699D03*
X153738Y555957D03*
X157084Y572900D03*
Y550914D03*
X153738Y566699D03*
X123620Y555957D03*
X126580Y572500D03*
X126666Y550914D03*
X123620Y566699D03*
X147045Y555957D03*
X150391Y572900D03*
Y550914D03*
X147045Y566699D03*
X167124Y555957D03*
X169770Y572500D03*
Y550914D03*
X167124Y566699D03*
X163477Y588714D03*
X132959D03*
X157084D03*
X126666D03*
X150391D03*
X169770D03*
X113692Y566000D03*
X119892Y536983D03*
Y547900D03*
Y574700D03*
Y585700D03*
X114150Y585850D03*
X114509Y575658D03*
X116927Y555700D03*
X115883Y548024D03*
X132959Y610300D03*
X130313Y593757D03*
X163391Y610300D03*
X160431Y593757D03*
Y604499D03*
X130313D03*
X157084Y610700D03*
X153738Y593757D03*
Y604499D03*
X126580Y610300D03*
X123620Y593757D03*
Y604499D03*
X150391Y610700D03*
X147045Y593757D03*
Y604499D03*
X167124Y593757D03*
X169770Y610300D03*
X167124Y604499D03*
X114792Y604600D03*
X119892Y612583D03*
X116927Y593500D03*
X193895Y34100D03*
X190549Y27899D03*
X187202Y34100D03*
X183856Y27899D03*
X206581Y33700D03*
X203935Y27899D03*
X230706Y34100D03*
X227360Y27899D03*
X200202Y33700D03*
X197242Y27899D03*
X224013Y34100D03*
X220667Y27899D03*
X234053D03*
X193895Y-3700D03*
X190549Y17157D03*
Y-9901D03*
X193895Y12114D03*
X187202Y-3700D03*
X183856Y17157D03*
Y-9901D03*
X187202Y12114D03*
X206581Y-4100D03*
X203935Y17157D03*
Y-9901D03*
X206581Y12114D03*
X230706Y-3700D03*
X227360Y17157D03*
Y-9901D03*
X230706Y12114D03*
X200202Y-4100D03*
X197242Y17157D03*
Y-9901D03*
X200288Y12114D03*
X224013Y-3700D03*
X220667Y17157D03*
Y-9901D03*
X224013Y12114D03*
X234053Y17157D03*
Y-9901D03*
X193895Y71900D03*
X190549Y92757D03*
Y65699D03*
X193895Y87714D03*
X187202Y71900D03*
X183856Y92757D03*
Y65699D03*
X187202Y87714D03*
X206581Y71500D03*
X203935Y92757D03*
Y65699D03*
X206581Y87714D03*
X230706Y71900D03*
X227360Y92757D03*
Y65699D03*
X230706Y87714D03*
X200202Y71500D03*
X197242Y92757D03*
Y65699D03*
X200288Y87714D03*
X224013Y71900D03*
X220667Y92761D03*
Y65699D03*
X224013Y87714D03*
X234053Y92757D03*
Y65699D03*
X190549Y54957D03*
X193895Y49914D03*
X183856Y54957D03*
X187202Y49914D03*
X203935Y54957D03*
X206581Y49914D03*
X227360Y54957D03*
X230706Y49914D03*
X197242Y54957D03*
X200288Y49914D03*
X220667Y54957D03*
X224013Y49914D03*
X234053Y54957D03*
Y112327D03*
X206600Y372400D03*
X190549Y518157D03*
X193895Y513114D03*
X190549Y528899D03*
X183856Y518157D03*
Y528899D03*
X187202Y513114D03*
X203935Y518157D03*
X206581Y513114D03*
X203935Y528899D03*
X227360Y518157D03*
Y528899D03*
X230706Y513114D03*
X197242Y518157D03*
X200288Y513114D03*
X197242Y528899D03*
X220667Y518161D03*
Y528899D03*
X224013Y513114D03*
X234053Y518157D03*
Y528899D03*
X233292Y498500D03*
X193895Y535100D03*
X187202D03*
X206581Y534700D03*
X230706Y535100D03*
X200202Y534700D03*
X224013Y535100D03*
X190549Y555957D03*
X193895Y572900D03*
Y550914D03*
X190549Y566699D03*
X183856Y555957D03*
X187202Y572900D03*
Y550914D03*
X183856Y566699D03*
X203935Y555957D03*
X206581Y572500D03*
Y550914D03*
X203935Y566699D03*
X227360Y555957D03*
X230706Y572900D03*
Y550914D03*
X227360Y566699D03*
X197242Y555957D03*
X200202Y572500D03*
X200288Y550914D03*
X197242Y566699D03*
X220667Y555961D03*
X224013Y572900D03*
Y550914D03*
X220667Y566699D03*
X234053Y555957D03*
Y566699D03*
X193895Y588714D03*
X187202D03*
X206581D03*
X230706D03*
X200288D03*
X224013D03*
X190549Y593757D03*
X193895Y610700D03*
X190549Y604499D03*
X183856Y593757D03*
X187202Y610700D03*
X183856Y604499D03*
X206581Y610300D03*
X203935Y593757D03*
Y604499D03*
X230706Y610700D03*
X227360Y593757D03*
Y604499D03*
X197242Y593757D03*
X200202Y610300D03*
X197242Y604499D03*
X224013Y610700D03*
X220667Y593761D03*
Y604499D03*
X234053Y593757D03*
Y604499D03*
X243392Y33700D03*
X240746Y27899D03*
X267517Y34100D03*
X264171Y27899D03*
X237013Y33700D03*
X260824Y34100D03*
X257478Y27899D03*
X280203Y33700D03*
X277557Y27899D03*
X273824Y33700D03*
X270864Y27899D03*
X294289D03*
X243392Y-4100D03*
X240746Y17157D03*
Y-9901D03*
X243392Y12114D03*
X267517Y-3700D03*
X264171Y17157D03*
Y-9901D03*
X267517Y12114D03*
X237013Y-4100D03*
X237099Y12114D03*
X260824Y-3700D03*
X257478Y17157D03*
Y-9901D03*
X260824Y12114D03*
X280203Y-4100D03*
X277557Y17157D03*
Y-9901D03*
X280203Y12114D03*
X270864Y17157D03*
X273824Y-4100D03*
X270864Y-9901D03*
X273910Y12114D03*
X294289Y17157D03*
Y-9901D03*
X243392Y71500D03*
X240746Y92757D03*
Y65699D03*
X243392Y87714D03*
X267517Y71900D03*
X264171Y92757D03*
Y65699D03*
X267517Y87714D03*
X237013Y71500D03*
X237099Y87714D03*
X260824Y71900D03*
X257478Y92757D03*
Y65699D03*
X260824Y87714D03*
X280203Y71500D03*
X277557Y92757D03*
Y65699D03*
X280203Y87714D03*
X270864Y92757D03*
X273824Y71500D03*
X270864Y65699D03*
X273910Y87714D03*
X294289Y92757D03*
Y65699D03*
X240746Y54957D03*
X243392Y49914D03*
X264171Y54957D03*
X267517Y49914D03*
X237099D03*
X257478Y54957D03*
X260824Y49914D03*
X277557Y54957D03*
X280203Y49914D03*
X270864Y54957D03*
X273910Y49914D03*
X294289Y54957D03*
X240746Y112327D03*
X243392Y106934D03*
X264171Y112327D03*
X267517Y107284D03*
X237099D03*
X257478Y112327D03*
X260824Y107284D03*
X277557Y112327D03*
X280203Y106934D03*
X270864Y112327D03*
X273910Y107284D03*
X294889Y110927D03*
X274619Y205210D03*
X271239Y207159D03*
X277999Y218860D03*
X281379Y216909D03*
X284759Y218860D03*
X294899Y216909D03*
Y220809D03*
X288139D03*
X284759Y203260D03*
Y211060D03*
X294899Y205210D03*
Y209109D03*
X281379Y205210D03*
Y209109D03*
X291519Y203260D03*
Y211060D03*
X288139Y201309D03*
Y213009D03*
Y205210D03*
Y209109D03*
X267859D03*
X277999Y199360D03*
X274619Y201309D03*
X271239Y203260D03*
X294899Y197409D03*
X274619Y209109D03*
X264179Y257860D03*
X281379Y228610D03*
X288139Y224709D03*
X271239Y257860D03*
X284759Y230559D03*
X288139Y228610D03*
X277999Y222760D03*
X264092Y242260D03*
X271239D03*
X264179Y261760D03*
X271239D03*
X264179Y246160D03*
X271239D03*
Y250060D03*
X277999Y226660D03*
X271239Y253960D03*
X267859Y248109D03*
X281379Y224709D03*
X284759Y222760D03*
X267859Y255909D03*
X281379Y267609D03*
X277999Y238360D03*
X281379Y236409D03*
X284759Y250060D03*
X288139Y248109D03*
X277999Y242260D03*
X284759Y238360D03*
X288139Y263709D03*
X277999Y257860D03*
X281379Y255909D03*
X284759Y269560D03*
X288139Y267609D03*
X277999Y261760D03*
X284759Y257860D03*
X281379Y248109D03*
X288139Y244209D03*
Y259809D03*
X277999Y246160D03*
X288139Y240309D03*
X277999Y265660D03*
X284759Y261760D03*
X281379Y244209D03*
X284759Y242260D03*
X281379Y263709D03*
X294899Y232509D03*
Y236409D03*
Y252009D03*
Y255909D03*
Y240309D03*
Y259809D03*
X239778Y274478D03*
X271239Y277360D03*
Y281260D03*
X267392Y276000D03*
X267359Y279310D03*
Y283209D03*
X288139Y279310D03*
X284759Y281260D03*
X291519D03*
X277999D03*
X274619Y279310D03*
Y283209D03*
X288139D03*
X281379Y279310D03*
Y283209D03*
X294899D03*
Y279310D03*
X267859Y271509D03*
X264179Y273460D03*
X274619Y271509D03*
X294899D03*
Y267609D03*
X291519Y273460D03*
X277999D03*
X271239Y335860D03*
X264179D03*
X271239Y331960D03*
X264179D03*
X271239Y343660D03*
Y339760D03*
X267859Y345609D03*
Y337809D03*
X288139Y333909D03*
X281379Y330009D03*
Y341709D03*
X277999Y339760D03*
X288139Y330009D03*
X284759Y328060D03*
Y339760D03*
X277999Y335860D03*
Y331960D03*
X284759Y335860D03*
X281379Y333909D03*
X288139Y337809D03*
X294899Y341709D03*
Y337809D03*
X271239Y320260D03*
Y324160D03*
X270939Y316160D03*
X267359Y318309D03*
X267859Y326110D03*
X267392Y322000D03*
X270892Y304660D03*
Y311960D03*
Y300760D03*
Y308560D03*
Y292959D03*
Y289060D03*
Y285500D03*
Y296860D03*
X281379Y302709D03*
X288139D03*
X294899D03*
X291519Y304660D03*
X281379Y306609D03*
Y310509D03*
X288139Y306609D03*
Y310509D03*
X284759Y304660D03*
X294899Y310509D03*
Y306609D03*
X281379Y287109D03*
X288139Y291009D03*
X284759Y289060D03*
X291519D03*
Y296860D03*
X288139Y298809D03*
X274619Y306609D03*
Y310509D03*
X277999Y304660D03*
X274619Y302709D03*
Y298809D03*
Y294909D03*
X277999Y289060D03*
X274619Y287109D03*
Y291009D03*
X277999Y296860D03*
X288139Y287109D03*
X281379Y298809D03*
Y294909D03*
X288139D03*
X284759Y296860D03*
X281379Y291009D03*
X294899Y298809D03*
Y294909D03*
Y291009D03*
Y287109D03*
X291519Y312460D03*
X284759D03*
X277999D03*
X274619Y314409D03*
X294899D03*
X281379D03*
X288139D03*
X274619Y318309D03*
X291519Y320260D03*
X284759D03*
X288139Y322209D03*
X281379D03*
X291519Y324160D03*
X277999D03*
X294899Y326109D03*
Y330009D03*
X288139Y372909D03*
X281379Y369010D03*
Y380709D03*
X277999Y378760D03*
X288139Y369010D03*
X284759Y367060D03*
Y378760D03*
X277999Y374860D03*
X294899Y376809D03*
Y380709D03*
X264179Y351460D03*
X271239D03*
X264179Y347560D03*
X271239D03*
X284759Y374860D03*
X277999Y370959D03*
X288139Y376809D03*
X281379Y372909D03*
X284759Y359260D03*
X281379Y361209D03*
X288139Y349509D03*
X284759Y347560D03*
X277999Y355360D03*
Y359260D03*
X284759Y386560D03*
Y394359D03*
X294899Y388509D03*
Y392410D03*
X281379Y388509D03*
Y392410D03*
X291519Y386560D03*
Y394359D03*
X288139Y353409D03*
X281379Y349509D03*
X284759Y355360D03*
X288139Y388509D03*
X277999Y351460D03*
X288139Y396309D03*
Y357309D03*
Y384609D03*
X281379Y353409D03*
X288139Y392410D03*
X294899Y361209D03*
Y365109D03*
Y345609D03*
Y357309D03*
X274619Y400209D03*
X281379D03*
X271239Y394359D03*
X267859Y392410D03*
X294899Y400209D03*
X271239Y398260D03*
X277999D03*
X274619Y396309D03*
X240746Y518157D03*
Y528899D03*
X243392Y513114D03*
X264171Y518157D03*
Y528899D03*
X267517Y513114D03*
X237099D03*
X257478Y518157D03*
Y528899D03*
X260824Y513114D03*
X277557Y518157D03*
X280203Y513114D03*
X277557Y528899D03*
X270864Y518157D03*
X273910Y513114D03*
X270864Y528899D03*
X294289Y518157D03*
Y528899D03*
X239592Y495900D03*
X243392Y495694D03*
X264171Y498487D03*
X267584Y493919D03*
X236892Y490800D03*
X257478Y498487D03*
X260824Y493744D03*
X277557Y498644D03*
X280203Y493244D03*
X271092Y498644D03*
X273992Y493744D03*
X294392Y493100D03*
X243392Y534700D03*
X267517Y535100D03*
X237013Y534700D03*
X260824Y535100D03*
X280203Y534700D03*
X273824D03*
X240746Y555957D03*
X243392Y572500D03*
Y550914D03*
X240746Y566699D03*
X264171Y555957D03*
X267517Y572900D03*
Y550914D03*
X264171Y566699D03*
X237013Y572500D03*
X237099Y550914D03*
X257478Y555957D03*
X260824Y572900D03*
Y550914D03*
X257478Y566699D03*
X277557Y555957D03*
X280203Y572500D03*
Y550914D03*
X277557Y566699D03*
X270864Y555957D03*
X273824Y572500D03*
X273910Y550914D03*
X270864Y566699D03*
X294289Y555957D03*
Y566699D03*
X243392Y588714D03*
X267517D03*
X237099D03*
X260824D03*
X280203D03*
X273910D03*
X240746Y593757D03*
X243392Y610300D03*
X240746Y604499D03*
X267517Y610700D03*
X264171Y593757D03*
Y604499D03*
X237013Y610300D03*
X257478Y593757D03*
X260824Y610700D03*
X257478Y604499D03*
X280203Y610300D03*
X277557Y593757D03*
Y604499D03*
X273824Y610300D03*
X270864Y593757D03*
Y604499D03*
X294289Y593757D03*
Y604499D03*
X308157Y-7180D03*
X304328Y34100D03*
X300982Y27899D03*
X297635Y34100D03*
X321061Y-7108D03*
X327754Y-1743D03*
X324407Y-9901D03*
Y-4536D03*
X314368Y-7108D03*
X311021Y-4536D03*
X304328Y-3700D03*
X300982Y17157D03*
Y-9901D03*
X304328Y12114D03*
X297635Y-3700D03*
Y12114D03*
X334447Y-1743D03*
X331100Y-9786D03*
X354526Y-7108D03*
X354525Y-1742D03*
X351179Y-9901D03*
X347833Y-1743D03*
X344486Y-4536D03*
Y-9786D03*
X337793Y-4536D03*
X341140Y-7108D03*
X334447D03*
X321061Y-1743D03*
X314368Y-1843D03*
X331100Y-4536D03*
X327754Y-7108D03*
X317714Y-9786D03*
X311021D03*
X321061Y9114D03*
X311021Y17057D03*
X317714D03*
X327754D03*
X347833Y-7108D03*
X357872Y-9786D03*
X351179Y9122D03*
X341140Y-1743D03*
X337793Y-9901D03*
X357872Y-1858D03*
X357672Y9114D03*
X341140Y9122D03*
X347833Y17057D03*
X337793D03*
X357872Y17014D03*
X351179Y-4536D03*
X331100Y9114D03*
X314368D03*
X317714Y-4536D03*
X304328Y71900D03*
X300982Y92757D03*
Y65699D03*
X304328Y87714D03*
X297635Y71900D03*
Y87714D03*
X300982Y54957D03*
X304328Y49914D03*
X297635D03*
X300982Y109700D03*
X304178Y107684D03*
X297635Y105084D03*
X298279Y214960D03*
X308418Y216909D03*
Y220809D03*
X305039Y214960D03*
X301659Y213009D03*
Y216909D03*
Y220809D03*
X338838Y250060D03*
X298279Y222760D03*
X305039D03*
X328698Y236409D03*
X301659Y224709D03*
X328698Y248109D03*
Y240309D03*
Y244209D03*
X325318Y238360D03*
Y246160D03*
X335458Y240309D03*
Y244209D03*
X321938Y240309D03*
Y244209D03*
X332078Y238360D03*
Y246160D03*
X298279Y261760D03*
Y230559D03*
X301659Y244209D03*
X305039Y242260D03*
X301659Y232509D03*
X311798Y230559D03*
X318558Y234460D03*
Y222760D03*
X321938Y224709D03*
X305039Y257860D03*
X311798Y234460D03*
X315178Y236409D03*
Y224709D03*
X321938Y228610D03*
X328698Y255909D03*
Y263709D03*
X338838Y257860D03*
Y261760D03*
X325318Y257860D03*
Y261760D03*
X335458Y255909D03*
Y263709D03*
X298279Y250060D03*
X301659Y263709D03*
X305039Y261760D03*
X301659Y252009D03*
X298279Y242260D03*
X305039Y238360D03*
Y253960D03*
X311798Y226660D03*
X332078Y253960D03*
X315178Y263709D03*
X305039Y234460D03*
X321938Y232509D03*
X332078Y265660D03*
X315178Y275409D03*
X301659Y255909D03*
X298279Y238360D03*
X315178Y228610D03*
X332078Y257860D03*
X315178Y267609D03*
X301659Y236409D03*
X318558Y230559D03*
X332078Y261760D03*
X315178Y271509D03*
X298279Y257860D03*
X311798Y265660D03*
Y273460D03*
X321938Y267609D03*
Y271509D03*
X308418Y267609D03*
Y271509D03*
X318558Y265660D03*
Y273460D03*
X301659Y279310D03*
X298279Y281260D03*
X308418Y283209D03*
X305039Y281260D03*
X308418Y279310D03*
X311798Y281260D03*
X301659Y283209D03*
X348978Y267609D03*
X357057Y277360D03*
Y281260D03*
X345598D03*
X348978Y283209D03*
X345598Y277360D03*
X348978Y279310D03*
Y275409D03*
Y271509D03*
X352357Y265660D03*
X355737Y263709D03*
X328698Y224709D03*
Y228610D03*
X332078Y230560D03*
X311798Y242260D03*
X315178Y244209D03*
X311798Y246160D03*
X315178Y248109D03*
X308418D03*
X352357Y250060D03*
X345598D03*
X318558D03*
X355737Y252009D03*
X348978D03*
X321938D03*
X352357Y253960D03*
X345598D03*
X355737Y255909D03*
X348978D03*
X338838Y273460D03*
X345598Y261760D03*
X338838Y269560D03*
X332078Y273460D03*
X298279D03*
X335458Y275409D03*
X328698D03*
X338838Y277360D03*
X332078D03*
X325318D03*
X335458Y279310D03*
X328698D03*
X321938D03*
X335458Y271509D03*
X342218Y252009D03*
X301659Y271509D03*
X328698D03*
X298279Y269560D03*
X348978Y259809D03*
X345598Y257860D03*
X352357D03*
X348978Y337809D03*
X305039Y339760D03*
X298279Y335860D03*
X332078D03*
Y343660D03*
X342218Y337809D03*
Y341709D03*
X328698Y337809D03*
Y341709D03*
X338838Y335860D03*
Y343660D03*
X305039Y335860D03*
X301659Y333909D03*
X335458Y337809D03*
X318558Y328060D03*
Y335860D03*
X301659Y341709D03*
X298279Y339760D03*
X335458Y333909D03*
X318558Y324160D03*
X335458Y341709D03*
X318558Y331960D03*
X305039Y343660D03*
X315178Y326110D03*
Y333909D03*
X325318Y328060D03*
Y331960D03*
X311798Y328060D03*
Y331960D03*
X321938Y326110D03*
Y333909D03*
X308418Y306609D03*
X301659Y310509D03*
Y306609D03*
X311798Y304660D03*
X305039D03*
X321938Y306609D03*
X325318Y304660D03*
Y308560D03*
X298279Y304660D03*
X308418Y302709D03*
X301659D03*
X315178D03*
X321938D03*
X318558Y304660D03*
Y308560D03*
X321938Y291009D03*
X318558Y296860D03*
X315178Y294909D03*
X321938D03*
X301659D03*
X325318Y285160D03*
Y289060D03*
Y296860D03*
X298279D03*
Y289060D03*
X308418Y298809D03*
X301659D03*
X305039Y289060D03*
X308418Y291009D03*
Y287109D03*
X311798Y289060D03*
X308418Y294909D03*
X311798Y296860D03*
X305039D03*
X315178Y287109D03*
X318558Y285160D03*
X321938Y287109D03*
X301659D03*
Y291009D03*
X315178Y298809D03*
X321938D03*
X318558Y289060D03*
X315178Y291009D03*
X332078Y308560D03*
Y304660D03*
X328698Y302709D03*
Y306609D03*
Y287109D03*
Y291009D03*
Y294909D03*
Y298809D03*
X332078Y296860D03*
Y285160D03*
Y289060D03*
X315178Y306609D03*
X308418Y310509D03*
X311798Y312460D03*
X305039D03*
X298279D03*
X308418Y314409D03*
X301659D03*
X335458Y298809D03*
X357057Y296860D03*
X348978Y287109D03*
X345598Y285160D03*
X357057D03*
Y292959D03*
X348978Y298809D03*
Y291009D03*
X345598Y289060D03*
Y292959D03*
Y296860D03*
X348978Y294909D03*
X345598Y300760D03*
X348978Y302709D03*
X357057Y300760D03*
Y308560D03*
X348978Y306609D03*
X345598Y304660D03*
Y308560D03*
X348978Y310509D03*
X357057Y304660D03*
Y289060D03*
X342218Y302709D03*
Y306609D03*
Y291009D03*
Y287109D03*
Y294909D03*
Y298809D03*
X338838Y308560D03*
X335458Y302709D03*
X338838Y304660D03*
X335458Y306609D03*
Y287109D03*
X338838Y289060D03*
Y285160D03*
X335458Y291009D03*
X338838Y296860D03*
X335458Y294909D03*
X348978Y314409D03*
X357057Y312460D03*
X345598D03*
X357987Y327609D03*
X348978Y322209D03*
X355737Y333909D03*
X345598Y316360D03*
X348978Y318309D03*
Y330009D03*
X352357Y331960D03*
X348978Y326110D03*
X357057Y320260D03*
Y324160D03*
Y316360D03*
X328698Y314409D03*
X321938D03*
X332078Y328060D03*
X328698Y322209D03*
Y318309D03*
X332078Y324160D03*
Y320260D03*
Y316360D03*
X325318Y320260D03*
X305039D03*
X321938Y318309D03*
X315178D03*
X318558Y316360D03*
X301659Y322209D03*
X325318Y316360D03*
X305039Y324160D03*
X311798Y320260D03*
X308418Y322209D03*
X301659Y326110D03*
X335458Y314409D03*
Y326110D03*
Y318309D03*
Y322209D03*
X338838Y320260D03*
Y324160D03*
Y328060D03*
X298279Y324160D03*
Y320260D03*
X355737Y345609D03*
X348978Y341709D03*
X352357Y343660D03*
X321938Y341709D03*
X352357Y339760D03*
X321938Y345609D03*
X359117Y343660D03*
X355737Y341709D03*
X298279Y374860D03*
Y382660D03*
X308418Y376809D03*
Y380709D03*
X305039Y374860D03*
Y382660D03*
X301659Y376809D03*
X328698Y353409D03*
X301659Y384609D03*
X328698Y361209D03*
X301659Y372909D03*
X328698Y349509D03*
X301659Y380709D03*
X328698Y357309D03*
X325318Y351460D03*
Y359260D03*
X321938Y353409D03*
Y357309D03*
X332078Y351460D03*
X301659Y365109D03*
X298279Y367060D03*
X305039Y355360D03*
X301659Y353409D03*
X318558Y363160D03*
X311798Y367060D03*
X321938Y372909D03*
X318558Y374860D03*
X315178Y361209D03*
X311798Y363160D03*
X321938Y369010D03*
X315178Y372909D03*
X298279Y347560D03*
X301659Y345609D03*
X305039Y359260D03*
X298279Y355360D03*
X301659Y361209D03*
X318558Y367060D03*
X311798Y370959D03*
X335458Y345609D03*
X305039Y363160D03*
X321938Y365109D03*
X298279Y359260D03*
X315178Y369010D03*
Y349509D03*
Y353409D03*
X348978Y345609D03*
X311798Y355360D03*
Y347560D03*
Y351460D03*
X308418Y349509D03*
X345598Y347560D03*
X315178Y384609D03*
Y380709D03*
X328698Y372909D03*
Y369010D03*
X352357Y347560D03*
X300982Y518157D03*
Y528899D03*
X304328Y513114D03*
X297635D03*
X301092Y493300D03*
X304392Y494700D03*
X297835Y494944D03*
X304328Y535100D03*
X297635D03*
X300982Y555957D03*
X304328Y572900D03*
Y550914D03*
X300982Y566699D03*
X297635Y572900D03*
Y550914D03*
X304328Y588714D03*
X297635D03*
X331100Y585714D03*
X314368D03*
X321061D03*
X341140Y585722D03*
X351179D03*
X308157Y607220D03*
X321061Y607292D03*
X327754Y612457D03*
X324407Y604499D03*
Y609864D03*
X314368Y607292D03*
X311021Y609864D03*
X304328Y610700D03*
X300982Y593757D03*
Y604499D03*
X297635Y610700D03*
X334447Y612457D03*
X331100Y604614D03*
X354526Y607292D03*
X354525Y612358D03*
X351179Y604499D03*
X347833Y612357D03*
X344486Y609864D03*
Y604614D03*
X337793Y609864D03*
X341140Y607292D03*
X334447D03*
X327754D03*
X331100Y609864D03*
X327754Y593657D03*
X317714D03*
X311021D03*
X317714Y604614D03*
X311021D03*
X314368Y612457D03*
X321061D03*
X337793Y593657D03*
Y604499D03*
X357872Y604614D03*
Y612242D03*
X352109Y609918D03*
X347833Y607292D03*
X341140Y612457D03*
X347833Y593657D03*
X317714Y609864D03*
X404722Y-9901D03*
X401375Y-1743D03*
X364565Y-9786D03*
Y-1858D03*
Y9114D03*
X361218Y-9786D03*
Y-1858D03*
Y9114D03*
X414761Y-7108D03*
X398029Y-9901D03*
X404722Y-4536D03*
X414761Y-1743D03*
X408068Y-7108D03*
X394682Y11792D03*
X394683Y-2200D03*
X367911Y-9786D03*
Y-1858D03*
Y9114D03*
X398029Y-4536D03*
X401375Y-7108D03*
X408068Y-1743D03*
X418108Y-4536D03*
X411415Y-9786D03*
X398029Y9107D03*
X418108Y-9701D03*
X411416Y17057D03*
X401376Y17042D03*
X418108D03*
Y9107D03*
X408069D03*
X376700Y-1300D03*
X371258Y-1858D03*
Y-9800D03*
X411415Y-4536D03*
X374401Y-11346D03*
X394682Y17157D03*
X415634Y220096D03*
Y216196D03*
X419214Y218147D03*
Y222047D03*
X415634Y239596D03*
Y243496D03*
X419214Y245447D03*
X415634Y227896D03*
Y231797D03*
X419214Y225947D03*
Y229847D03*
X372637Y253960D03*
X368127Y264300D03*
X364747Y266300D03*
X362497Y259809D03*
X365877Y257860D03*
X369257Y255909D03*
X388407Y256500D03*
X374887Y260300D03*
X359117Y261760D03*
X371507Y262300D03*
X381647Y256400D03*
X378267Y258400D03*
X395166Y256400D03*
X418084Y253546D03*
X405306Y254500D03*
X401926Y256500D03*
X359117Y250060D03*
Y253960D03*
X365877Y250060D03*
X362497Y252009D03*
X364747Y331509D03*
X361367Y329560D03*
X371507Y335409D03*
X362497Y337809D03*
X369257Y341709D03*
X368127Y333460D03*
X365877Y339760D03*
X372637Y343660D03*
X374887Y337360D03*
X381647Y341260D03*
X378267Y339309D03*
X359117Y335860D03*
X362497Y345609D03*
X411431Y359351D03*
X411086Y355360D03*
X365877Y347560D03*
X359117D03*
X394682Y588392D03*
X398029Y585707D03*
X408069D03*
X418108Y585599D03*
X370596Y585614D03*
X404722Y604499D03*
X401376Y612658D03*
X364565Y604614D03*
X361218D03*
X361964Y593642D03*
X361218Y612242D03*
X414761Y607292D03*
X398029Y604499D03*
X404722Y609864D03*
X414761Y612657D03*
X408068Y607292D03*
X394682Y612657D03*
X408068D03*
X367911Y604614D03*
X418108Y609864D03*
X398029D03*
X401376Y593642D03*
X401375Y607292D03*
X418108Y593642D03*
X411416Y593657D03*
X411415Y604614D03*
X418108Y604499D03*
X378600Y606200D03*
X371312Y604709D03*
X371134Y612453D03*
X411415Y609864D03*
X394682Y607292D03*
X421454Y-1817D03*
X460912Y33700D03*
X458266Y27899D03*
X481691D03*
X454533Y33700D03*
X451573Y27899D03*
X478344Y34100D03*
X474998Y27899D03*
X438187Y-4536D03*
X431494Y-9901D03*
X444880Y-9786D03*
Y-4536D03*
X460912Y-4100D03*
X458266Y17157D03*
Y-9901D03*
X460912Y12114D03*
X481691Y17157D03*
Y-9901D03*
X451573Y17157D03*
X454533Y-4100D03*
X451573Y-9901D03*
X454619Y12114D03*
X478344Y-3700D03*
X474998Y17157D03*
Y-9901D03*
X478344Y12114D03*
X428147Y-1743D03*
X421454Y-7108D03*
X434840Y-1743D03*
X424801Y-9786D03*
X438187D03*
X431494Y-4536D03*
X424801D03*
X428147Y-7108D03*
X434840D03*
X441533Y-1843D03*
X434842Y17057D03*
X441533Y17042D03*
X428149Y17057D03*
X441533Y9107D03*
X424801D03*
X431494D03*
X448226Y11100D03*
X460912Y71500D03*
X458266Y92757D03*
Y65699D03*
X460912Y87714D03*
X481691Y92757D03*
Y65699D03*
X454533Y71500D03*
X451573Y92757D03*
Y65699D03*
X454619Y87714D03*
X478344Y71900D03*
X474998Y92757D03*
Y65699D03*
X478344Y87714D03*
X458266Y54957D03*
X460912Y49914D03*
X481691Y54957D03*
X451573D03*
X454619Y49564D03*
X474998Y54957D03*
X478344Y49914D03*
X436113Y220096D03*
X446253Y222047D03*
X432733D03*
X442873Y220096D03*
X456393D03*
X466533Y222047D03*
X453013D03*
X463153Y220096D03*
X473292Y222047D03*
X439493Y218147D03*
X459773D03*
X480052D03*
X439493Y222047D03*
X459773D03*
X480052D03*
X425974D03*
X422594Y220096D03*
X458400Y276400D03*
X436113Y227896D03*
X446253Y225947D03*
X432733D03*
X442873Y227896D03*
X456393D03*
X466533Y225947D03*
X453013D03*
X463153Y227896D03*
X476672D03*
X473292Y225947D03*
X439493Y229847D03*
X459773D03*
X439493Y225947D03*
X459773D03*
X480052Y229847D03*
X425974Y225947D03*
X422594Y227896D03*
X466533Y233746D03*
Y241547D03*
X476672Y239596D03*
X463153Y235696D03*
Y239596D03*
X473292Y233746D03*
Y241547D03*
X469913Y231797D03*
Y243496D03*
Y235696D03*
Y239596D03*
X425974Y233746D03*
Y241547D03*
X436113Y235696D03*
Y239596D03*
X422594Y235696D03*
Y239596D03*
X432733Y233746D03*
Y241547D03*
X446253Y233746D03*
Y241547D03*
X456393Y235696D03*
Y239596D03*
X442873Y235696D03*
Y239596D03*
X453013Y233746D03*
Y241547D03*
X456393Y247396D03*
Y255196D03*
X466533Y249347D03*
Y253247D03*
X453013Y249347D03*
Y253247D03*
X463153Y247396D03*
Y255196D03*
X476672Y247396D03*
Y255196D03*
X473292Y249347D03*
Y253247D03*
X429354Y231797D03*
X449633D03*
X459773Y245447D03*
X480052D03*
X429354Y243496D03*
X449633D03*
X459773Y257147D03*
X480052D03*
X429354Y235696D03*
X449633D03*
X459773Y249347D03*
X480052D03*
X429354Y239596D03*
X449633D03*
X459773Y253247D03*
X480052D03*
X452865Y270081D03*
X465100Y280300D03*
X434983Y255497D03*
X438363Y257446D03*
X421464Y255497D03*
X431604Y257446D03*
X448503Y263297D03*
X441743Y259397D03*
X455263Y267197D03*
X436113Y247396D03*
X446253Y249347D03*
X442873Y251296D03*
X439493Y249347D03*
X442873Y247396D03*
X439493Y245447D03*
X446253Y253247D03*
X466533Y261047D03*
X463153Y262996D03*
X477792Y276646D03*
Y280547D03*
X469913Y282496D03*
X474413Y274696D03*
X469913Y278596D03*
X466533Y268847D03*
X422594Y247396D03*
X429781Y264793D03*
X459773Y264947D03*
X469913Y266896D03*
Y262996D03*
X473292Y261047D03*
X469913Y259096D03*
X481172Y282496D03*
Y270796D03*
X480052Y264947D03*
X473292D03*
Y268847D03*
X476672Y266896D03*
Y262996D03*
X474413Y344896D03*
X481172Y321496D03*
Y325396D03*
Y317596D03*
Y333196D03*
X463671Y319386D03*
X466734Y287074D03*
X442020Y339220D03*
X438240Y339380D03*
X451883Y342646D03*
X448503Y344597D03*
X481172Y298096D03*
X469913D03*
Y301996D03*
X481172Y305896D03*
X477792Y284447D03*
Y296147D03*
Y300047D03*
Y292247D03*
X481172Y294196D03*
X469913D03*
Y290296D03*
X474413Y329296D03*
X468783Y332897D03*
X474413Y333196D03*
Y325396D03*
X477792Y323446D03*
X463800Y289500D03*
X464273Y342947D03*
X471033Y339047D03*
X456900Y333000D03*
X481172Y329296D03*
X471033Y342947D03*
X466100Y300021D03*
X460893Y344896D03*
X481172Y286396D03*
X477792Y311747D03*
X469913Y309797D03*
Y313696D03*
Y317596D03*
X477792Y339047D03*
Y335147D03*
Y331247D03*
X481172Y340996D03*
Y337096D03*
X453400Y293686D03*
X477792Y346847D03*
X481172Y348796D03*
X477792Y350747D03*
X443993Y381947D03*
Y389747D03*
X454133Y383896D03*
Y387796D03*
X440613Y383896D03*
Y387796D03*
X450753Y381947D03*
Y389747D03*
X464273Y381947D03*
Y389747D03*
X474413Y383896D03*
Y387796D03*
X460893Y383896D03*
Y387796D03*
X471033Y381947D03*
Y389747D03*
X481172Y383896D03*
Y387796D03*
X447373Y383896D03*
X467653Y379996D03*
X447373Y391696D03*
X467653D03*
X447373Y379996D03*
X467653Y383896D03*
X447373Y387796D03*
X467653D03*
X423714Y389747D03*
Y393647D03*
X433854Y383896D03*
Y387796D03*
X423714Y378047D03*
Y381947D03*
X430474D03*
Y389747D03*
X474413Y368296D03*
Y376096D03*
X481172Y364396D03*
X471033Y370247D03*
Y374146D03*
X481172Y368296D03*
Y376096D03*
X427094Y383896D03*
X477792Y370247D03*
X427094Y391696D03*
X477792Y378047D03*
X427094Y379996D03*
X477792Y366347D03*
X427094Y387796D03*
X477792Y374146D03*
X427094Y364396D03*
X423714Y370247D03*
X437233Y366347D03*
Y370247D03*
X423714Y358547D03*
Y366347D03*
X433854Y364396D03*
Y372197D03*
X454133Y368296D03*
Y376096D03*
X464273Y370247D03*
Y374146D03*
X450753Y370247D03*
Y374146D03*
X460893Y368296D03*
Y376096D03*
X443993Y354647D03*
Y362447D03*
X454133Y356596D03*
Y360496D03*
X440613Y356596D03*
Y360496D03*
X450753Y354647D03*
Y362447D03*
X464273Y354647D03*
Y362447D03*
X474413Y356596D03*
Y360496D03*
X460893Y356596D03*
Y360496D03*
X471033Y354647D03*
Y362447D03*
X430474Y366347D03*
X457513Y370247D03*
X447373Y356596D03*
X467653D03*
X430474Y370247D03*
X457513Y378047D03*
X447373Y364396D03*
X467653D03*
X430474Y362447D03*
X457513Y366347D03*
X447373Y352696D03*
X467653D03*
X430474Y374146D03*
X457513D03*
X447373Y360496D03*
X467653D03*
X438363Y346546D03*
X424844D03*
X434983Y348497D03*
X428224D03*
X431604Y346546D03*
X471033Y346847D03*
X464273D03*
X457513Y350747D03*
X430474Y358547D03*
X433854Y356596D03*
X437233Y378047D03*
X440613Y376096D03*
X443993Y374147D03*
Y370247D03*
X481172Y356596D03*
X458266Y518157D03*
X460912Y513114D03*
X458266Y528899D03*
X481691Y518157D03*
Y528899D03*
X451573Y518157D03*
Y528899D03*
X454619Y513114D03*
X474998Y518157D03*
Y528899D03*
X478344Y513114D03*
X460912Y534700D03*
X454533D03*
X478344Y535100D03*
X458266Y555957D03*
X460912Y572500D03*
Y550914D03*
X458266Y566699D03*
X481691Y555957D03*
Y566699D03*
X451573Y555957D03*
X454533Y572500D03*
X451573Y566699D03*
X454619Y550914D03*
X474998Y555957D03*
X478344Y572900D03*
Y550914D03*
X474998Y566699D03*
X460912Y588714D03*
X454619D03*
X478344D03*
X441533Y585707D03*
X431494D03*
X424801D03*
X447735Y588394D03*
X421454Y612560D03*
X438187Y609864D03*
X431494Y604499D03*
X444880Y604614D03*
Y609864D03*
X458266Y593757D03*
X460912Y610300D03*
X458266Y604499D03*
X481691Y593757D03*
Y604499D03*
X454533Y610300D03*
X451573Y593757D03*
Y604499D03*
X478344Y610700D03*
X474998Y593757D03*
Y604499D03*
X428147Y612657D03*
X421454Y607292D03*
X434840Y612657D03*
X424801Y604614D03*
X438187D03*
X441533Y612557D03*
Y607292D03*
X434840D03*
X428147D03*
X424801Y609864D03*
X431494D03*
X434842Y593657D03*
X428149D03*
X441533Y593642D03*
X447766Y612659D03*
X485037Y34100D03*
X497723Y33700D03*
X495077Y27899D03*
X521848Y34100D03*
X518502Y27899D03*
X491344Y33700D03*
X488384Y27899D03*
X515155Y34100D03*
X511809Y27899D03*
X534534Y33700D03*
X531888Y27899D03*
X528155Y33700D03*
X525195Y27899D03*
X485037Y-3700D03*
Y12114D03*
X497723Y-4100D03*
X495077Y17157D03*
Y-9901D03*
X497723Y12114D03*
X521848Y-3700D03*
X518502Y17157D03*
Y-9901D03*
X521848Y12114D03*
X491344Y-4100D03*
X488384Y17157D03*
Y-9901D03*
X491430Y12114D03*
X511809Y17157D03*
X515155Y-3700D03*
X511809Y-9901D03*
X515155Y12114D03*
X534534Y-4100D03*
X531888Y17157D03*
Y-9901D03*
X534534Y12114D03*
X528155Y-4100D03*
X525195Y17157D03*
Y-9901D03*
X528241Y12114D03*
X485037Y71900D03*
Y87714D03*
X497723Y71500D03*
X495077Y92757D03*
Y65699D03*
X497723Y87714D03*
X521848Y71900D03*
X518502Y92757D03*
Y65699D03*
X521848Y87714D03*
X491344Y71500D03*
X488384Y92757D03*
Y65699D03*
X491430Y87714D03*
X511809Y92757D03*
X515155Y71900D03*
X511809Y65699D03*
X515155Y87714D03*
X534534Y71500D03*
X531888Y92757D03*
Y65699D03*
X534534Y87714D03*
X528155Y71500D03*
X525195Y92757D03*
Y65699D03*
X528241Y87714D03*
X485037Y49914D03*
X495077Y54957D03*
X497723Y49914D03*
X518502Y54957D03*
X521848Y49914D03*
X488384Y54957D03*
X491430Y49914D03*
X511809Y54957D03*
X515155Y49914D03*
X531888Y54957D03*
X534534Y49914D03*
X525195Y54957D03*
X528241Y49914D03*
X494927Y112357D03*
X497723Y106964D03*
X518317Y112357D03*
X521113Y106964D03*
X488634Y112357D03*
X491430Y106964D03*
X512024Y112357D03*
X514820Y106964D03*
X531888Y112357D03*
X534534Y106964D03*
X525134Y112357D03*
X528241Y107314D03*
X483432Y220096D03*
X511592Y222047D03*
X514972Y220096D03*
X518352Y222047D03*
X521731Y216196D03*
X531871Y218147D03*
X542011Y208396D03*
X528491Y204496D03*
X538631Y202247D03*
X525111Y222047D03*
Y210346D03*
X521731Y212296D03*
X514972Y208397D03*
Y212296D03*
X508212Y216196D03*
X501452Y220096D03*
X504832Y214247D03*
X498072Y218147D03*
Y214247D03*
X494692Y220096D03*
X542011Y216196D03*
X538631Y218147D03*
X535251Y212296D03*
X531871Y210346D03*
Y214247D03*
X525111D03*
X518352D03*
Y210345D03*
X514972Y216196D03*
X511592Y214247D03*
X504832Y222047D03*
Y218147D03*
X501452Y216196D03*
X494692Y212296D03*
Y216196D03*
X542011Y212296D03*
Y220096D03*
X535251D03*
Y208397D03*
X528491Y212296D03*
X535251Y216196D03*
X484552Y272747D03*
Y276646D03*
X501452Y270796D03*
X511592Y268847D03*
X514972Y255196D03*
X501452D03*
Y251296D03*
X521731Y270796D03*
X514972Y282496D03*
X521731D03*
X508212D03*
X494692D03*
X491312Y280547D03*
X486812Y261047D03*
X483432Y262996D03*
X518352Y261047D03*
X525111D03*
X514972Y251296D03*
X518352Y272747D03*
X521731Y255196D03*
Y251296D03*
X498072Y264947D03*
X511592Y245447D03*
X514972Y243496D03*
X483432Y227896D03*
X486812Y249347D03*
Y253247D03*
X483432Y247396D03*
Y255196D03*
X498072Y280547D03*
X514972Y274696D03*
X525111Y272747D03*
X518352Y257147D03*
X508212Y274696D03*
X504832Y268847D03*
X491312Y272747D03*
X511592D03*
X504832Y276647D03*
X498072Y245447D03*
X494692Y223996D03*
X504832Y225947D03*
X484552Y280547D03*
X518352Y233746D03*
X531871Y241547D03*
Y249347D03*
X528491Y223996D03*
X531871Y237647D03*
X535251Y223996D03*
X542011D03*
X528491Y270796D03*
Y278596D03*
X542011Y270796D03*
X535251Y255196D03*
X531871Y264947D03*
X494692Y266896D03*
X504832Y257147D03*
X508212Y251296D03*
X504832Y249347D03*
X508212Y247396D03*
X518352Y264947D03*
X508212Y243496D03*
X518352Y245447D03*
X531871Y257147D03*
X528491Y255196D03*
X511592Y253247D03*
X525111Y268847D03*
X518352Y241547D03*
Y237647D03*
X521731Y239596D03*
Y243496D03*
X528491Y262996D03*
Y266896D03*
X498072Y249347D03*
X525111D03*
Y245447D03*
X508212Y266896D03*
X521731Y278596D03*
X498072Y276647D03*
X491312D03*
X511592D03*
X504832Y272747D03*
X498072Y253247D03*
Y257147D03*
X518352Y280547D03*
X535251Y243496D03*
X542011Y266896D03*
X538631Y272747D03*
X531871D03*
X538631Y280547D03*
X542011Y282496D03*
X538631Y276646D03*
X535251Y278596D03*
X531871Y280547D03*
X538631Y241547D03*
X542011Y243496D03*
Y251296D03*
Y255196D03*
Y262996D03*
X538631Y261047D03*
X531871Y245447D03*
X538631Y264947D03*
Y268847D03*
X535251Y270796D03*
X542011Y278596D03*
X535251Y274696D03*
Y282496D03*
X528491D03*
X538631Y245447D03*
Y253247D03*
X542011Y259096D03*
X535251Y262996D03*
X511592Y229847D03*
Y225947D03*
Y237647D03*
X508212Y235696D03*
X498072Y229847D03*
X504832Y233746D03*
X494692Y227896D03*
X501452Y235696D03*
X498072Y237647D03*
Y241547D03*
X542011Y227896D03*
Y235696D03*
X535251Y231797D03*
Y227896D03*
X531871Y229847D03*
X525111Y233746D03*
X521731Y223996D03*
X525111Y229847D03*
X514972Y231797D03*
X508212Y227896D03*
X511592Y233746D03*
X504832Y237647D03*
X501452Y227896D03*
Y231797D03*
X494692D03*
X501452Y239596D03*
X494692D03*
X501452Y243496D03*
X542011Y231797D03*
X538631Y233746D03*
Y229847D03*
X531871Y225947D03*
Y233746D03*
X528491Y231797D03*
X525111Y225947D03*
X518352D03*
X521731Y227896D03*
X525111Y257147D03*
X528491Y259096D03*
X525111Y276646D03*
X504832Y280547D03*
X511592D03*
X518352Y276646D03*
Y268847D03*
X498072Y272747D03*
X531871Y253247D03*
X528491Y251296D03*
X525111Y241547D03*
X528491Y239596D03*
X518352Y249347D03*
X513857Y260881D03*
X501452Y262996D03*
X504832Y261047D03*
X501452Y278596D03*
X498072Y268847D03*
X504832Y264947D03*
X494692Y262996D03*
X491312Y264947D03*
X487932Y266896D03*
X491312Y268847D03*
X487932Y270796D03*
X498072Y261047D03*
X494692Y259096D03*
X521731Y262996D03*
X525111Y264947D03*
X494692Y274696D03*
X487932Y313696D03*
X491312Y315647D03*
X484552Y319546D03*
Y331247D03*
X491312Y288347D03*
Y284447D03*
X498072D03*
Y288347D03*
X501452Y286396D03*
X494692Y290296D03*
X498072Y292247D03*
X504832D03*
X518352Y284447D03*
X504832Y288347D03*
Y284447D03*
X508212Y286396D03*
X531871Y315647D03*
X487932Y286396D03*
X514972Y344896D03*
X511592Y342947D03*
X508212Y340996D03*
Y344896D03*
X487932Y290296D03*
X484552Y288347D03*
Y296147D03*
X498072Y339047D03*
X504832Y327347D03*
X508212Y321496D03*
X514972Y340996D03*
X518352Y331247D03*
X521731Y344896D03*
Y321496D03*
X525111Y339047D03*
X535251Y333196D03*
Y325396D03*
X484552Y284447D03*
X487932Y305896D03*
X491312Y303947D03*
X501452Y305896D03*
X494692Y298096D03*
X498072Y307847D03*
X484552Y303947D03*
X487932Y294196D03*
X491312Y296147D03*
X494692Y301996D03*
X487932D03*
X501452Y309797D03*
X487932Y298096D03*
X511592Y311747D03*
X508212Y309797D03*
X511592Y300047D03*
Y303947D03*
X542011Y286396D03*
X531871Y284447D03*
X542011Y290296D03*
X535251Y286396D03*
X542011Y313696D03*
Y309797D03*
X538631Y307847D03*
Y303947D03*
Y300047D03*
X535251Y298096D03*
Y317596D03*
X542011D03*
Y305896D03*
X535251D03*
X542011Y301996D03*
X538631Y296147D03*
X531871D03*
X535251Y313696D03*
X538631Y315647D03*
X484552Y311747D03*
Y315647D03*
X511592Y288347D03*
Y292245D03*
X491312Y323446D03*
X528491Y305896D03*
X518352Y311747D03*
X504832D03*
X508212Y305896D03*
Y301996D03*
X504832Y303947D03*
Y300045D03*
X518352Y303947D03*
X514972Y305896D03*
Y309797D03*
X528491Y301996D03*
Y309797D03*
X525111Y311747D03*
Y307847D03*
Y303947D03*
X521731Y305896D03*
Y309797D03*
X518352Y307847D03*
X514972Y313696D03*
X528491D03*
X521731D03*
X487932Y344896D03*
X484552Y342947D03*
X518352Y296147D03*
Y300047D03*
X521731Y294196D03*
X525111Y288347D03*
X528491Y290296D03*
X525111Y296147D03*
Y292245D03*
X521731Y298096D03*
Y290296D03*
Y286396D03*
X518352Y288347D03*
Y292245D03*
X514972Y298096D03*
X501452Y325396D03*
X498072Y323446D03*
Y315647D03*
X501452Y317596D03*
X498072Y335147D03*
X501452Y321496D03*
X498072Y331247D03*
X501452Y329296D03*
Y313696D03*
X498072Y300047D03*
X508212Y298096D03*
X504832Y296147D03*
X498072D03*
X501452Y294196D03*
X511592Y296147D03*
X498072Y311747D03*
X501452Y301996D03*
X494692Y325396D03*
Y321496D03*
X491312Y319547D03*
X494692Y333196D03*
X491312Y335147D03*
X487932Y333196D03*
Y337096D03*
X484552Y339047D03*
Y335147D03*
X491312Y327347D03*
X494692Y329296D03*
X487932D03*
Y340996D03*
X494692Y313696D03*
X484552Y307847D03*
X491312D03*
Y311747D03*
X494692Y305896D03*
Y317596D03*
X487932Y321496D03*
X484552Y327347D03*
X487932Y325396D03*
X484552Y381947D03*
X494692Y395597D03*
X491312Y401447D03*
X487932Y379996D03*
Y391696D03*
Y387796D03*
X514972Y352696D03*
Y348796D03*
X511592Y350747D03*
Y346847D03*
X508212Y348796D03*
X504832Y362447D03*
X494692Y368296D03*
Y352696D03*
X508212Y356596D03*
X504832Y350747D03*
X511592Y374146D03*
X501452Y383896D03*
X498072Y389747D03*
X494692Y376096D03*
X508212Y379996D03*
X521731Y368296D03*
X518352Y366347D03*
Y358547D03*
X542011Y364396D03*
X538631Y370247D03*
X542011Y372197D03*
Y352696D03*
X525111Y350747D03*
X514972Y399496D03*
X538631Y381947D03*
X531871Y385847D03*
X528491Y391696D03*
X525111Y397546D03*
X531871Y405347D03*
X504832Y370247D03*
X508212Y376096D03*
X501452Y372197D03*
X498072Y370247D03*
X504832Y397546D03*
Y393647D03*
X511592D03*
X501452Y387796D03*
X511592Y385847D03*
X518352D03*
Y381947D03*
Y378047D03*
X508212Y395597D03*
X504832Y389747D03*
X508212Y391696D03*
X504832Y385847D03*
X511592Y381947D03*
X514972Y383896D03*
X521731Y379996D03*
X518352Y374146D03*
Y405347D03*
X525111D03*
Y401447D03*
X528491Y395597D03*
X535251Y399496D03*
X531871Y393647D03*
X538631Y389747D03*
Y385847D03*
X518352Y401447D03*
X521731Y403396D03*
X528491Y399496D03*
X531871Y397546D03*
X535251Y395597D03*
Y391696D03*
Y387796D03*
X542011Y383896D03*
Y391696D03*
Y395597D03*
Y387796D03*
X525111Y370247D03*
X531871D03*
X525111Y362447D03*
X528491Y360496D03*
Y356596D03*
X535251Y352696D03*
X525111Y378047D03*
Y374146D03*
Y366347D03*
X528491Y368296D03*
X521731Y364396D03*
X525111Y358547D03*
X531871Y354647D03*
Y350747D03*
X521731Y376096D03*
X528491Y372197D03*
X542011Y379996D03*
X535251Y376096D03*
X487932Y352696D03*
X484552Y354647D03*
Y350747D03*
Y358547D03*
X487932Y348796D03*
X485037Y513114D03*
X495077Y518157D03*
X497723Y513114D03*
X495077Y528899D03*
X518502Y518157D03*
X521848Y513114D03*
X518502Y528899D03*
X488384Y518157D03*
Y528899D03*
X491430Y513114D03*
X511809Y518157D03*
Y528899D03*
X515155Y513114D03*
X531888Y518157D03*
X534534Y513114D03*
X531888Y528899D03*
X525195Y518157D03*
X528241Y513114D03*
X525195Y528899D03*
X494777Y498487D03*
X497723Y490894D03*
X517902Y498487D03*
X521048Y493844D03*
X488384Y498487D03*
X491430Y491144D03*
X511809Y498487D03*
X514755Y493744D03*
X530792Y498387D03*
X534534Y493394D03*
X524595Y498387D03*
X528191Y493544D03*
X485037Y535100D03*
X497723Y534700D03*
X521848Y535100D03*
X491344Y534700D03*
X515155Y535100D03*
X534534Y534700D03*
X528155D03*
X485037Y572900D03*
Y550914D03*
X495077Y555957D03*
X497723Y572500D03*
Y550914D03*
X495077Y566699D03*
X518502Y555957D03*
X521848Y572900D03*
Y550914D03*
X518502Y566699D03*
X488384Y555957D03*
X491344Y572500D03*
X491430Y550914D03*
X488384Y566699D03*
X511809Y555957D03*
X515155Y572900D03*
Y550914D03*
X511809Y566699D03*
X531888Y555957D03*
X534534Y572500D03*
Y550914D03*
X531888Y566699D03*
X525195Y555957D03*
X528155Y572500D03*
X528241Y550914D03*
X525195Y566699D03*
X485037Y588714D03*
X497723D03*
X521848D03*
X491430D03*
X515155D03*
X534534D03*
X528241D03*
X485037Y610700D03*
X495077Y593757D03*
X498092Y611200D03*
X495077Y604499D03*
X521848Y610700D03*
X518502Y593757D03*
Y604499D03*
X488384Y593757D03*
X491724Y611668D03*
X488384Y604499D03*
X515155Y610700D03*
X511809Y593757D03*
Y604499D03*
X534534Y610300D03*
X531888Y593757D03*
Y604499D03*
X528155Y610300D03*
X525195Y593757D03*
Y604499D03*
X558659Y34100D03*
X555313Y27899D03*
X551966Y34100D03*
X548620Y27899D03*
X571345Y33700D03*
X568699Y27899D03*
X595470Y34100D03*
X592124Y27899D03*
X564966Y33700D03*
X562006Y27899D03*
X588777Y34100D03*
X585431Y27899D03*
X558659Y-3700D03*
X555313Y17157D03*
Y-9901D03*
X558659Y12114D03*
X551966Y-3700D03*
X548620Y17157D03*
Y-9901D03*
X551966Y12114D03*
X571345Y-4100D03*
X568699Y17157D03*
Y-9901D03*
X571345Y12114D03*
X595470Y-3700D03*
X592124Y17157D03*
Y-9901D03*
X595470Y12114D03*
X564966Y-4100D03*
X561868Y17019D03*
X562006Y-9901D03*
X565052Y12114D03*
X588777Y-3700D03*
X585431Y17157D03*
Y-9901D03*
X588777Y12114D03*
X598817Y17057D03*
X602163Y9157D03*
Y-1743D03*
Y36057D03*
Y27899D03*
X605510D03*
Y-9901D03*
Y16999D03*
Y-1743D03*
Y9157D03*
Y36057D03*
X558659Y71900D03*
X555313Y92757D03*
Y65699D03*
X558659Y87714D03*
X551966Y71900D03*
X548620Y92757D03*
Y65699D03*
X551966Y87714D03*
X571345Y71500D03*
X568699Y92757D03*
Y65699D03*
X571345Y87714D03*
X595470Y71900D03*
X592124Y92757D03*
Y65699D03*
X595470Y87714D03*
X564966Y71500D03*
X562006Y92757D03*
Y65699D03*
X565266Y87374D03*
X588777Y71900D03*
X585431Y92757D03*
Y65699D03*
X588777Y87714D03*
X555313Y54957D03*
X558659Y49914D03*
X548620Y54957D03*
X551966Y49914D03*
X568699Y54957D03*
X571345Y49914D03*
X592124Y54957D03*
X595470Y49914D03*
X562006Y54957D03*
X565052Y49914D03*
X585431Y54957D03*
X588777Y49914D03*
X598817Y92657D03*
X602163Y84757D03*
Y54799D03*
Y46957D03*
X598817Y54857D03*
X602163Y73857D03*
X605510Y92599D03*
Y65699D03*
Y54799D03*
Y46957D03*
Y84757D03*
Y73857D03*
X603163Y103971D03*
X555313Y112357D03*
X558659Y107314D03*
X548620Y112357D03*
X551966Y107314D03*
X605028Y119000D03*
X604977Y110200D03*
X558911Y218147D03*
X555531Y220096D03*
X548771D03*
X545391Y218147D03*
Y214247D03*
X552151Y222047D03*
X548771Y216196D03*
X603273Y198896D03*
X600286Y202921D03*
X599773Y199596D03*
X592300Y220500D03*
X552151Y237647D03*
X555531Y231797D03*
X548771Y227896D03*
X552151Y245447D03*
X548771Y251296D03*
X545391Y237647D03*
X548771Y282496D03*
Y270796D03*
Y262996D03*
X545391Y276646D03*
Y245447D03*
Y253247D03*
X548771Y259096D03*
X545391Y241547D03*
X548771Y247396D03*
X545391Y249347D03*
Y257147D03*
Y261047D03*
Y229847D03*
X548771Y231797D03*
X562616Y223996D03*
X555531Y259096D03*
Y266896D03*
X558911Y268847D03*
X552151D03*
Y276646D03*
X555531Y278596D03*
Y282496D03*
X562640Y231735D03*
X555531Y243496D03*
X552151Y253247D03*
X558911Y249347D03*
Y257147D03*
Y225947D03*
X555531Y262996D03*
X552151Y264947D03*
X555531Y270796D03*
X552151Y272747D03*
X548771Y274696D03*
X552151Y280547D03*
X562630Y227896D03*
X558911Y241547D03*
X555531Y251296D03*
X558911Y253247D03*
X555531Y255196D03*
Y227896D03*
Y223996D03*
X548771D03*
Y321496D03*
X545391Y323446D03*
X548771Y337096D03*
X545391Y342947D03*
X548771Y329296D03*
Y290296D03*
Y294196D03*
X545391Y284447D03*
X560884Y290296D03*
X555831Y294196D03*
X552151Y292245D03*
X545391Y311747D03*
X552151Y319547D03*
Y315647D03*
Y311747D03*
X548771Y305896D03*
X552151Y300047D03*
X548771Y301996D03*
X559211Y331103D03*
X555531Y329296D03*
X559211Y323446D03*
X555531Y321496D03*
X548771Y317596D03*
X555831Y313696D03*
X552151Y307847D03*
Y303947D03*
X555831Y301996D03*
X548771Y298096D03*
X559211Y327347D03*
X552151D03*
X555531Y325396D03*
X555831Y317446D03*
X559212Y385847D03*
X552151Y393647D03*
X545391Y389747D03*
Y393647D03*
X559212Y389747D03*
X545391Y378047D03*
X552151Y374146D03*
X545391D03*
X548771Y364396D03*
Y360496D03*
Y356596D03*
Y383896D03*
Y376096D03*
Y372196D03*
X545391Y370247D03*
Y362447D03*
X552151Y358547D03*
X548771Y352696D03*
X545391Y381947D03*
X548771Y379996D03*
X552151Y366347D03*
Y370247D03*
X563500Y360500D03*
X555531Y372197D03*
X548990Y403670D03*
X555750Y399770D03*
X562591Y348796D03*
X592216Y445152D03*
X595070Y447970D03*
X555313Y518157D03*
X558659Y513114D03*
X555313Y528899D03*
X548620Y518157D03*
Y528899D03*
X551966Y513114D03*
X568699Y518157D03*
X571345Y513114D03*
X568699Y528899D03*
X592124Y518157D03*
X595470Y513114D03*
X592124Y528899D03*
X562006Y518157D03*
Y528899D03*
X565266Y512774D03*
X585431Y518157D03*
X588777Y513114D03*
X585431Y528899D03*
X554792Y498487D03*
X558659Y496144D03*
X548492Y498400D03*
X551366Y493344D03*
X602163Y510157D03*
X598817Y518057D03*
X605510Y528899D03*
Y517999D03*
Y510157D03*
X558659Y535100D03*
X551966D03*
X571345Y534700D03*
X595470Y535100D03*
X564966Y534700D03*
X588777Y535100D03*
X555313Y555957D03*
X558659Y572900D03*
Y550914D03*
X555313Y566699D03*
X548620Y555957D03*
X551966Y572900D03*
Y550914D03*
X548620Y566699D03*
X568699Y555957D03*
X571345Y572500D03*
Y550914D03*
X568699Y566699D03*
X592124Y555957D03*
X595470Y572900D03*
Y550914D03*
X592124Y566699D03*
X562006Y555957D03*
X564966Y572500D03*
X565266Y550574D03*
X562006Y566699D03*
X585431Y555957D03*
X588777Y572900D03*
Y550914D03*
X585431Y566699D03*
X558659Y588714D03*
X551966D03*
X571345D03*
X595470D03*
X565052D03*
X588777D03*
X602163Y574857D03*
Y566699D03*
Y555799D03*
X598817Y555857D03*
X602163Y547957D03*
Y537057D03*
Y585757D03*
X605510Y555799D03*
Y566699D03*
Y585757D03*
Y547957D03*
Y574857D03*
Y537057D03*
X558659Y610700D03*
X555313Y593757D03*
Y604499D03*
X551966Y610700D03*
X548620Y593757D03*
Y604499D03*
X571345Y610300D03*
X568699Y593757D03*
Y604499D03*
X592124Y593757D03*
X595470Y610700D03*
X592124Y604499D03*
X564966Y610300D03*
X562006Y593757D03*
Y604499D03*
X585431Y593757D03*
X588777Y610700D03*
X585431Y604499D03*
X598817Y593657D03*
X602163Y612657D03*
X605510Y604499D03*
Y593599D03*
Y612657D03*
X661494Y32946D03*
X657250Y-2050D03*
X608856Y16999D03*
X612203D03*
Y9157D03*
X608856D03*
X615549D03*
X608856Y-9901D03*
X612203D03*
X608856Y-1743D03*
X612203D03*
X615549D03*
Y36057D03*
X608856D03*
X612203D03*
Y27899D03*
X608856D03*
X659747Y-12132D03*
X615549Y27899D03*
Y-9901D03*
Y16999D03*
X659700Y22900D03*
X665396Y23000D03*
X615549Y84757D03*
X608856D03*
X612203D03*
X608856Y92599D03*
X612203D03*
X608856Y46957D03*
X612203D03*
X608856Y54799D03*
X615549Y46957D03*
X612203Y54799D03*
X608856Y65699D03*
X612203D03*
X615549Y73857D03*
X608856D03*
X612203D03*
X652718Y93881D03*
X664471Y86061D03*
X662352Y89566D03*
X615549Y92599D03*
Y65699D03*
Y54799D03*
X626040Y98281D03*
X608600Y103000D03*
X613602Y118047D03*
Y109247D03*
X633800Y119000D03*
X658055Y141493D03*
X647555Y143643D03*
X651055Y142893D03*
X654555Y142193D03*
X642673Y139811D03*
X644055Y144493D03*
X635673Y141318D03*
X639173Y140618D03*
X632173Y142018D03*
X628673Y142718D03*
X609482Y124568D03*
X618800Y100100D03*
X644750Y175650D03*
X660600Y170000D03*
Y175000D03*
X611148Y206994D03*
X618648Y219494D03*
Y214494D03*
X608648Y204494D03*
X613648D03*
X610273Y197496D03*
X613773Y196796D03*
X613082Y200676D03*
X609860Y201356D03*
X654950Y253446D03*
X627529Y280441D03*
X618279Y251393D03*
X624500Y240500D03*
X639320Y268000D03*
X643500Y274868D03*
X633410Y269610D03*
Y274610D03*
X651235Y249165D03*
X641665Y281139D03*
X643100Y253700D03*
X649800Y252600D03*
X656100Y275500D03*
X606148Y229494D03*
X617235Y247735D03*
X614456Y244956D03*
X637681Y337390D03*
X628525Y287832D03*
X631250Y289650D03*
X639622Y290210D03*
X643823Y289650D03*
X658500Y284500D03*
X632869Y293720D03*
X648900Y336600D03*
X646520Y297400D03*
X664267Y292668D03*
X637143Y322000D03*
X637561Y312000D03*
Y317000D03*
X637600Y302000D03*
Y307000D03*
X646700Y308850D03*
X658900Y339150D03*
X628950Y293550D03*
X654600Y296000D03*
X662238Y296146D03*
X659694Y351206D03*
X664194D03*
X649194D03*
X654194D03*
X649600Y391200D03*
X640300Y437600D03*
X608800Y463475D03*
Y468475D03*
X609191Y451454D03*
X615300Y457900D03*
X641150Y484300D03*
X653800Y496600D03*
X618430Y491550D03*
X623400Y476300D03*
X629300Y490000D03*
X648500Y477400D03*
X662640Y528330D03*
X608856Y517999D03*
X612203D03*
Y528899D03*
X608856D03*
X615549Y510157D03*
X608856D03*
X612203D03*
X612515Y498752D03*
X609284Y480055D03*
X636500Y493924D03*
X627000Y478300D03*
X611250Y476750D03*
X618800Y474500D03*
X615549Y517999D03*
Y528899D03*
X639120Y475620D03*
X658900Y509300D03*
X639197Y490367D03*
X623600Y521700D03*
X608856Y574857D03*
X612203D03*
X615549D03*
X612203Y566699D03*
X608856D03*
Y555799D03*
X612203D03*
Y547957D03*
X615549D03*
X608856D03*
Y537057D03*
X615549D03*
X612203D03*
X615549Y585757D03*
X612203D03*
X608856D03*
X660217Y576734D03*
X615549Y555799D03*
Y566699D03*
X662000Y589000D03*
X608856Y593599D03*
X612203D03*
X608856Y604499D03*
X612203D03*
X608856Y612657D03*
X615549D03*
X612203D03*
X615549Y604499D03*
Y593599D03*
X665000Y598500D03*
X631741Y615759D03*
X723715Y23462D03*
X692500Y15300D03*
X708000Y26600D03*
X700500D03*
X724837Y13852D03*
X714300Y-1900D03*
X680200Y13100D03*
X675235Y36797D03*
X719400Y14300D03*
X679936Y18406D03*
X670227Y34277D03*
X670400Y26100D03*
X701100Y8100D03*
X704450Y4950D03*
X720572Y88700D03*
X715130Y79574D03*
X697200Y79500D03*
X697100Y90600D03*
X670795Y89189D03*
X716894Y84047D03*
X701500Y85500D03*
X694600Y85000D03*
X698300Y85300D03*
X709560Y84648D03*
X689500Y37900D03*
X685000Y46650D03*
X670503Y115884D03*
X670600Y144900D03*
Y150000D03*
X706500Y207800D03*
X706561Y211417D03*
X705292Y195729D03*
X701956Y195294D03*
X701129Y192106D03*
X709341Y190507D03*
X725725Y241560D03*
X697255Y267098D03*
X710500Y224500D03*
X700400Y257200D03*
X710272Y281911D03*
X706800Y281900D03*
X704500Y252500D03*
X700800Y261300D03*
X690130Y277380D03*
X715200Y258900D03*
X704090Y256080D03*
X689960Y260500D03*
X700000Y233700D03*
X710900Y231660D03*
X677800Y254100D03*
X667700Y275600D03*
X710700Y260200D03*
X710675Y263425D03*
X679300Y261700D03*
X712400Y324400D03*
X711900Y327700D03*
X697120Y305349D03*
Y300349D03*
X704404Y315875D03*
Y310875D03*
X697521Y325500D03*
Y320500D03*
X724000Y291700D03*
X686140Y298260D03*
X695000Y289500D03*
X686600Y335600D03*
X670800Y292600D03*
X667900Y339000D03*
X697352Y335500D03*
Y330500D03*
X705800Y301600D03*
X674700Y339200D03*
X688100Y308600D03*
X688924Y288147D03*
X674469Y287375D03*
X674194Y358467D03*
X683417Y364972D03*
X686619Y392600D03*
X683100Y392200D03*
X691240Y390039D03*
X687427Y384926D03*
X676900Y381800D03*
X669194Y351206D03*
X674194D03*
X679194D03*
X684194D03*
X695700Y346300D03*
X680370Y427770D03*
X680200Y432100D03*
X687400Y411200D03*
X674300Y489500D03*
X679700Y489400D03*
X718546Y500283D03*
X696000Y496800D03*
X669300Y504000D03*
X708500Y512500D03*
X680000Y511800D03*
X686200Y511700D03*
X700500Y512850D03*
X690500Y523300D03*
X675500Y521900D03*
X721894Y501346D03*
X726040Y506080D03*
X696600Y581400D03*
X722200Y571300D03*
X718200Y581000D03*
X680029Y577503D03*
X680910Y582000D03*
X693200Y575900D03*
X717612Y598554D03*
X722406Y598950D03*
X756176Y-4300D03*
X782567Y33700D03*
X779921Y27899D03*
X776188Y33700D03*
X773228Y27899D03*
X782567Y-4100D03*
X779921Y17157D03*
X782567Y12114D03*
X779921Y-9901D03*
X776188Y-4100D03*
X773228Y17157D03*
X776274Y12114D03*
X773228Y-9901D03*
X729500Y23500D03*
X764100Y17100D03*
X760100Y17255D03*
X769881Y9157D03*
X763500Y23940D03*
X765900Y35800D03*
X765400Y-9800D03*
X766300Y-1800D03*
X729600Y17991D03*
X734256D03*
X755000Y17255D03*
X753100Y92111D03*
X782567Y71500D03*
X779921Y92757D03*
Y65699D03*
X782567Y87714D03*
X776188Y71500D03*
X773228Y92757D03*
Y65699D03*
X776274Y87714D03*
X779921Y54957D03*
X782567Y49914D03*
X773228Y54957D03*
X776274Y49914D03*
X764100Y55100D03*
X751600Y41000D03*
X755500Y55200D03*
X769881Y46957D03*
X763500Y59700D03*
X766500Y102900D03*
X752900Y101000D03*
X769044Y191348D03*
X770300Y204930D03*
X771232Y214033D03*
X749126Y220843D03*
X761580Y220160D03*
X748700Y257500D03*
X771650Y246451D03*
Y278451D03*
X759700Y232000D03*
X739400Y253400D03*
X739500Y247500D03*
X731662Y247716D03*
X775200Y230500D03*
X775171Y227116D03*
Y234316D03*
X775271Y262716D03*
X775171Y259116D03*
X730000Y254675D03*
X737750Y298894D03*
X771600Y310600D03*
X771700Y342501D03*
X729405Y290725D03*
X737912Y315500D03*
X741512Y315538D03*
X736000Y303400D03*
X775271Y294716D03*
X775171Y291116D03*
X775271Y326716D03*
X775171Y323116D03*
X757956Y328095D03*
X741250Y298856D03*
X743600Y304100D03*
X771400Y374400D03*
X760500Y359800D03*
X775271Y358716D03*
X775171Y355116D03*
X775221Y390716D03*
X775121Y387116D03*
X765007Y348363D03*
X732000Y380000D03*
X739933Y447401D03*
X756000Y525950D03*
X779921Y518157D03*
Y528899D03*
X782567Y513114D03*
X773228Y518157D03*
Y528899D03*
X776274Y513114D03*
X743483Y492937D03*
X764400Y528600D03*
X738648Y492050D03*
X763544Y522236D03*
X769500Y510100D03*
X766535Y517900D03*
X763706Y514250D03*
X782567Y534700D03*
X776188D03*
X779921Y555957D03*
X782567Y572500D03*
Y550914D03*
X779921Y566699D03*
X773228Y555957D03*
X776188Y572500D03*
X776274Y550914D03*
X773228Y566699D03*
X782567Y588714D03*
X776274D03*
X763300Y566000D03*
X769500Y536983D03*
X755000Y566000D03*
X769500Y547900D03*
Y574700D03*
Y585700D03*
X764117Y575658D03*
X765100Y537110D03*
X766535Y555700D03*
X732600Y573950D03*
X763450Y585200D03*
X765900Y587300D03*
X782567Y610300D03*
X779921Y593757D03*
Y604499D03*
X776188Y610300D03*
X773228Y593757D03*
Y604499D03*
X764400Y604600D03*
X739307Y598850D03*
X755800Y604600D03*
X769500Y612583D03*
X766535Y593500D03*
X733032Y604000D03*
X843503Y34100D03*
X840157Y27899D03*
X812999Y33700D03*
X810039Y27899D03*
X836810Y34100D03*
X833464Y27899D03*
X849810Y33700D03*
X846850Y27899D03*
X806692Y34100D03*
X803346Y27899D03*
X799999Y34100D03*
X796653Y27899D03*
X819378Y33700D03*
X816732Y27899D03*
X843503Y-3700D03*
X840157Y17157D03*
Y-9901D03*
X843503Y12114D03*
X812999Y-4100D03*
X810039Y17157D03*
Y-9901D03*
X813085Y12114D03*
X833464Y17157D03*
X836810Y-3700D03*
X833464Y-9901D03*
X836810Y12114D03*
X849810Y-4100D03*
X846850Y17157D03*
Y-9901D03*
X849896Y12114D03*
X806692Y-3700D03*
X803346Y17157D03*
Y-9901D03*
X806692Y12114D03*
X799999Y-3700D03*
X796653Y17157D03*
Y-9901D03*
X799999Y12114D03*
X816732Y17157D03*
X819378Y-4100D03*
Y12114D03*
X816732Y-9901D03*
X843503Y71900D03*
X840157Y92757D03*
Y65699D03*
X843503Y87714D03*
X812999Y71500D03*
X810039Y92757D03*
Y65699D03*
X813085Y87714D03*
X836810Y71900D03*
X833464Y92757D03*
Y65699D03*
X836810Y87714D03*
X849810Y71500D03*
X846850Y92757D03*
Y65699D03*
X849896Y87714D03*
X806692Y71900D03*
X803346Y92757D03*
Y65699D03*
X806692Y87714D03*
X799999Y71900D03*
X796653Y92757D03*
Y65699D03*
X799999Y87714D03*
X816732Y92757D03*
X819378Y71500D03*
X816732Y65699D03*
X819378Y87714D03*
X840157Y54957D03*
X843503Y49914D03*
X810039Y54957D03*
X813085Y49914D03*
X833464Y54957D03*
X836810Y49914D03*
X846850Y54957D03*
X849896Y49914D03*
X803346Y54957D03*
X806692Y49914D03*
X796653Y54957D03*
X799999Y49914D03*
X816732Y54957D03*
X819378Y49914D03*
X798337Y181216D03*
X799300Y195600D03*
X813700D03*
Y198900D03*
X799620Y186547D03*
X804470Y186814D03*
X824000Y402863D03*
X797000Y404700D03*
X851430Y367468D03*
X805600Y403900D03*
X840871Y391380D03*
X837272Y391420D03*
X827800Y402863D03*
X832300D03*
X805367Y407400D03*
X797780Y423484D03*
X840157Y518157D03*
Y528899D03*
X843503Y513114D03*
X810039Y518157D03*
X813085Y513114D03*
X810039Y528899D03*
X833464Y518157D03*
Y528899D03*
X836810Y513114D03*
X846850Y518157D03*
X849896Y513114D03*
X846850Y528899D03*
X803346Y518157D03*
X806692Y513114D03*
X803346Y528899D03*
X796653Y518157D03*
X799999Y513114D03*
X796653Y528899D03*
X816732Y518157D03*
Y528899D03*
X819378Y513114D03*
X843503Y535100D03*
X812999Y534700D03*
X836810Y535100D03*
X849810Y534700D03*
X806692Y535100D03*
X799999D03*
X819378Y534700D03*
X840157Y555957D03*
X843503Y572900D03*
Y550914D03*
X840157Y566699D03*
X810039Y555957D03*
X812999Y572500D03*
X813085Y550914D03*
X810039Y566699D03*
X833464Y555957D03*
X836810Y572900D03*
Y550914D03*
X833464Y566699D03*
X846850Y555957D03*
X849810Y572500D03*
X849896Y550914D03*
X846850Y566699D03*
X803346Y555957D03*
X806692Y572900D03*
Y550914D03*
X803346Y566699D03*
X796653Y555957D03*
X799999Y572900D03*
Y550914D03*
X796653Y566699D03*
X816732Y555957D03*
X819378Y572500D03*
X816732Y566699D03*
X819378Y550914D03*
X843503Y588714D03*
X813085D03*
X836810D03*
X849896D03*
X806692D03*
X799999D03*
X819378D03*
X840157Y593757D03*
X843503Y610700D03*
X840157Y604499D03*
X812999Y610300D03*
X810039Y593757D03*
Y604499D03*
X833464Y593757D03*
X836810Y610700D03*
X833464Y604499D03*
X846850Y593757D03*
X849810Y610300D03*
X846850Y604499D03*
X806692Y610700D03*
X803346Y593757D03*
Y604499D03*
X799999Y610700D03*
X796653Y593757D03*
Y604499D03*
X816732Y593757D03*
X819378Y610300D03*
X816732Y604499D03*
X856189Y33700D03*
X853543Y27899D03*
X880314Y34100D03*
X876968Y27899D03*
X873621Y34100D03*
X870275Y27899D03*
X893000Y33700D03*
X890354Y27899D03*
X913779D03*
X886621Y33700D03*
X883661Y27899D03*
X910432Y34100D03*
X907086Y27899D03*
X856189Y-4100D03*
X853543Y17157D03*
Y-9901D03*
X856189Y12114D03*
X880314Y-3700D03*
X876968Y17157D03*
Y-9901D03*
X880314Y12114D03*
X873621Y-3700D03*
X870275Y17157D03*
Y-9901D03*
X873621Y12114D03*
X893000Y-4100D03*
X890354Y17157D03*
X893000Y12114D03*
X890354Y-9901D03*
X913779Y17157D03*
Y-9901D03*
X883661Y17157D03*
X886621Y-4100D03*
X886707Y12114D03*
X883661Y-9901D03*
X907086Y17157D03*
X910432Y-3700D03*
X907086Y-9901D03*
X910432Y12114D03*
X856189Y71500D03*
X853543Y92757D03*
Y65699D03*
X856189Y87714D03*
X876968Y92757D03*
X880314Y71900D03*
X876968Y65699D03*
X880314Y87714D03*
X873621Y71900D03*
X870275Y92761D03*
Y65699D03*
X873621Y87714D03*
X893000Y71500D03*
X890354Y92757D03*
X893000Y87714D03*
X890354Y65699D03*
X913779Y92757D03*
Y65699D03*
X886621Y71500D03*
X883661Y92757D03*
X886707Y87714D03*
X883661Y65699D03*
X910432Y71900D03*
X907086Y92757D03*
X910432Y87714D03*
X907086Y65699D03*
X853543Y54957D03*
X856189Y49914D03*
X876968Y54957D03*
X880314Y49914D03*
X870275Y54957D03*
X873621Y49914D03*
X890354Y54957D03*
X893000Y49914D03*
X913779Y54957D03*
X883661D03*
X886707Y49914D03*
X907086Y54957D03*
X910432Y49914D03*
X890354Y112327D03*
X893000Y106934D03*
X913779Y112327D03*
X883661D03*
X886707Y107284D03*
X907086Y112327D03*
X910432Y107284D03*
X913787Y257860D03*
X913700Y242260D03*
X913787Y261760D03*
Y246160D03*
Y273460D03*
Y335860D03*
Y331960D03*
X882008Y321100D03*
X913787Y351460D03*
Y347560D03*
X853543Y518157D03*
Y528899D03*
X856189Y513114D03*
X876968Y518157D03*
Y528899D03*
X880314Y513114D03*
X870275Y518161D03*
Y528899D03*
X873621Y513114D03*
X890354Y518157D03*
Y528899D03*
X893000Y513114D03*
X913779Y518157D03*
Y528899D03*
X883661Y518157D03*
Y528899D03*
X886707Y513114D03*
X907086Y518157D03*
Y528899D03*
X910432Y513114D03*
X889200Y495900D03*
X893000Y495694D03*
X913779Y498487D03*
X882900Y498500D03*
X886500Y490800D03*
X907086Y498487D03*
X910432Y493744D03*
X856189Y534700D03*
X880314Y535100D03*
X873621D03*
X893000Y534700D03*
X886621D03*
X910432Y535100D03*
X853543Y555957D03*
X856189Y572500D03*
Y550914D03*
X853543Y566699D03*
X876968Y555957D03*
X880314Y572900D03*
X876968Y566699D03*
X880314Y550914D03*
X870275Y555961D03*
X873621Y572900D03*
Y550914D03*
X870275Y566699D03*
X893000Y572500D03*
X890354Y555957D03*
X893000Y550914D03*
X890354Y566699D03*
X913779Y555957D03*
Y566699D03*
X886621Y572500D03*
X883661Y555957D03*
X886707Y550914D03*
X883661Y566699D03*
X910432Y572900D03*
X907086Y555957D03*
X910432Y550914D03*
X907086Y566699D03*
X856189Y588714D03*
X880314D03*
X873621D03*
X893000D03*
X886707D03*
X910432D03*
X853543Y593757D03*
X856189Y610300D03*
X853543Y604499D03*
X876968Y593757D03*
X880314Y610700D03*
X876968Y604499D03*
X870275Y593761D03*
X873621Y610700D03*
X870275Y604499D03*
X893000Y610300D03*
X890354Y593757D03*
Y604499D03*
X913779Y593757D03*
Y604499D03*
X886621Y610300D03*
X883661Y593757D03*
Y604499D03*
X907086Y593757D03*
X910432Y610700D03*
X907086Y604499D03*
X957765Y-7180D03*
X917125Y34100D03*
X929811Y33700D03*
X927165Y27899D03*
X953936Y34100D03*
X950590Y27899D03*
X923432Y33700D03*
X920472Y27899D03*
X947243Y34100D03*
X943897Y27899D03*
X970669Y-7108D03*
X974015Y-9901D03*
Y-4536D03*
X963976Y-7108D03*
X960629Y-4536D03*
X917125Y-3700D03*
Y12114D03*
X929811Y-4100D03*
X927165Y17157D03*
Y-9901D03*
X929811Y12114D03*
X953936Y-3700D03*
X950590Y17157D03*
Y-9901D03*
X953936Y12114D03*
X923432Y-4100D03*
X920472Y17157D03*
Y-9901D03*
X923518Y12114D03*
X947243Y-3700D03*
X943897Y17157D03*
Y-9901D03*
X947243Y12114D03*
X960629Y-9786D03*
X963976Y-1843D03*
X970669Y-1743D03*
X967322Y-9786D03*
X963976Y9114D03*
X970669D03*
X960629Y17057D03*
X967322D03*
Y-4536D03*
X917125Y71900D03*
Y87714D03*
X929811Y71500D03*
X927165Y92757D03*
Y65699D03*
X929811Y87714D03*
X953936Y71900D03*
X950590Y92757D03*
Y65699D03*
X953936Y87714D03*
X923432Y71500D03*
X920472Y92757D03*
Y65699D03*
X923518Y87714D03*
X947243Y71900D03*
X943897Y92757D03*
Y65699D03*
X947243Y87714D03*
X917125Y49914D03*
X927165Y54957D03*
X929811Y49914D03*
X950590Y54957D03*
X953936Y49914D03*
X920472Y54957D03*
X923518Y49914D03*
X943897Y54957D03*
X947243Y49914D03*
X917125Y107284D03*
X927165Y112327D03*
X929811Y106934D03*
X950590Y109700D03*
X953786Y107684D03*
X920472Y112327D03*
X923518Y107284D03*
X944497Y110927D03*
X947243Y105084D03*
X924227Y205210D03*
X920847Y207159D03*
X927607Y218860D03*
X930987Y216909D03*
X934367Y218860D03*
X947887Y214960D03*
X958026Y216909D03*
Y220809D03*
X944507Y216909D03*
Y220809D03*
X954647Y214960D03*
X951267Y213009D03*
X937747Y220809D03*
X951267Y216909D03*
Y220809D03*
X934367Y203260D03*
Y211060D03*
X944507Y205210D03*
Y209109D03*
X930987Y205210D03*
Y209109D03*
X941127Y203260D03*
Y211060D03*
X937747Y201309D03*
Y213009D03*
Y205210D03*
Y209109D03*
X917467D03*
X927607Y199360D03*
X924227Y201309D03*
X944507Y197409D03*
X924227Y209109D03*
X920847Y203260D03*
X930987Y228610D03*
X937747Y224709D03*
X920847Y257860D03*
X934367Y230559D03*
X937747Y228610D03*
X927607Y222760D03*
X947887D03*
X954647D03*
X920847Y242260D03*
Y261760D03*
Y246160D03*
Y250060D03*
X927607Y226660D03*
X951267Y224709D03*
X920847Y253960D03*
X917467Y248109D03*
X930987Y224709D03*
X934367Y222760D03*
X917467Y255909D03*
X974926Y238360D03*
Y246160D03*
X971546Y240309D03*
Y244209D03*
X930987Y267609D03*
X927607Y238360D03*
X930987Y236409D03*
X934367Y250060D03*
X937747Y248109D03*
X927607Y242260D03*
X934367Y238360D03*
X937747Y263709D03*
X927607Y257860D03*
X930987Y255909D03*
X934367Y269560D03*
X937747Y267609D03*
X927607Y261760D03*
X934367Y257860D03*
X930987Y248109D03*
X937747Y244209D03*
Y259809D03*
X927607Y246160D03*
X937747Y240309D03*
X927607Y265660D03*
X934367Y261760D03*
X930987Y244209D03*
X934367Y242260D03*
X930987Y263709D03*
X947887Y261760D03*
X944507Y232509D03*
X947887Y230559D03*
X951267Y244209D03*
X954647Y242260D03*
X944507Y236409D03*
X951267Y232509D03*
X961406Y230559D03*
X968166Y234460D03*
Y222760D03*
X971546Y224709D03*
X954647Y257860D03*
X961406Y234460D03*
X964786Y236409D03*
Y224709D03*
X971546Y228610D03*
X974926Y257860D03*
Y261760D03*
X944507Y252009D03*
X947887Y250060D03*
X951267Y263709D03*
X954647Y261760D03*
X944507Y255909D03*
X951267Y252009D03*
X947887Y242260D03*
X954647Y238360D03*
Y253960D03*
X944507Y240309D03*
X961406Y226660D03*
X964786Y263709D03*
X954647Y234460D03*
X971546Y232509D03*
X964786Y275409D03*
X944507Y259809D03*
X951267Y255909D03*
X947887Y238360D03*
X964786Y228610D03*
Y267609D03*
X951267Y236409D03*
X968166Y230559D03*
X964786Y271509D03*
X947887Y257860D03*
X961406Y265660D03*
Y273460D03*
X971546Y267609D03*
Y271509D03*
X958026Y267609D03*
Y271509D03*
X968166Y265660D03*
Y273460D03*
X937747Y279310D03*
X917000Y276000D03*
X920847Y277360D03*
X924227Y279310D03*
Y283209D03*
X927607Y281260D03*
X920847D03*
X916967Y279310D03*
X934367Y281260D03*
X930987Y279310D03*
Y283209D03*
X937747D03*
X944507D03*
Y279310D03*
X958026D03*
X954647Y281260D03*
X958026Y283209D03*
X951267Y279310D03*
Y283209D03*
X961406Y281260D03*
X941127D03*
X947887D03*
X917467Y271509D03*
X961406Y242260D03*
X964786Y244209D03*
X961406Y246160D03*
X964786Y248109D03*
X958026D03*
X968166Y250060D03*
X971546Y252009D03*
X944507Y267609D03*
X947887Y269560D03*
X951267Y271509D03*
X947887Y273460D03*
X941127D03*
X927607D03*
X974926Y277360D03*
X971546Y279310D03*
X944507Y271509D03*
X924227D03*
X920847Y335860D03*
Y331960D03*
Y343660D03*
Y339760D03*
X917467Y345609D03*
Y337809D03*
X937747Y333909D03*
X930987Y330009D03*
Y341709D03*
X927607Y339760D03*
X937747Y330009D03*
X934367Y328060D03*
Y339760D03*
X927607Y335860D03*
Y331960D03*
X934367Y335860D03*
X930987Y333909D03*
X937747Y337809D03*
X954647Y339760D03*
X947887Y335860D03*
X954647D03*
X951267Y333909D03*
X944507Y341709D03*
Y337809D03*
X968166Y328060D03*
Y335860D03*
X951267Y341709D03*
X947887Y339760D03*
X968166Y324160D03*
Y331960D03*
X954647Y343660D03*
X964786Y326110D03*
Y333909D03*
X974926Y328060D03*
Y331960D03*
X961406Y328060D03*
Y331960D03*
X971546Y326110D03*
Y333909D03*
X937747Y287109D03*
X920500Y304660D03*
Y300760D03*
X930987Y302709D03*
X924227D03*
X920500Y311960D03*
X927607Y304660D03*
X924227Y306609D03*
X930987D03*
Y310509D03*
X934367Y304660D03*
X924227Y310509D03*
X920500Y308560D03*
Y289060D03*
X934367Y296860D03*
X930987Y294909D03*
X920500Y296860D03*
Y292959D03*
X927607Y296860D03*
X924227Y298809D03*
X930987D03*
X920500Y285500D03*
X924227Y287109D03*
X930987D03*
X934367Y289060D03*
X924227Y291009D03*
X930987D03*
X927607Y289060D03*
X937747Y302709D03*
Y306609D03*
Y310509D03*
Y291009D03*
Y294909D03*
Y298809D03*
Y314409D03*
X924227D03*
X930987D03*
X934367Y312460D03*
X927607D03*
X920847Y324160D03*
X924227Y318309D03*
X920547Y316160D03*
X917167Y318309D03*
Y322209D03*
X917467Y326110D03*
X920847Y320260D03*
X971546Y294909D03*
X964786Y291009D03*
X951267Y287109D03*
X958026D03*
X961406Y296860D03*
X964786Y298809D03*
Y302709D03*
X971546D03*
X961406Y304660D03*
X958026Y302709D03*
X951267D03*
X968166Y308560D03*
X964786Y306609D03*
X968166Y304660D03*
X971546Y306609D03*
X974926Y304660D03*
Y308560D03*
X951267Y310509D03*
X954647Y304660D03*
X958026Y306609D03*
Y310509D03*
X951267Y306609D03*
X944507Y302709D03*
Y306609D03*
Y310509D03*
X941127Y304660D03*
X947887D03*
X944507Y294909D03*
Y287109D03*
X971546Y298809D03*
X974926Y285160D03*
Y296860D03*
Y289060D03*
X968166Y285160D03*
X964786Y287109D03*
X944507Y291009D03*
X941127Y289060D03*
Y296860D03*
X944507Y298809D03*
X947887Y289060D03*
Y296860D03*
X968166D03*
X964786Y294909D03*
X971546Y291009D03*
Y287109D03*
X968166Y289060D03*
X961406D03*
X958026Y298809D03*
X951267D03*
Y291009D03*
X958026D03*
X954647Y289060D03*
Y296860D03*
X958026Y294909D03*
X951267D03*
X944507Y314409D03*
X951267D03*
X958026D03*
X961406Y312460D03*
X954647D03*
X941127D03*
X947887D03*
X951267Y326110D03*
X958026Y322209D03*
X954647Y320260D03*
X961406D03*
X954647Y324160D03*
X951267Y322209D03*
X964786Y318309D03*
X971546D03*
X974926Y320260D03*
X968166Y316360D03*
X974926D03*
X971546Y314409D03*
X947887Y320260D03*
X941127D03*
X934367D03*
X927607Y324160D03*
X944507Y326110D03*
Y330009D03*
X971546Y341709D03*
Y345609D03*
X937747Y372909D03*
X930987Y369010D03*
Y380709D03*
X927607Y378760D03*
X937747Y369010D03*
X934367Y367060D03*
Y378760D03*
X927607Y374860D03*
X947887D03*
Y382660D03*
X958026Y376809D03*
Y380709D03*
X944507Y376809D03*
Y380709D03*
X954647Y374860D03*
Y382660D03*
X920847Y351460D03*
Y347560D03*
X934367Y374860D03*
X951267Y376809D03*
X927607Y370959D03*
X951267Y384609D03*
X937747Y376809D03*
X951267Y372909D03*
X930987D03*
X951267Y380709D03*
X974926Y351460D03*
Y359260D03*
X971546Y353409D03*
Y357309D03*
X934367Y359260D03*
X930987Y361209D03*
X937747Y349509D03*
X934367Y347560D03*
X927607Y355360D03*
Y359260D03*
X934367Y386560D03*
Y394359D03*
X944507Y388509D03*
Y392410D03*
X930987Y388509D03*
Y392410D03*
X941127Y386560D03*
Y394359D03*
X937747Y353409D03*
X930987Y349509D03*
X934367Y355360D03*
X937747Y388509D03*
X927607Y351460D03*
X937747Y396309D03*
Y357309D03*
Y384609D03*
X930987Y353409D03*
X937747Y392410D03*
X951267Y365109D03*
X947887Y367060D03*
X954647Y355360D03*
X951267Y353409D03*
X944507Y361209D03*
Y365109D03*
X968166Y363160D03*
X961406Y367060D03*
X971546Y372909D03*
X968166Y374860D03*
X964786Y361209D03*
X961406Y363160D03*
X971546Y369010D03*
X964786Y372909D03*
X947887Y347560D03*
X944507Y345609D03*
X951267D03*
X954647Y359260D03*
X947887Y355360D03*
X951267Y361209D03*
X968166Y367060D03*
X944507Y357309D03*
X961406Y370959D03*
X954647Y363160D03*
X971546Y365109D03*
X947887Y359260D03*
X964786Y369010D03*
Y349509D03*
Y353409D03*
X961406Y355360D03*
Y347560D03*
Y351460D03*
X924227Y400209D03*
X930987D03*
X920847Y394359D03*
X917467Y392410D03*
X944507Y400209D03*
X964786Y384609D03*
Y380709D03*
X920847Y398260D03*
X927607D03*
X958026Y349509D03*
X924227Y396309D03*
X917125Y513114D03*
X927165Y518157D03*
Y528899D03*
X929811Y513114D03*
X950590Y518157D03*
Y528899D03*
X953936Y513114D03*
X920472Y518157D03*
Y528899D03*
X923518Y513114D03*
X943897Y518157D03*
Y528899D03*
X947243Y513114D03*
X917192Y493919D03*
X927165Y498644D03*
X929811Y493244D03*
X950700Y493300D03*
X954000Y494700D03*
X920700Y498644D03*
X923600Y493744D03*
X944000Y493100D03*
X947443Y494944D03*
X917125Y535100D03*
X929811Y534700D03*
X953936Y535100D03*
X923432Y534700D03*
X947243Y535100D03*
X917125Y572900D03*
Y550914D03*
X929811Y572500D03*
X927165Y555957D03*
Y566699D03*
X929811Y550914D03*
X953936Y572900D03*
X950590Y555957D03*
X953936Y550914D03*
X950590Y566699D03*
X923432Y572500D03*
X920472Y555957D03*
Y566699D03*
X923518Y550914D03*
X947243Y572900D03*
X943897Y555957D03*
X947243Y550914D03*
X943897Y566699D03*
X917125Y588714D03*
X929811D03*
X953936D03*
X923518D03*
X947243D03*
X970669Y585714D03*
X963976D03*
X957765Y607220D03*
X970669Y607292D03*
X974015Y604499D03*
Y609864D03*
X963976Y607292D03*
X960629Y609864D03*
X917125Y610700D03*
X929811Y610300D03*
X927165Y593757D03*
Y604499D03*
X953936Y610700D03*
X950590Y593757D03*
Y604499D03*
X923432Y610300D03*
X920472Y593757D03*
Y604499D03*
X947243Y610700D03*
X943897Y593757D03*
Y604499D03*
X967322Y593657D03*
X963976Y612457D03*
X970669D03*
X960629Y604614D03*
X967322D03*
X960629Y593657D03*
X967322Y609864D03*
X1026700Y1700D03*
X977362Y-1743D03*
X1014173Y-9786D03*
Y-1858D03*
Y9114D03*
X1010826Y-9786D03*
Y-1858D03*
Y9114D03*
X984055Y-1743D03*
X980708Y-9786D03*
X1004134Y-7108D03*
X1004133Y-1742D03*
X1000787Y-9901D03*
X997441Y-1743D03*
X994094Y-4536D03*
Y-9786D03*
X987401Y-4536D03*
X990748Y-7108D03*
X984055D03*
X980708Y-4536D03*
X987401Y-9901D03*
X997441Y-7108D03*
X990748Y-1743D03*
X977362Y-7108D03*
X980708Y9114D03*
X990748Y9122D03*
X987401Y17057D03*
X977362D03*
X997441D03*
X1000787Y-4536D03*
Y9122D03*
X1017519Y-1858D03*
Y-9786D03*
X1007480Y-1858D03*
X1007280Y9114D03*
X1017519D03*
X1007480Y-9786D03*
Y17014D03*
X1025670Y6640D03*
X1020866Y-1858D03*
X1027202Y-11005D03*
X1028639Y-6615D03*
X988446Y250060D03*
X978306Y236409D03*
Y248109D03*
Y240309D03*
Y244209D03*
X985066Y240309D03*
Y244209D03*
X981686Y238360D03*
Y246160D03*
X978306Y255909D03*
Y263709D03*
X988446Y257860D03*
Y261760D03*
X985066Y255909D03*
Y263709D03*
X981686Y253960D03*
Y265660D03*
Y257860D03*
Y261760D03*
X995206Y277360D03*
Y281260D03*
X998586Y267609D03*
Y271509D03*
Y275409D03*
Y279310D03*
Y283209D03*
X1022245Y253960D03*
X1017735Y264300D03*
X1014355Y266300D03*
X1021115Y262300D03*
X1024495Y260300D03*
X1027875Y258400D03*
X1031255Y256400D03*
X1005345Y263709D03*
X1001965Y265660D03*
X1008725Y261760D03*
X1006665Y277360D03*
Y281260D03*
X1015485Y257860D03*
X1018865Y255909D03*
X1012105Y259809D03*
X978306Y224709D03*
Y228610D03*
X981686Y230559D03*
X1008725Y250060D03*
X1001965D03*
X995206D03*
X1005345Y252009D03*
X998586D03*
X1008725Y253960D03*
X1001965D03*
X995206D03*
X1005345Y255909D03*
X998586D03*
X1001965Y257860D03*
X995206D03*
X998586Y259809D03*
X995206Y261760D03*
X988446Y269560D03*
X985066Y271509D03*
X978306D03*
X988446Y273460D03*
X981686D03*
X985066Y275409D03*
X978306D03*
X988446Y277360D03*
X981686D03*
X985066Y279310D03*
X978306D03*
X1015485Y250060D03*
X1012105Y252009D03*
X991826D03*
X998586Y337809D03*
X981686Y335860D03*
Y343660D03*
X991826Y337809D03*
Y341709D03*
X978306Y337809D03*
Y341709D03*
X988446Y335860D03*
Y343660D03*
X985066Y337809D03*
Y333909D03*
Y341709D03*
X995206Y296860D03*
X985066Y294909D03*
Y287109D03*
X988446Y285160D03*
X991826Y287109D03*
X978306Y298809D03*
Y287109D03*
X981686Y285160D03*
X978306Y294909D03*
X981686Y296860D03*
Y289060D03*
X978306Y291009D03*
X998586Y302709D03*
Y306609D03*
Y310509D03*
Y287109D03*
Y294909D03*
Y291009D03*
Y298809D03*
X985066Y302709D03*
X978306D03*
X988446Y304660D03*
Y308560D03*
X985066Y306609D03*
X995206Y304660D03*
Y308560D03*
X991826Y306609D03*
X978306D03*
X981686Y308560D03*
Y304660D03*
X995206Y300760D03*
X991826Y302709D03*
X995206Y292959D03*
X988446Y296860D03*
X991826Y294909D03*
X995206Y289060D03*
X988446D03*
X991826Y291009D03*
X985066D03*
X995206Y285160D03*
X985066Y298809D03*
X991826D03*
X998586Y314409D03*
X995206Y312460D03*
X998586Y318309D03*
Y322209D03*
Y326110D03*
Y330009D03*
X995206Y316360D03*
X1006665Y300760D03*
Y304660D03*
Y308560D03*
Y285160D03*
Y296860D03*
Y289060D03*
Y292959D03*
X1008725Y335860D03*
X1005345Y333909D03*
X1001965Y331960D03*
X1007595Y327609D03*
X1021115Y335409D03*
X1018865Y341709D03*
X1017735Y333460D03*
X1015485Y339760D03*
X1024495Y337360D03*
X1012105Y337809D03*
X1006665Y312460D03*
X1014355Y331509D03*
X1010975Y329560D03*
X1027875Y339309D03*
X1034635Y343209D03*
X1031255Y341260D03*
X1006665Y324160D03*
Y316360D03*
Y320260D03*
X1022245Y343660D03*
X981686Y324160D03*
X988446Y320260D03*
X985066Y322209D03*
Y318309D03*
X988446Y324160D03*
Y328060D03*
X981686D03*
X985066Y326110D03*
X981686Y320260D03*
X978306Y322209D03*
Y318309D03*
X981686Y316360D03*
X978306Y314409D03*
X985066D03*
X998586Y341709D03*
Y345609D03*
X1001965Y343660D03*
Y339760D03*
X1008725Y343660D03*
X1012105Y345609D03*
X1005345Y341709D03*
X978306Y353409D03*
Y361209D03*
Y349509D03*
Y357309D03*
X985066Y353409D03*
Y357309D03*
X981686Y351460D03*
Y359260D03*
X985066Y345609D03*
X1005345D03*
X1018865Y349509D03*
X1032385Y353409D03*
X1035765Y355360D03*
X978306Y372909D03*
Y369010D03*
X981686Y367060D03*
X1029005Y351460D03*
X991826Y349509D03*
X1012105D03*
X1025625D03*
X995206Y347560D03*
X1001965D03*
X1015485D03*
X1008725D03*
X990748Y585722D03*
X980708Y585714D03*
X1019277D03*
X1000787Y585722D03*
X1026500Y581000D03*
X977362Y612457D03*
X1014173Y604614D03*
X1010826D03*
X1011572Y593642D03*
X1010826Y612242D03*
X984055Y612457D03*
X980708Y604614D03*
X1004134Y607292D03*
X1004133Y612358D03*
X1000787Y604499D03*
X997441Y612357D03*
X994094Y609864D03*
Y604614D03*
X987401Y609864D03*
X990748Y607292D03*
X984055D03*
X977362Y593657D03*
X987401D03*
X997441D03*
Y607292D03*
X977362D03*
X990748Y612457D03*
X980708Y609864D03*
X987401Y604499D03*
X1007480Y612242D03*
X1000787Y609864D03*
X1007480Y604614D03*
X1029777Y613581D03*
X1020800Y612600D03*
X1071062Y-1817D03*
X1054330Y-9901D03*
X1050983Y-1743D03*
X1087795Y-4536D03*
X1064369Y-7108D03*
X1081102Y-9901D03*
X1094488Y-9786D03*
Y-4536D03*
X1047637Y-9901D03*
X1054330Y-4536D03*
X1077755Y-1743D03*
X1064369D03*
X1071062Y-7108D03*
X1057676D03*
X1084448Y-1743D03*
X1074409Y-9786D03*
X1087795D03*
X1044290Y11792D03*
X1044291Y-2200D03*
X1047637Y-4536D03*
X1057676Y-1743D03*
X1047637Y9107D03*
X1057677D03*
X1050983Y-7108D03*
X1050984Y17042D03*
X1061023Y-9786D03*
X1067716Y-4536D03*
Y-9901D03*
X1081102Y-4536D03*
X1074409D03*
X1084448Y-7108D03*
X1077755D03*
X1091141Y-1843D03*
X1067716Y9107D03*
X1091141D03*
X1074409D03*
X1081102D03*
X1061024Y17057D03*
X1067716Y17042D03*
X1091141D03*
X1084450Y17057D03*
X1077757D03*
X1097834Y11100D03*
X1061023Y-4536D03*
X1085721Y220096D03*
X1095861Y222047D03*
X1082341D03*
X1092481Y220096D03*
X1089101Y218147D03*
Y222047D03*
X1065242Y220096D03*
Y216196D03*
X1075582Y222047D03*
X1072202Y220096D03*
X1068822Y218147D03*
Y222047D03*
X1065242Y239596D03*
Y243496D03*
X1068822Y245447D03*
X1085721Y227896D03*
X1095861Y225947D03*
X1082341D03*
X1092481Y227896D03*
X1089101Y229847D03*
Y225947D03*
X1075582D03*
X1065242Y227896D03*
Y231797D03*
X1072202Y227896D03*
X1068822Y225947D03*
Y229847D03*
X1075582Y233746D03*
Y241547D03*
X1085721Y235696D03*
Y239596D03*
X1072202Y235696D03*
Y239596D03*
X1082341Y233746D03*
Y241547D03*
X1095861Y233746D03*
Y241547D03*
X1092481Y235696D03*
Y239596D03*
X1078962Y231797D03*
X1099241D03*
X1078962Y243496D03*
X1099241D03*
X1078962Y235696D03*
X1099241D03*
X1078962Y239596D03*
X1099241D03*
X1038015Y256500D03*
X1051534D03*
X1044774Y256400D03*
X1054914Y254500D03*
X1067692Y254000D03*
X1071072Y255728D03*
X1087971Y257800D03*
X1091351Y259600D03*
X1094731Y261500D03*
X1098111Y263400D03*
X1084591Y255497D03*
X1081212Y257600D03*
X1092481Y247396D03*
X1089101Y245447D03*
X1085721Y247396D03*
X1089101Y249347D03*
X1092481Y251296D03*
X1095861Y249347D03*
Y253247D03*
X1072202Y247396D03*
X1079859Y265000D03*
X1038015Y345160D03*
X1044774D03*
X1051534D03*
X1098111Y344597D03*
X1044256Y338341D03*
X1076435Y343595D03*
X1042524Y355360D03*
X1045904Y357309D03*
X1039145D03*
X1093601Y381947D03*
Y389747D03*
X1090221Y383896D03*
Y387796D03*
X1096981Y383896D03*
Y391696D03*
Y379996D03*
Y387796D03*
X1073322Y389747D03*
Y393647D03*
X1083462Y383896D03*
Y387796D03*
X1073322Y378047D03*
Y381947D03*
X1080082D03*
Y389747D03*
X1076702Y383896D03*
Y391696D03*
Y379996D03*
Y387796D03*
Y364396D03*
X1073322Y370247D03*
X1086841Y366347D03*
Y370247D03*
X1073322Y358547D03*
Y366347D03*
X1083462Y364396D03*
Y372197D03*
X1093601Y354647D03*
Y362447D03*
X1090221Y356596D03*
Y360496D03*
X1080082Y366347D03*
X1096981Y356596D03*
X1080082Y370247D03*
X1096981Y364396D03*
X1080082Y362447D03*
X1096981Y352696D03*
X1080082Y374146D03*
X1096981Y360496D03*
X1049284Y359260D03*
X1041395Y347109D03*
X1048154D03*
X1071072Y348497D03*
X1087971Y346546D03*
X1074452D03*
X1081212D03*
X1077832Y348497D03*
X1084591D03*
X1052664Y357309D03*
X1061039Y359351D03*
X1060694Y355360D03*
X1052664Y353409D03*
X1086841Y378047D03*
X1090221Y376096D03*
X1093601Y374146D03*
Y370247D03*
X1049284Y355360D03*
X1080082Y358547D03*
X1083462Y356596D03*
X1044290Y588392D03*
X1057677Y585707D03*
X1047637D03*
X1081102D03*
X1074409D03*
X1091141D03*
X1067716Y585599D03*
X1097343Y588394D03*
X1071062Y612560D03*
X1054330Y604499D03*
X1050984Y612658D03*
X1087795Y609864D03*
X1064369Y607292D03*
X1081102Y604499D03*
X1094488Y604614D03*
Y609864D03*
X1047637Y604499D03*
X1054330Y609864D03*
X1077755Y612657D03*
X1064369D03*
X1071062Y607292D03*
X1057676D03*
X1084448Y612657D03*
X1074409Y604614D03*
X1087795D03*
X1074409Y593642D03*
X1044291Y612658D03*
X1091141Y612557D03*
X1057676Y612657D03*
X1050984Y593642D03*
X1047637Y609864D03*
X1050983Y607292D03*
X1061024Y593657D03*
X1061023Y604614D03*
X1077757Y593657D03*
X1084450D03*
X1067716Y593642D03*
Y609864D03*
Y604499D03*
X1081102Y609864D03*
X1091141Y593642D03*
Y607292D03*
X1084448D03*
X1077755D03*
X1074409Y609864D03*
X1097374Y612659D03*
X1061023Y609864D03*
X1044290Y607292D03*
X1110520Y33700D03*
X1107874Y27899D03*
X1134645Y34100D03*
X1131299Y27899D03*
X1104141Y33700D03*
X1101181Y27899D03*
X1127952Y34100D03*
X1124606Y27899D03*
X1147331Y33700D03*
X1144685Y27899D03*
X1140952Y33700D03*
X1137992Y27899D03*
X1110520Y-4100D03*
X1107874Y17157D03*
Y-9901D03*
X1110520Y12114D03*
X1134645Y-3700D03*
X1131299Y17157D03*
Y-9901D03*
X1134645Y12114D03*
X1101181Y17157D03*
X1104141Y-4100D03*
X1104227Y12114D03*
X1101181Y-9901D03*
X1127952Y-3700D03*
X1124606Y17157D03*
Y-9901D03*
X1127952Y12114D03*
X1147331Y-4100D03*
X1144685Y17157D03*
Y-9901D03*
X1147331Y12114D03*
X1140952Y-4100D03*
X1137992Y17157D03*
Y-9901D03*
X1141038Y12114D03*
X1110520Y71500D03*
X1107874Y92757D03*
Y65699D03*
X1110520Y87714D03*
X1134645Y71900D03*
X1131299Y92757D03*
Y65699D03*
X1134645Y87714D03*
X1101181Y92757D03*
X1104141Y71500D03*
X1101181Y65699D03*
X1104227Y87714D03*
X1127952Y71900D03*
X1124606Y92757D03*
Y65699D03*
X1127952Y87714D03*
X1147331Y71500D03*
X1144685Y92757D03*
Y65699D03*
X1147331Y87714D03*
X1140952Y71500D03*
X1137992Y92757D03*
Y65699D03*
X1141038Y87714D03*
X1107874Y54957D03*
X1110520Y49914D03*
X1131299Y54957D03*
X1134645Y49914D03*
X1101181Y54957D03*
X1104227Y49564D03*
X1124606Y54957D03*
X1127952Y49914D03*
X1144685Y54957D03*
X1147331Y49914D03*
X1137992Y54957D03*
X1141038Y49914D03*
X1144535Y112357D03*
X1147331Y106964D03*
X1138242Y112357D03*
X1141038Y106964D03*
X1106001Y220096D03*
X1116141Y222047D03*
X1102621D03*
X1112761Y220096D03*
X1126280D03*
X1122900Y222047D03*
X1133040Y216196D03*
Y220096D03*
X1109381Y218147D03*
X1129660D03*
X1109381Y222047D03*
X1129660D03*
Y210346D03*
X1133040Y212296D03*
X1144300Y216196D03*
Y212296D03*
X1147680Y218147D03*
X1154440Y214247D03*
X1151060Y220096D03*
X1157820Y216196D03*
X1144300Y220096D03*
X1147680Y214247D03*
X1151060Y216196D03*
X1154440Y218147D03*
Y222047D03*
X1161200Y214247D03*
X1134160Y272747D03*
Y276646D03*
X1151060Y270796D03*
Y255196D03*
Y251296D03*
X1154440Y280547D03*
X1157820Y282496D03*
X1144300D03*
X1140920Y280547D03*
X1136420Y261047D03*
X1133040Y262996D03*
X1147680Y264947D03*
X1106001Y227896D03*
X1116141Y225947D03*
X1102621D03*
X1112761Y227896D03*
X1126280D03*
X1133040D03*
Y231797D03*
X1122900Y225947D03*
X1109381Y229847D03*
X1129660Y225947D03*
X1109381D03*
X1129660Y229847D03*
X1116141Y233746D03*
Y241547D03*
X1126280Y235696D03*
Y239596D03*
X1112761Y235696D03*
Y239596D03*
X1122900Y233746D03*
Y241547D03*
X1119521Y231797D03*
Y243496D03*
Y235696D03*
Y239596D03*
X1106001Y235696D03*
Y239596D03*
X1102621Y233746D03*
Y241547D03*
X1106001Y247396D03*
Y255196D03*
X1116141Y249347D03*
Y253247D03*
X1102621Y249347D03*
Y253247D03*
X1112761Y247396D03*
Y255196D03*
X1126280Y247396D03*
Y255196D03*
X1136420Y249347D03*
Y253247D03*
X1122900Y249347D03*
Y253247D03*
X1133040Y247396D03*
Y255196D03*
X1109381Y245447D03*
X1129660D03*
X1109381Y257147D03*
X1129660D03*
X1109381Y249347D03*
X1129660D03*
X1109381Y253247D03*
X1129660D03*
X1147680Y280547D03*
X1157820Y274696D03*
X1154440Y268847D03*
X1140920Y272747D03*
X1114340Y280560D03*
X1154440Y276647D03*
X1101491Y265400D03*
X1104871Y267300D03*
X1119521Y282496D03*
X1116141Y268847D03*
X1112761Y262996D03*
X1116141Y261047D03*
X1119521Y278596D03*
X1144300Y223996D03*
X1154440Y225947D03*
X1147680Y245447D03*
X1127400Y280547D03*
Y276646D03*
X1134160Y280547D03*
X1102336Y274819D03*
X1108125Y276799D03*
X1144300Y266896D03*
X1154440Y257147D03*
X1157820Y251296D03*
X1154440Y249347D03*
X1157820Y247396D03*
X1107600Y271900D03*
X1147680Y249347D03*
X1157820Y266896D03*
X1147680Y276647D03*
X1140920D03*
X1161200Y276646D03*
X1154440Y272747D03*
X1147680Y253247D03*
Y257147D03*
X1109381Y264947D03*
X1151060Y243496D03*
X1144300Y239596D03*
X1151060Y235696D03*
X1144300Y227896D03*
X1154440Y233746D03*
X1147680Y229847D03*
X1154440Y237647D03*
X1157820Y227896D03*
X1147680Y241547D03*
Y237647D03*
X1151060Y239596D03*
X1144300Y231797D03*
X1151060D03*
Y227896D03*
X1157820Y235696D03*
X1161200Y237647D03*
Y280547D03*
X1130780Y282496D03*
X1119521Y266896D03*
Y262996D03*
X1122900Y261047D03*
X1119521Y259096D03*
X1157820Y243496D03*
X1147680Y272747D03*
X1151060Y278596D03*
X1133040Y239596D03*
X1137540Y266896D03*
X1147680Y268847D03*
X1137540Y270796D03*
X1140920Y268847D03*
Y264947D03*
X1144300Y262996D03*
X1126280Y266896D03*
X1129660Y264947D03*
X1122900D03*
Y268847D03*
X1126280Y262996D03*
X1154440Y264947D03*
X1147680Y261047D03*
X1144300Y259096D03*
X1151060Y262996D03*
X1154440Y261047D03*
X1144300Y274696D03*
X1124021Y344896D03*
X1130780Y321496D03*
X1137540Y313696D03*
X1130780Y325396D03*
X1140920Y315647D03*
X1134160Y319547D03*
X1130780Y317596D03*
Y333196D03*
X1134160Y331247D03*
X1151060Y337096D03*
X1140920Y288347D03*
Y284447D03*
X1147680D03*
Y288347D03*
X1151060Y286396D03*
X1144300Y290296D03*
X1147680Y292247D03*
X1154440D03*
Y288347D03*
Y284447D03*
X1157820Y286396D03*
X1114839Y320075D03*
X1113132Y291702D03*
X1113500Y323400D03*
X1137540Y286396D03*
X1101491Y342646D03*
X1119521Y301996D03*
Y298096D03*
Y294196D03*
Y290296D03*
X1118391Y332897D03*
X1127400Y284447D03*
Y300047D03*
X1130780Y294196D03*
X1127400Y296147D03*
Y292247D03*
X1130780Y298096D03*
Y305896D03*
X1137540Y290296D03*
X1134160Y296147D03*
Y288347D03*
X1124021Y325396D03*
X1127400Y323446D03*
X1124021Y329296D03*
Y333196D03*
X1154440Y327347D03*
X1147680Y339047D03*
X1157820Y321496D03*
X1134160Y284447D03*
X1157820Y309797D03*
X1120641Y339047D03*
X1113881Y342947D03*
X1130780Y329296D03*
Y286396D03*
X1134160Y311747D03*
Y315647D03*
X1161200Y288347D03*
Y292247D03*
X1140920Y323446D03*
X1147680Y307847D03*
X1151060Y309797D03*
Y305896D03*
X1144300Y301996D03*
Y298096D03*
X1137540Y301996D03*
X1134160Y303947D03*
X1137540Y298096D03*
X1140920Y303947D03*
X1137540Y305896D03*
X1140920Y296147D03*
X1137540Y294196D03*
X1120641Y342947D03*
X1140920D03*
X1110501Y344896D03*
X1119521Y309797D03*
Y313696D03*
Y317596D03*
X1127400Y311747D03*
X1154440D03*
X1157820Y305896D03*
X1154440Y303947D03*
X1157820Y301996D03*
X1154440Y300047D03*
X1134160Y307847D03*
X1151060Y294196D03*
X1147680Y300047D03*
Y296147D03*
X1140920Y307847D03*
Y311747D03*
X1151060Y301996D03*
X1144300Y305896D03*
X1147680Y311747D03*
X1157820Y298096D03*
X1154440Y296147D03*
X1134160Y335147D03*
Y339047D03*
X1140920Y319547D03*
X1144300Y313696D03*
X1151060D03*
X1144300Y325396D03*
Y321496D03*
X1151060Y329296D03*
X1147680Y335147D03*
Y331247D03*
X1140920Y335147D03*
X1144300Y333196D03*
X1151060Y325396D03*
Y321496D03*
X1147680Y323446D03*
X1137540Y329296D03*
X1144300D03*
X1140920Y327347D03*
X1130780Y340996D03*
Y337096D03*
X1127400Y331247D03*
Y335147D03*
Y339047D03*
X1147680Y315647D03*
X1151060Y317596D03*
X1137540Y337096D03*
Y340996D03*
Y333196D03*
X1134160Y342947D03*
X1137540Y344896D03*
X1144300Y317596D03*
X1137540Y321496D03*
X1134160Y327347D03*
X1137540Y325396D03*
X1109200Y325100D03*
X1127400Y346847D03*
X1130780Y348796D03*
X1127400Y350747D03*
X1103741Y383896D03*
Y387796D03*
X1100361Y381947D03*
Y389747D03*
X1113881Y381947D03*
Y389747D03*
X1124021Y383896D03*
Y387796D03*
X1110501Y383896D03*
Y387796D03*
X1120641Y381947D03*
Y389747D03*
X1134160Y381947D03*
Y389747D03*
X1144300Y395597D03*
Y399496D03*
X1130780Y383896D03*
Y387796D03*
X1140920Y401447D03*
Y393647D03*
X1117261Y379996D03*
X1137540D03*
X1117261Y391696D03*
X1137540D03*
X1117261Y383896D03*
X1137540D03*
X1117261Y387796D03*
X1137540D03*
X1124021Y368296D03*
Y376096D03*
X1130780Y364396D03*
X1134160Y374146D03*
X1120641Y370247D03*
Y374146D03*
X1130780Y368296D03*
Y376096D03*
X1127400Y370247D03*
Y378047D03*
Y366347D03*
Y374146D03*
X1103741Y368296D03*
Y376096D03*
X1113881Y370247D03*
Y374146D03*
X1100361Y370247D03*
Y374146D03*
X1110501Y368296D03*
Y376096D03*
X1103741Y356596D03*
Y360496D03*
X1100361Y354647D03*
Y362447D03*
X1113881Y354647D03*
Y362447D03*
X1124021Y356596D03*
Y360496D03*
X1110501Y356596D03*
Y360496D03*
X1120641Y354647D03*
Y362447D03*
X1107121Y370247D03*
X1117261Y356596D03*
X1107121Y378047D03*
X1117261Y364396D03*
X1107121Y366347D03*
X1117261Y352696D03*
X1107121Y374146D03*
X1117261Y360496D03*
X1157820Y356596D03*
X1144300Y352696D03*
X1154440Y350747D03*
Y362447D03*
X1144300Y368296D03*
X1157820Y379996D03*
X1147680Y389747D03*
X1144300Y376096D03*
X1151060Y383896D03*
X1161200Y362447D03*
X1157820Y364396D03*
X1154440Y370246D03*
X1157820Y376096D03*
X1151060Y372196D03*
X1147680Y378047D03*
X1144300Y379996D03*
Y387796D03*
X1161200Y358547D03*
Y366347D03*
X1157820Y368296D03*
Y372196D03*
X1154440Y374146D03*
X1151060Y376096D03*
X1147680Y381947D03*
X1144300Y383896D03*
X1161200Y354647D03*
X1107121Y350747D03*
X1113881Y346847D03*
X1147680Y370247D03*
Y374146D03*
X1120641Y346847D03*
X1161200Y389747D03*
X1154440Y397546D03*
Y393647D03*
X1151060Y387796D03*
X1157820Y395597D03*
X1154440Y389747D03*
X1157820Y391696D03*
X1154440Y385847D03*
X1140920Y354647D03*
X1161201Y401447D03*
X1157820Y383896D03*
X1137540Y356596D03*
X1156699Y401447D03*
X1134160Y358547D03*
X1137540Y352696D03*
X1130780Y356596D03*
X1134160Y354647D03*
Y350747D03*
X1137540Y348796D03*
X1107874Y518157D03*
Y528899D03*
X1110520Y513114D03*
X1131299Y518157D03*
Y528899D03*
X1134645Y513114D03*
X1101181Y518157D03*
X1104227Y513114D03*
X1101181Y528899D03*
X1124606Y518157D03*
Y528899D03*
X1127952Y513114D03*
X1144685Y518157D03*
X1147331Y513114D03*
X1144685Y528899D03*
X1137992Y518157D03*
X1141038Y513114D03*
X1137992Y528899D03*
X1144385Y498487D03*
X1147331Y490894D03*
X1137992Y498487D03*
X1141038Y491144D03*
X1110520Y534700D03*
X1134645Y535100D03*
X1104141Y534700D03*
X1127952Y535100D03*
X1147331Y534700D03*
X1140952D03*
X1107874Y555957D03*
X1110520Y572500D03*
Y550914D03*
X1107874Y566699D03*
X1131299Y555957D03*
X1134645Y572900D03*
Y550914D03*
X1131299Y566699D03*
X1101181Y555957D03*
X1104141Y572500D03*
X1104227Y550914D03*
X1101181Y566699D03*
X1124606Y555957D03*
X1127952Y572900D03*
Y550914D03*
X1124606Y566699D03*
X1147331Y572500D03*
X1144685Y555957D03*
X1147331Y550914D03*
X1144685Y566699D03*
X1140952Y572500D03*
X1137992Y555957D03*
X1141038Y550914D03*
X1137992Y566699D03*
X1110520Y588714D03*
X1134645D03*
X1104227D03*
X1127952D03*
X1147331D03*
X1141038D03*
X1110520Y610300D03*
X1107874Y593757D03*
Y604499D03*
X1134645Y610700D03*
X1131299Y593757D03*
Y604499D03*
X1101181Y593757D03*
X1104141Y610300D03*
X1101181Y604499D03*
X1124606Y593757D03*
X1127952Y610700D03*
X1124606Y604499D03*
X1147700Y611200D03*
X1144685Y593757D03*
Y604499D03*
X1137992Y593757D03*
X1141332Y611668D03*
X1137992Y604499D03*
X1171456Y34100D03*
X1168110Y27899D03*
X1164763Y34100D03*
X1161417Y27899D03*
X1184142Y33700D03*
X1181496Y27899D03*
X1208267Y34100D03*
X1204921Y27899D03*
X1177763Y33700D03*
X1174803Y27899D03*
X1201574Y34100D03*
X1198228Y27899D03*
X1220953Y33700D03*
X1218307Y27899D03*
X1214574Y33700D03*
X1211614Y27899D03*
X1171456Y-3700D03*
X1168110Y17157D03*
Y-9901D03*
X1171456Y12114D03*
X1164763Y-3700D03*
X1161417Y17157D03*
Y-9901D03*
X1164763Y12114D03*
X1184142Y-4100D03*
X1181496Y17157D03*
X1184142Y12114D03*
X1181496Y-9901D03*
X1204921Y17157D03*
X1208267Y-3700D03*
X1204921Y-9901D03*
X1208267Y12114D03*
X1177763Y-4100D03*
X1174803Y17157D03*
Y-9901D03*
X1177849Y12114D03*
X1198228Y17157D03*
X1201574Y-3700D03*
Y12114D03*
X1198228Y-9901D03*
X1220953Y-4100D03*
X1218307Y17157D03*
Y-9901D03*
X1220953Y12114D03*
X1214574Y-4100D03*
X1211614Y17157D03*
Y-9901D03*
X1214660Y12114D03*
X1171456Y71900D03*
X1168110Y92757D03*
Y65699D03*
X1171456Y87714D03*
X1164763Y71900D03*
X1161417Y92757D03*
Y65699D03*
X1164763Y87714D03*
X1181496Y92757D03*
X1184142Y71500D03*
Y87714D03*
X1181496Y65699D03*
X1208267Y71900D03*
X1204921Y92757D03*
X1208267Y87714D03*
X1204921Y65699D03*
X1177763Y71500D03*
X1174803Y92757D03*
Y65699D03*
X1177849Y87714D03*
X1201574Y71900D03*
X1198228Y92757D03*
X1201574Y87714D03*
X1198228Y65699D03*
X1220953Y71500D03*
X1218307Y92757D03*
X1220953Y87714D03*
X1218307Y65699D03*
X1214574Y71500D03*
X1211614Y92757D03*
X1214874Y87374D03*
X1211614Y65699D03*
X1168110Y54957D03*
X1171456Y49914D03*
X1161417Y54957D03*
X1164763Y49914D03*
X1181496Y54957D03*
X1184142Y49914D03*
X1204921Y54957D03*
X1208267Y49914D03*
X1174803Y54957D03*
X1177849Y49914D03*
X1198228Y54957D03*
X1201574Y49914D03*
X1218307Y54957D03*
X1220953Y49914D03*
X1211614Y54957D03*
X1214660Y49914D03*
X1167925Y112357D03*
X1170721Y106964D03*
X1161632Y112357D03*
X1164428Y106964D03*
X1181496Y112357D03*
X1184142Y106964D03*
X1204921Y112357D03*
X1208267Y107314D03*
X1174742Y112357D03*
X1177849Y107314D03*
X1198228Y112357D03*
X1201574Y107314D03*
X1208519Y218147D03*
X1167960Y222047D03*
X1164580Y220096D03*
X1161200Y222047D03*
X1171339Y216196D03*
X1181479Y218147D03*
X1191619Y208397D03*
X1209033Y183907D03*
X1188239Y202247D03*
X1181479Y202547D03*
X1174719D03*
X1178099Y204496D03*
X1181479Y214247D03*
X1178099Y212296D03*
X1184859Y208397D03*
Y220096D03*
X1191619Y216196D03*
X1194999Y214247D03*
Y218147D03*
X1198379Y220096D03*
X1201759Y222047D03*
X1164580Y212296D03*
Y208397D03*
X1167960Y214247D03*
X1174719Y210346D03*
X1184859Y216196D03*
X1181479Y210346D03*
X1184859Y212296D03*
X1188239Y218147D03*
X1191619Y220096D03*
Y212296D03*
X1198379Y216196D03*
X1205139Y220096D03*
X1164580Y216196D03*
X1167960Y210346D03*
X1171339Y212296D03*
X1174719Y214247D03*
Y222047D03*
X1221767Y175858D03*
X1220580Y179810D03*
X1161200Y268847D03*
X1164580Y255196D03*
X1171339Y270796D03*
X1164580Y282496D03*
X1167960Y280547D03*
X1171339Y282496D03*
X1167960Y261047D03*
X1174719D03*
X1164580Y251296D03*
X1167960Y272747D03*
X1171339Y255196D03*
Y251296D03*
X1161200Y245447D03*
X1164580Y243496D03*
Y274696D03*
X1174719Y272747D03*
X1167960Y257147D03*
X1161200Y272747D03*
X1191619Y223996D03*
X1178099D03*
X1167960Y233746D03*
X1178099Y270796D03*
Y278596D03*
X1181479Y249347D03*
Y237647D03*
Y241547D03*
X1184859Y223996D03*
X1201759Y237647D03*
X1198379Y227896D03*
X1205139Y231797D03*
X1201759Y245447D03*
X1194999Y237647D03*
X1198379Y251296D03*
X1181479Y264947D03*
X1184859Y255196D03*
X1191619Y270796D03*
X1198379Y262996D03*
X1194999Y276646D03*
X1198379Y282496D03*
Y270796D03*
X1178099Y266896D03*
X1162300Y264947D03*
X1167960Y249347D03*
X1181479Y257147D03*
X1178099Y255196D03*
X1161200Y253247D03*
X1174719Y268847D03*
X1167960Y241547D03*
Y245447D03*
Y237647D03*
X1171339Y239596D03*
Y243496D03*
X1174719Y241547D03*
X1178099Y239596D03*
X1174719Y249347D03*
Y245447D03*
X1171339Y278596D03*
X1178099Y262996D03*
X1205139Y255196D03*
X1208519Y249347D03*
X1201759Y253247D03*
X1205139Y243496D03*
X1212199Y239596D03*
X1205139Y235696D03*
X1212199Y227896D03*
X1208519Y225947D03*
X1205139Y282496D03*
X1201759Y280547D03*
X1198379Y274696D03*
X1201759Y272747D03*
X1205139Y270796D03*
X1201759Y264947D03*
X1205139Y262996D03*
X1208519Y257147D03*
Y253247D03*
X1205139Y251296D03*
X1208519Y241547D03*
Y237647D03*
X1205139Y239596D03*
X1212199Y231797D03*
Y223996D03*
X1205139Y278596D03*
X1201759Y276646D03*
Y268847D03*
X1208519D03*
X1205139Y266896D03*
Y259096D03*
Y223996D03*
X1198379D03*
X1205139Y227896D03*
X1178099Y282496D03*
X1184859Y262996D03*
X1191619Y259096D03*
X1194999Y261047D03*
Y257147D03*
X1188239Y253247D03*
X1194999Y249347D03*
X1198379Y247396D03*
X1191619Y243496D03*
X1188239Y241547D03*
X1181479Y245447D03*
X1184859Y278596D03*
X1188239Y276646D03*
Y280547D03*
X1181479Y272747D03*
X1188239Y268847D03*
X1191619Y266896D03*
X1181479Y280547D03*
X1188239Y261047D03*
X1191619Y262996D03*
X1198379Y259096D03*
X1191619Y255196D03*
Y251296D03*
X1194999Y253247D03*
Y245447D03*
Y241547D03*
X1188239Y245447D03*
X1184859Y243496D03*
Y282496D03*
Y274696D03*
X1191619Y282496D03*
Y278596D03*
X1184859Y270796D03*
X1188239Y272747D03*
Y264947D03*
X1174719Y229847D03*
X1167960Y225947D03*
X1174719Y233746D03*
X1181479Y229847D03*
X1184859Y227896D03*
Y231797D03*
X1191619Y235696D03*
Y227896D03*
X1198379Y231797D03*
X1161200Y233746D03*
Y229847D03*
X1171339Y227896D03*
Y223996D03*
X1174719Y225947D03*
X1178099Y231797D03*
X1181479Y233746D03*
Y225947D03*
X1188239Y229847D03*
Y233746D03*
X1191619Y231797D03*
X1194999Y229847D03*
X1161200Y225947D03*
X1164580Y231797D03*
X1174719Y257147D03*
X1178099Y259096D03*
X1174719Y276646D03*
X1167960D03*
Y268847D03*
X1181479Y253247D03*
X1178099Y251296D03*
X1167960Y264947D03*
X1171339Y262996D03*
X1174719Y264947D03*
X1208519Y229847D03*
X1184859Y337096D03*
X1178099Y340996D03*
X1181479Y339047D03*
Y342947D03*
X1178099Y344896D03*
X1201759Y331247D03*
Y335147D03*
Y342947D03*
X1198379Y344896D03*
Y333196D03*
X1201759Y339047D03*
X1205139Y340996D03*
X1181479Y331247D03*
X1167960Y284447D03*
X1198379Y321496D03*
X1194999Y323446D03*
X1181479Y315647D03*
X1171339Y344896D03*
X1174719Y339047D03*
X1164580Y340996D03*
X1167960Y331247D03*
X1171339Y321496D03*
X1184859Y325396D03*
Y333196D03*
X1198379Y337096D03*
Y329296D03*
X1194999Y342947D03*
X1174719Y323446D03*
X1181479D03*
X1174719Y327347D03*
X1178099Y333196D03*
X1171339Y329296D03*
X1167960Y335147D03*
X1171339Y340996D03*
X1174719Y319547D03*
X1178099Y321496D03*
Y325396D03*
Y329296D03*
X1174719Y331247D03*
X1171339Y333196D03*
Y337096D03*
X1161200Y311747D03*
X1198379Y290296D03*
Y294196D03*
X1161200Y300047D03*
Y303947D03*
X1201759Y292247D03*
X1205439Y290296D03*
Y294196D03*
Y286596D03*
X1208819Y284447D03*
X1184859Y286396D03*
X1191619D03*
X1194999Y284447D03*
X1181479D03*
X1191619Y290296D03*
Y313696D03*
Y309797D03*
X1188239Y307847D03*
Y303947D03*
Y300047D03*
X1184859Y298096D03*
Y344896D03*
X1191619D03*
Y340996D03*
Y337096D03*
X1188239Y331247D03*
X1194999Y327347D03*
X1188239D03*
X1184859Y317596D03*
X1191619D03*
X1194999Y311747D03*
X1191619Y305896D03*
X1184859D03*
X1191619Y301996D03*
X1188239Y296147D03*
X1181479D03*
X1184859Y340996D03*
X1188239Y342947D03*
X1194999Y339047D03*
X1191619Y333196D03*
Y329296D03*
Y325396D03*
X1188239Y323446D03*
X1184859Y313696D03*
X1188239Y315647D03*
X1174719Y303947D03*
X1167960D03*
X1178099Y309797D03*
X1171339Y305896D03*
X1164580Y309797D03*
Y305896D03*
X1167960Y307847D03*
Y311747D03*
X1171339Y309797D03*
X1178099Y301996D03*
X1174719Y311747D03*
Y307847D03*
X1178099Y305896D03*
Y313696D03*
X1171339D03*
X1164580D03*
X1174719Y292247D03*
Y288347D03*
X1171339Y286396D03*
Y290296D03*
X1167960Y300047D03*
X1164580Y298096D03*
X1167960Y296147D03*
Y292247D03*
Y288347D03*
X1161200Y296147D03*
X1178099Y290296D03*
X1171339Y298096D03*
Y294196D03*
X1174719Y296147D03*
Y346847D03*
X1178099Y348796D03*
Y352696D03*
X1201759Y346847D03*
X1167960Y358547D03*
X1174719Y350747D03*
X1167960Y366347D03*
X1171339Y368296D03*
X1161200Y374146D03*
X1178099Y391696D03*
X1174719Y397546D03*
X1164580Y399496D03*
X1188239Y370247D03*
X1191619Y372197D03*
Y364396D03*
Y352696D03*
X1181479Y385847D03*
Y405347D03*
X1188239Y381947D03*
X1208819Y385847D03*
X1164580Y368296D03*
X1167960Y350747D03*
Y354647D03*
X1164580Y360496D03*
Y364396D03*
X1167960Y346847D03*
X1171339Y352696D03*
X1184859Y348796D03*
X1188239Y346847D03*
X1178099Y387796D03*
X1171339D03*
Y391696D03*
X1167960Y393647D03*
X1164580Y395597D03*
X1178099Y379996D03*
Y383896D03*
X1174719Y385847D03*
X1171339Y383896D03*
X1174719Y389747D03*
X1171339Y395596D03*
X1164580Y391696D03*
Y387796D03*
X1178099Y376096D03*
X1181479Y381947D03*
X1188239Y354647D03*
Y358547D03*
Y362447D03*
X1181479D03*
Y366347D03*
X1184859Y372197D03*
Y376096D03*
Y379996D03*
X1188239Y350747D03*
X1191619Y356596D03*
X1184859Y360496D03*
X1181479Y358547D03*
X1184859Y364396D03*
Y368296D03*
X1188239Y374146D03*
X1181479Y378047D03*
X1174719Y370247D03*
X1181479D03*
X1171339Y364396D03*
X1178099Y360496D03*
Y356596D03*
X1184859Y352696D03*
X1161200Y393647D03*
Y385847D03*
X1167960D03*
Y381947D03*
Y378047D03*
X1174719D03*
Y374146D03*
Y366347D03*
X1178099Y368296D03*
X1174719Y362447D03*
Y358547D03*
X1181479Y354647D03*
Y350747D03*
X1161200Y381947D03*
X1164580Y383896D03*
X1171339Y379996D03*
X1167960Y374146D03*
X1171339Y376096D03*
X1178099Y372197D03*
X1167960Y405347D03*
X1194999Y378047D03*
X1201759Y374146D03*
X1194999D03*
X1198379Y364396D03*
Y360496D03*
Y356596D03*
X1174719Y405347D03*
Y401447D03*
X1178099Y395596D03*
X1184859Y399496D03*
X1181479Y393647D03*
X1188239Y389747D03*
Y385847D03*
X1191619Y379996D03*
X1198379Y383896D03*
X1167960Y401447D03*
X1198379Y376096D03*
Y372197D03*
X1194999Y370247D03*
Y362447D03*
X1201759Y358547D03*
X1198379Y352696D03*
X1171339Y403396D03*
X1178099Y399496D03*
X1181479Y397546D03*
X1184859Y395596D03*
Y391696D03*
Y387796D03*
X1191619Y383896D03*
X1194999Y381947D03*
X1198379Y379996D03*
X1164580Y376096D03*
X1194999Y350747D03*
X1198379Y348796D03*
X1168110Y518157D03*
X1171456Y513114D03*
X1168110Y528899D03*
X1161417Y518157D03*
Y528899D03*
X1164763Y513114D03*
X1181496Y518157D03*
Y528899D03*
X1184142Y513114D03*
X1204921Y518157D03*
X1208267Y513114D03*
X1204921Y528899D03*
X1174803Y518157D03*
Y528899D03*
X1177849Y513114D03*
X1198228Y518157D03*
X1201574Y513114D03*
X1198228Y528899D03*
X1218307Y518157D03*
X1220953Y513114D03*
X1218307Y528899D03*
X1211614Y518157D03*
X1214874Y512774D03*
X1211614Y528899D03*
X1167510Y498487D03*
X1170656Y493844D03*
X1161417Y498487D03*
X1164363Y493744D03*
X1180400Y498387D03*
X1184142Y493394D03*
X1204400Y498487D03*
X1208267Y496144D03*
X1174203Y498387D03*
X1177799Y493544D03*
X1198100Y498400D03*
X1200974Y493344D03*
X1171456Y535100D03*
X1164763D03*
X1184142Y534700D03*
X1208267Y535100D03*
X1177763Y534700D03*
X1201574Y535100D03*
X1220953Y534700D03*
X1214574D03*
X1171456Y572900D03*
X1168110Y555957D03*
X1171456Y550914D03*
X1168110Y566699D03*
X1164763Y572900D03*
X1161417Y555957D03*
X1164763Y550914D03*
X1161417Y566699D03*
X1184142Y572500D03*
X1181496Y555957D03*
X1184142Y550914D03*
X1181496Y566699D03*
X1208267Y572900D03*
X1204921Y555957D03*
X1208267Y550914D03*
X1204921Y566699D03*
X1177763Y572500D03*
X1174803Y555957D03*
X1177849Y550914D03*
X1174803Y566699D03*
X1201574Y572900D03*
X1198228Y555957D03*
X1201574Y550914D03*
X1198228Y566699D03*
X1218307Y555957D03*
X1220953Y572500D03*
Y550914D03*
X1218307Y566699D03*
X1211614Y555957D03*
X1214574Y572500D03*
X1214874Y550574D03*
X1211614Y566699D03*
X1171456Y588714D03*
X1164763D03*
X1184142D03*
X1208267D03*
X1177849D03*
X1201574D03*
X1220953D03*
X1214660D03*
X1168110Y593757D03*
X1171456Y610700D03*
X1168110Y604499D03*
X1161417Y593757D03*
X1164763Y610700D03*
X1161417Y604499D03*
X1181496Y593757D03*
X1184142Y610300D03*
X1181496Y604499D03*
X1208267Y610700D03*
X1204921Y593757D03*
Y604499D03*
X1174803Y593757D03*
X1177763Y610300D03*
X1174803Y604499D03*
X1198228Y593757D03*
X1201574Y610700D03*
X1198228Y604499D03*
X1218307Y593757D03*
X1220953Y610300D03*
X1218307Y604499D03*
X1211614Y593757D03*
X1214574Y610300D03*
X1211614Y604499D03*
X1245078Y34100D03*
X1241732Y27899D03*
X1238385Y34100D03*
X1235039Y27899D03*
X1245078Y-3700D03*
X1241732Y17157D03*
Y-9901D03*
X1245078Y12114D03*
X1238385Y-3700D03*
X1235039Y17157D03*
Y-9901D03*
X1238385Y12114D03*
X1251771Y27899D03*
Y36057D03*
X1248425Y17057D03*
X1258464Y36057D03*
Y27899D03*
X1265157Y36057D03*
X1261811D03*
Y27899D03*
Y16999D03*
X1258464D03*
X1265157Y9157D03*
X1251771D03*
Y-1743D03*
X1261811Y-9901D03*
X1258464D03*
X1261811Y-1743D03*
X1265157D03*
X1258464D03*
X1255118Y-9901D03*
Y27899D03*
Y16999D03*
Y-1743D03*
Y36057D03*
Y9157D03*
X1265157Y27899D03*
Y-9901D03*
Y16999D03*
X1276346Y-10250D03*
X1245078Y71900D03*
X1241732Y92757D03*
X1245078Y87714D03*
X1241732Y65699D03*
X1238385Y71900D03*
X1235039Y92757D03*
X1238385Y87714D03*
X1235039Y65699D03*
X1241732Y54957D03*
X1245078Y49914D03*
X1235039Y54957D03*
X1238385Y49914D03*
X1251771Y54799D03*
X1248425Y54857D03*
X1251771Y46957D03*
X1258464D03*
Y54799D03*
X1261811Y46957D03*
Y54799D03*
Y65699D03*
X1258464D03*
X1251771Y84757D03*
X1248425Y92657D03*
X1265157Y73857D03*
X1261811D03*
X1258464D03*
X1261811Y84757D03*
X1258464D03*
X1265157D03*
X1251771Y73857D03*
X1261811Y92599D03*
X1258464D03*
X1255118Y65699D03*
Y54799D03*
Y92599D03*
Y46957D03*
Y84757D03*
Y73857D03*
X1265157Y65699D03*
Y92599D03*
Y54799D03*
X1270350Y98300D03*
X1268111Y58040D03*
X1251344Y127925D03*
X1259950Y144650D03*
X1277100Y122670D03*
X1272100Y141603D03*
X1264550Y114670D03*
X1277100Y114800D03*
X1261030Y105350D03*
X1277600Y106200D03*
X1248616Y133817D03*
X1237704Y148423D03*
X1268576Y117788D03*
X1250200Y122900D03*
X1251980Y106960D03*
X1262569Y147201D03*
X1243948Y154916D03*
X1269810Y154398D03*
X1275470Y99390D03*
X1252000Y145300D03*
X1257800Y120800D03*
X1255400Y108000D03*
X1252437Y140192D03*
X1249025Y130460D03*
X1240000Y129500D03*
X1259200Y168350D03*
X1281799Y193190D03*
X1267800Y161800D03*
X1271400Y161900D03*
X1240309D03*
X1267050Y169800D03*
X1233902Y173337D03*
X1241381Y172040D03*
X1246655Y176395D03*
X1263300Y169450D03*
X1268404Y246304D03*
X1279393Y247602D03*
X1270478Y243490D03*
X1277504Y250346D03*
X1272761Y240220D03*
X1283720Y223870D03*
X1249230Y402022D03*
X1262700Y461804D03*
X1262900Y466504D03*
X1277978Y491571D03*
X1241732Y518157D03*
Y528899D03*
X1245078Y513114D03*
X1235039Y518157D03*
X1238385Y513114D03*
X1235039Y528899D03*
X1278573Y519596D03*
X1265157Y510157D03*
X1261811Y517999D03*
X1258464Y510157D03*
Y517999D03*
X1261811Y510157D03*
X1248425Y518057D03*
X1251771Y510157D03*
X1258464Y528899D03*
X1261811D03*
X1255120Y518000D03*
Y510158D03*
X1271300Y510600D03*
X1271105Y498516D03*
X1274576Y510235D03*
X1265157Y528876D03*
Y517999D03*
X1262843Y497553D03*
X1258140Y474540D03*
X1271571Y479000D03*
X1271662Y487326D03*
X1256320Y490660D03*
X1258126Y469540D03*
X1271640Y474420D03*
X1271647Y482500D03*
X1256350Y486080D03*
X1245078Y535100D03*
X1238385D03*
X1241732Y555957D03*
X1245078Y572900D03*
Y550914D03*
X1241732Y566699D03*
X1238385Y572900D03*
X1235039Y555957D03*
X1238385Y550914D03*
X1235039Y566699D03*
X1245078Y588714D03*
X1238385D03*
X1265157Y547957D03*
X1261811D03*
X1258464D03*
X1251771D03*
X1265157Y537057D03*
X1261811D03*
X1251771D03*
X1258464D03*
X1265157Y585757D03*
X1261811D03*
X1258464D03*
X1251771D03*
X1261811Y555799D03*
X1258464D03*
X1251771D03*
X1248425Y555857D03*
X1251771Y566699D03*
Y574857D03*
X1265157D03*
X1261811D03*
X1258464D03*
X1261811Y566699D03*
X1258464D03*
X1273200Y582200D03*
X1255120Y555144D03*
Y574834D03*
Y537034D03*
X1265157Y566676D03*
Y555799D03*
X1277200Y539100D03*
X1270400Y593600D03*
X1241732Y593757D03*
X1245078Y610700D03*
X1241732Y604499D03*
X1238385Y610700D03*
X1235039Y593757D03*
Y604499D03*
X1258464Y593599D03*
X1261811D03*
X1248425Y593657D03*
X1251771Y612657D03*
X1258464Y604499D03*
X1261811D03*
X1265157Y612657D03*
X1261811D03*
X1258464D03*
X1255120Y593600D03*
Y612634D03*
X1265157Y604476D03*
Y593599D03*
X1293600Y-17000D03*
X1293816Y-13533D03*
X1292692Y1008D03*
X1296908Y36900D03*
X1287700Y-16700D03*
X1303774Y-18842D03*
X1298422Y74000D03*
X1330300Y83500D03*
X1336850Y76450D03*
X1327168Y61483D03*
X1304685Y78827D03*
X1298754Y83233D03*
X1336900Y61600D03*
X1343260Y53770D03*
X1327500Y51547D03*
X1327452Y55544D03*
X1309700Y83300D03*
X1336500Y81100D03*
X1324127Y50827D03*
X1337400Y72000D03*
X1338500Y96000D03*
X1343500Y87500D03*
X1335120Y94450D03*
X1301219Y89141D03*
X1304500Y40066D03*
X1296935Y51335D03*
X1323000Y83000D03*
X1328500Y92500D03*
X1308400Y79600D03*
X1306900Y131744D03*
X1301900Y124400D03*
X1325125Y100001D03*
X1310098Y150040D03*
X1293700Y121800D03*
X1295700Y144450D03*
X1327900Y142918D03*
X1301770Y101300D03*
X1345257Y100000D03*
X1320500Y145000D03*
X1325100D03*
X1287790Y156575D03*
X1310175Y154696D03*
X1299907Y159808D03*
X1295500Y159970D03*
X1300300Y169900D03*
X1315130Y164870D03*
X1315180Y169950D03*
X1326474Y216500D03*
X1338224Y209051D03*
X1305171Y164767D03*
X1310061Y165235D03*
X1344462Y209272D03*
X1323030Y216531D03*
X1330100Y165000D03*
Y170000D03*
X1340100Y165000D03*
X1345100D03*
Y170000D03*
X1340100D03*
X1335100D03*
Y165000D03*
X1320100D03*
X1325100D03*
X1320100Y170000D03*
X1325100D03*
X1345050Y272350D03*
X1300444Y267919D03*
X1309462Y240229D03*
X1288800Y233900D03*
X1320289Y237671D03*
X1331400Y237900D03*
X1342400D03*
X1315100Y237645D03*
X1325900Y237900D03*
X1336900D03*
X1320400Y232118D03*
X1331400D03*
X1342400D03*
X1314900D03*
X1325900D03*
X1336900D03*
X1331650Y317250D03*
X1338700Y284700D03*
X1323750Y319750D03*
X1320900Y321300D03*
X1335250Y344250D03*
X1319310Y300795D03*
X1336336Y333825D03*
X1302768Y296942D03*
X1331720Y334810D03*
X1326300Y341309D03*
X1341375Y314675D03*
Y319675D03*
X1341740Y306760D03*
X1336240D03*
X1316600Y305500D03*
X1306290Y298255D03*
X1308887Y285015D03*
X1319888Y290205D03*
X1323688D03*
X1345700Y285300D03*
X1341740Y301243D03*
X1336240D03*
X1335400Y284900D03*
X1302203Y314439D03*
X1315496Y361190D03*
X1342570Y368220D03*
X1326014Y347732D03*
X1296468Y437500D03*
X1325100Y457500D03*
Y452500D03*
X1320100Y457500D03*
Y452500D03*
X1315100D03*
X1310100D03*
X1315100Y457500D03*
X1305100D03*
Y452500D03*
X1310100Y457500D03*
X1330100D03*
Y452500D03*
X1300315Y427902D03*
X1335100Y427500D03*
Y432500D03*
X1300438Y433001D03*
X1318054Y460507D03*
X1340100Y432500D03*
X1304200Y466600D03*
Y462030D03*
X1329419Y464337D03*
X1344761Y498282D03*
X1309870Y499254D03*
X1287770Y501897D03*
X1340986Y511187D03*
X1341050Y498275D03*
X1299450Y484950D03*
X1320300Y498300D03*
X1322260Y477492D03*
X1329419Y469337D03*
X1322360Y472592D03*
X1316100Y543400D03*
X1308500Y540784D03*
X1324707Y545493D03*
X1327956Y545655D03*
X1318500Y539900D03*
X1305500Y542500D03*
X1296295Y615596D03*
X1301384Y618119D03*
X1400616Y13795D03*
X1376094Y4406D03*
X1380678Y-422D03*
X1380950Y30232D03*
X1379025Y-9799D03*
X1407422Y13139D03*
X1377009Y39753D03*
X1347500Y83000D03*
X1355500D03*
X1359500D03*
X1358500Y74500D03*
X1363500Y77400D03*
X1370975Y67225D03*
X1370849Y59349D03*
X1371910Y48800D03*
X1351500Y83000D03*
X1367700Y86450D03*
X1371500Y63200D03*
X1351488Y74000D03*
X1347000Y87500D03*
X1360700Y86550D03*
X1372300Y86400D03*
X1406546Y43116D03*
X1353500Y96959D03*
X1348615Y96239D03*
X1357000Y86640D03*
X1383171Y57549D03*
X1401300Y149600D03*
X1384600Y108500D03*
X1381359Y108496D03*
X1388100Y108500D03*
X1371500Y101000D03*
X1404200Y119200D03*
X1402500Y116300D03*
X1399100Y166900D03*
X1396933Y215763D03*
X1353569Y208960D03*
X1348569D03*
X1367789Y209216D03*
X1384671Y214832D03*
X1402020Y165561D03*
X1350100Y170000D03*
X1380100Y165000D03*
X1355100Y170000D03*
X1360100D03*
X1355100Y165000D03*
X1360100D03*
X1350100D03*
X1365100Y170000D03*
Y165000D03*
X1370100D03*
X1375100Y170000D03*
X1370100D03*
X1375100Y165000D03*
X1380100Y170000D03*
X1399852Y252353D03*
X1407274Y245652D03*
X1353400Y237900D03*
X1364400D03*
X1375400D03*
X1386400D03*
X1347900D03*
X1358900D03*
X1369900D03*
X1380900D03*
X1391900D03*
X1353400Y232118D03*
X1364400D03*
X1375400D03*
X1347900D03*
X1358900D03*
X1369900D03*
X1380900D03*
X1391900D03*
X1365246Y285931D03*
X1363700Y321600D03*
X1367200D03*
X1352400Y285000D03*
X1396470Y330014D03*
X1392400Y330800D03*
X1400400Y335400D03*
X1388450Y331250D03*
X1359200Y322200D03*
X1364260Y331619D03*
X1349134Y317436D03*
X1360294Y315025D03*
X1371090Y315395D03*
X1380904Y315947D03*
X1392226Y315658D03*
X1400558Y320157D03*
X1349134Y321145D03*
X1360294Y318825D03*
X1371090Y319195D03*
X1380904Y319747D03*
X1392226Y319458D03*
X1400558Y316357D03*
X1353142Y306760D03*
X1364044Y306690D03*
X1374840Y307130D03*
X1386048Y307310D03*
X1397635Y307630D03*
X1347642Y306760D03*
X1358544Y306690D03*
X1369340Y307130D03*
X1380548Y307310D03*
X1392135Y307630D03*
X1403037D03*
X1368200Y284000D03*
X1353672Y299605D03*
X1364014Y300815D03*
X1374820Y301219D03*
X1386101Y301465D03*
X1397635Y302051D03*
X1347892Y299741D03*
X1358514Y300815D03*
X1369320Y301219D03*
X1380601Y301465D03*
X1392135Y302051D03*
X1403037Y302046D03*
X1355300Y321675D03*
X1381431Y284259D03*
X1394370Y384230D03*
X1378207Y394568D03*
X1394260Y351170D03*
X1389500Y360500D03*
X1391845Y348325D03*
X1388300Y346200D03*
X1371600Y368700D03*
X1374300Y377885D03*
Y381485D03*
X1380872Y378098D03*
X1380900Y383164D03*
X1388900Y387800D03*
X1378200Y346900D03*
X1377028Y458125D03*
X1372028D03*
X1360100Y447500D03*
Y452500D03*
Y457500D03*
X1385100Y452500D03*
Y447500D03*
X1390100Y457500D03*
X1389900Y447400D03*
X1390100Y452500D03*
X1395100Y432500D03*
Y447500D03*
Y427500D03*
X1349800Y458200D03*
X1350100Y447500D03*
Y452500D03*
X1375100Y447500D03*
X1362560Y463478D03*
X1370100Y452500D03*
X1375100D03*
X1385100Y427500D03*
Y442500D03*
Y437500D03*
X1390100Y432500D03*
X1389900Y427400D03*
X1385100Y432500D03*
X1365100D03*
Y427500D03*
Y437500D03*
X1380100Y442500D03*
Y437500D03*
X1370100D03*
X1375100D03*
X1370100Y447500D03*
X1403027Y520231D03*
X1355800Y508500D03*
X1395242Y520301D03*
X1347546Y476897D03*
X1380741Y487489D03*
X1360863Y481673D03*
X1362841Y492823D03*
X1383263Y493673D03*
X1381041Y482575D03*
X1360741Y486523D03*
X1362880Y497556D03*
X1383241Y498595D03*
X1347081Y507919D03*
X1396035Y514863D03*
X1347196Y472941D03*
X1354462Y474141D03*
X1350500Y475100D03*
X1386241Y487323D03*
X1366341Y481823D03*
X1368441Y492723D03*
X1388741Y493623D03*
X1386241Y482623D03*
X1366309Y486618D03*
X1368441Y497523D03*
X1388719Y498745D03*
X1399721Y537509D03*
X1379053Y581864D03*
X1390595Y549328D03*
X1375961Y569473D03*
X1376000Y565700D03*
X1382000Y589500D03*
X1375600Y589700D03*
X1400216Y560128D03*
X1396158Y537595D03*
X1380890Y615820D03*
X1386921Y620689D03*
X1390851D03*
X1375961Y600673D03*
X1375861Y597073D03*
X1375961Y593473D03*
X1382100Y592800D03*
X1410600Y9100D03*
X1425081Y48412D03*
X1411546Y43116D03*
X1453700Y83750D03*
X1457000Y82000D03*
X1420337Y45477D03*
X1416837D03*
X1451021Y151626D03*
X1438348Y155908D03*
X1468700Y163100D03*
X1458569Y192143D03*
X1458908Y187699D03*
X1459548Y221731D03*
X1446331Y197285D03*
X1422281Y221479D03*
X1447999Y205645D03*
X1451366Y165296D03*
X1408247Y206270D03*
X1422196Y218052D03*
X1452728Y243306D03*
X1452200Y254500D03*
X1430365Y262624D03*
X1448500Y257700D03*
X1458318Y243000D03*
X1426905Y267045D03*
X1464150Y235550D03*
X1455600Y254826D03*
X1433057Y257388D03*
X1447154Y251710D03*
X1441750Y236800D03*
X1467040Y260357D03*
X1466006Y265300D03*
X1426658Y274252D03*
X1461348Y244350D03*
X1444850Y242730D03*
X1408250Y333000D03*
X1413387Y320033D03*
Y316233D03*
X1408537Y307630D03*
X1413720Y307634D03*
X1419333Y307598D03*
X1443500Y327900D03*
X1468399Y324930D03*
X1408537Y302046D03*
X1413720Y301983D03*
X1419220D03*
X1444311Y324366D03*
X1466970Y320235D03*
X1420075Y388402D03*
X1413735Y391302D03*
X1420075Y383375D03*
X1420515Y368585D03*
X1420075Y393402D03*
X1413735Y396302D03*
X1420075Y378375D03*
X1420515Y373585D03*
X1452699Y404060D03*
X1457300Y373600D03*
X1444400Y371600D03*
X1413400Y361300D03*
X1464400Y390800D03*
X1450400Y354300D03*
X1448000Y431500D03*
X1431900Y437100D03*
X1447700Y442500D03*
X1431900Y448000D03*
X1448000Y437000D03*
X1431900Y442600D03*
X1447500Y448000D03*
X1431900Y453500D03*
X1414107Y447267D03*
X1458300Y442675D03*
X1431690Y521530D03*
X1410486Y529792D03*
X1458060Y495020D03*
X1464553Y508872D03*
X1428500Y521000D03*
X1461267Y489790D03*
X1412941Y489523D03*
X1413193Y482532D03*
X1436600Y482900D03*
X1436541Y494423D03*
X1412741Y494223D03*
X1413041Y477423D03*
X1436396Y477691D03*
X1436441Y489323D03*
X1451533Y527867D03*
X1460661Y484891D03*
X1418241Y489523D03*
X1418441Y482523D03*
X1441842Y482924D03*
X1442041Y494423D03*
X1418341D03*
Y477323D03*
X1442141Y477623D03*
X1442041Y489223D03*
X1441252Y548631D03*
X1451150Y569900D03*
Y573200D03*
X1439822Y537382D03*
X1429026Y541026D03*
X1428281Y546119D03*
X1413600Y531300D03*
X1432560Y561160D03*
X1436160Y561200D03*
X1428791Y535512D03*
X1419600Y531500D03*
X1410950Y589670D03*
X1441409Y561117D03*
X1453533Y532667D03*
X1426870Y530800D03*
X1423800Y534800D03*
X1425243Y562260D03*
X1421560Y563455D03*
X1460200Y606200D03*
X1477100Y2400D03*
X1522600Y-6500D03*
X1504400Y20300D03*
X1481600Y5300D03*
X1501900Y-9124D03*
X1485242Y4589D03*
X1506300Y-6600D03*
X1521092Y21665D03*
X1520700Y7100D03*
X1513700Y7082D03*
X1470862Y38209D03*
X1519599Y86117D03*
X1524557Y88336D03*
X1505673Y146346D03*
X1473354Y153246D03*
X1485210Y134837D03*
X1476761Y157400D03*
X1483366Y120746D03*
Y115902D03*
X1484113Y128513D03*
X1485755Y131671D03*
X1518376Y111499D03*
X1476761Y152725D03*
X1490178Y112315D03*
X1518438Y100926D03*
X1494939Y159500D03*
X1510184Y142614D03*
X1503466Y142486D03*
X1500703Y158233D03*
X1514425Y134180D03*
X1520150Y127600D03*
X1475200Y142600D03*
X1496038Y154229D03*
X1488300Y158300D03*
X1500643Y154819D03*
X1513136Y157081D03*
X1496726Y120588D03*
X1496658Y115088D03*
X1500700Y127250D03*
X1500806Y133339D03*
X1518514Y130991D03*
X1524900Y139100D03*
X1526310Y142190D03*
X1524284Y112773D03*
X1474717Y110370D03*
X1482455Y124222D03*
X1502000Y147500D03*
X1490674Y98787D03*
X1524744Y133656D03*
X1496713Y174853D03*
X1504706Y164871D03*
X1511100Y186275D03*
X1492597Y172636D03*
X1488900Y172576D03*
X1474883Y182275D03*
X1478089Y182650D03*
X1470382Y188372D03*
X1472758Y216495D03*
X1513900Y218000D03*
X1519243Y191627D03*
X1487716Y218650D03*
X1477388Y172988D03*
X1497237Y217281D03*
X1497493Y162078D03*
X1512700Y205100D03*
X1488300Y161700D03*
X1498022Y221900D03*
X1512525Y208944D03*
X1492136Y199125D03*
X1493200Y162700D03*
X1512500Y199837D03*
X1510638Y166240D03*
X1516872Y208863D03*
X1491438Y221137D03*
X1510800Y193330D03*
X1515060Y192443D03*
X1507524Y218600D03*
X1472200Y243000D03*
X1482004Y222483D03*
X1525650Y248700D03*
X1470950Y229669D03*
X1526150Y234300D03*
X1486926Y247834D03*
X1516549Y234278D03*
X1516613Y240656D03*
X1521962Y278650D03*
X1512790Y240099D03*
X1499681Y279910D03*
X1507003Y272249D03*
X1492753Y273724D03*
X1484000Y257500D03*
X1492697Y267303D03*
X1475004Y246287D03*
X1474520Y251740D03*
X1482400Y248000D03*
X1487500Y244500D03*
X1505946Y254432D03*
X1519300Y245196D03*
X1499070Y255934D03*
X1470556Y256900D03*
X1484700Y251800D03*
X1527657Y278700D03*
X1503842Y245678D03*
X1504772Y259229D03*
X1523580Y237960D03*
X1496812Y273718D03*
X1479700Y224801D03*
X1504461Y274426D03*
X1520413Y239498D03*
X1491265Y226492D03*
X1483457Y244568D03*
X1474096Y256706D03*
X1497082Y277987D03*
X1526936Y307015D03*
X1529734Y319714D03*
X1473231Y320250D03*
X1499723Y300106D03*
X1471562Y325531D03*
X1512182Y293317D03*
X1497179Y306372D03*
X1508455Y313041D03*
X1523935Y318901D03*
X1514067Y315626D03*
X1484100Y330115D03*
X1501550Y293750D03*
X1482550Y333600D03*
X1487000Y333300D03*
X1503538Y318068D03*
X1518006Y286706D03*
X1499987Y288487D03*
X1496628Y288440D03*
X1520766Y341000D03*
X1505000Y340990D03*
X1508650Y287500D03*
X1510851Y340113D03*
X1500840Y319870D03*
X1504370Y330970D03*
X1518060Y317520D03*
X1470276Y330774D03*
X1493268Y293943D03*
X1496900Y293900D03*
X1525677Y311835D03*
X1499829Y341250D03*
X1530500Y287700D03*
X1510584Y330640D03*
X1526900Y292866D03*
X1470257Y321929D03*
X1493290Y287984D03*
X1483506Y326061D03*
X1514100Y321792D03*
X1517115Y330005D03*
X1507025Y391034D03*
X1493375Y380894D03*
X1505075D03*
X1501175Y394414D03*
X1499225Y391034D03*
Y384274D03*
X1487525Y397794D03*
X1493375Y394414D03*
X1489475D03*
X1487525Y384274D03*
X1489475Y387654D03*
X1514265Y355542D03*
X1499225Y377514D03*
X1495325Y391034D03*
X1493375Y387654D03*
X1505075Y394414D03*
X1501175Y387654D03*
X1495325Y377514D03*
X1524575Y394414D03*
X1530425Y384274D03*
X1487525Y377514D03*
X1517367Y349964D03*
X1472940Y384030D03*
X1473255Y372654D03*
X1525561Y350253D03*
X1511000Y350627D03*
X1505075Y387654D03*
Y401174D03*
X1501175D03*
X1507025Y404554D03*
X1522625Y391034D03*
X1495325Y397794D03*
X1499225D03*
Y404554D03*
X1493375Y401174D03*
X1489475D03*
X1507025Y384274D03*
X1501175Y380894D03*
X1522625Y404554D03*
X1481000Y350000D03*
X1502970Y350610D03*
X1496000Y350000D03*
X1528475Y380894D03*
X1522625Y397794D03*
X1528475Y401174D03*
Y387654D03*
X1529829Y362655D03*
X1516775Y380894D03*
X1526659Y397500D03*
X1528475Y394414D03*
X1524575Y380894D03*
X1522476Y361907D03*
X1507025Y377514D03*
X1520675Y394414D03*
X1522625Y377514D03*
X1530425D03*
X1518725Y397794D03*
Y391034D03*
Y384274D03*
X1510925Y397794D03*
X1512875Y401174D03*
Y394414D03*
X1530425Y391034D03*
X1514925Y358844D03*
X1484600Y394100D03*
X1495325Y384274D03*
X1483868Y390233D03*
X1483664Y362914D03*
X1520675Y401174D03*
X1516775D03*
Y394414D03*
X1510925Y377514D03*
X1512875Y380894D03*
X1515328Y363389D03*
X1518725Y377514D03*
X1522625Y384274D03*
X1510925Y391034D03*
X1516775Y387654D03*
X1512875D03*
X1510925Y384274D03*
X1478163Y354940D03*
X1530425Y397794D03*
X1489475Y380894D03*
X1524575Y387654D03*
X1503878Y364717D03*
X1485300Y443484D03*
X1489475Y450306D03*
X1491425Y453686D03*
X1493375Y457066D03*
X1499225Y460446D03*
X1493375Y450306D03*
X1489475Y457066D03*
X1495325Y460446D03*
X1497275Y463826D03*
X1483375Y458375D03*
X1530425Y467206D03*
X1516700Y409900D03*
X1528475Y407934D03*
X1512875Y463826D03*
X1510925Y467206D03*
X1507025D03*
X1508975Y463826D03*
X1501175Y428214D03*
X1495325Y418074D03*
X1499225Y424834D03*
X1516775Y463826D03*
X1505075D03*
X1524575D03*
X1493375Y414694D03*
X1489475D03*
X1491425Y411314D03*
X1487525D03*
X1493375Y443546D03*
X1489475D03*
X1491425Y440166D03*
X1487525D03*
X1516775Y457066D03*
X1528475Y463826D03*
X1524575Y407624D03*
X1514825Y467206D03*
X1499225Y411314D03*
X1501175Y407934D03*
X1499225Y440166D03*
X1524575Y457066D03*
X1505075D03*
X1501175Y443546D03*
X1485250Y408017D03*
X1501200Y450600D03*
X1521800Y419900D03*
X1508975Y457066D03*
X1505715Y441368D03*
X1497200Y421200D03*
X1491425Y446926D03*
X1493375Y428214D03*
X1489475D03*
X1493375Y436786D03*
X1489475D03*
X1499225Y446926D03*
Y453686D03*
X1491425Y460446D03*
X1499225Y467206D03*
X1489475Y463826D03*
X1491425Y467206D03*
X1487525Y460446D03*
X1495325Y467206D03*
X1485030Y463690D03*
X1491400Y424600D03*
X1487500D03*
X1489475Y421454D03*
X1493375D03*
X1520675Y463826D03*
X1505075Y407934D03*
X1497273Y407610D03*
X1489475Y407934D03*
X1493375D03*
X1520675Y470586D03*
X1503400Y524663D03*
X1524575Y470586D03*
X1520675Y477346D03*
X1512875Y470586D03*
X1472500Y509810D03*
X1474400Y517200D03*
X1482200Y477800D03*
X1497275Y470586D03*
Y477346D03*
X1489475D03*
X1499225Y473966D03*
X1493375Y470586D03*
X1495325Y473966D03*
X1493375Y477346D03*
X1491425Y480726D03*
X1501175Y477346D03*
X1530425Y487486D03*
X1528475Y484106D03*
X1520675D03*
X1524575Y477346D03*
X1512875D03*
X1497275Y484106D03*
X1499225Y487486D03*
X1503125Y473966D03*
X1507025D03*
X1501175Y484106D03*
X1505075D03*
X1503125Y480726D03*
X1505075Y477346D03*
X1508975Y484106D03*
X1507025Y480726D03*
X1510925Y487486D03*
X1512875Y484106D03*
X1493375D03*
X1491425Y487486D03*
X1495325Y480726D03*
Y487486D03*
X1526525Y480726D03*
X1530425D03*
X1524575Y484106D03*
X1522625Y480726D03*
X1516775Y477346D03*
X1472250Y485100D03*
X1470643Y495299D03*
X1482958Y486118D03*
X1485100Y469900D03*
X1487525Y480726D03*
X1478700Y533700D03*
X1500445Y619956D03*
X1523450Y612900D03*
X1519850Y613000D03*
X1487912Y611632D03*
X1484312Y611732D03*
X1549600Y-10800D03*
X1538520Y11911D03*
X1590431Y-6702D03*
X1544882Y-6900D03*
X1592829Y24460D03*
X1589623Y24528D03*
X1543500Y3400D03*
X1540000D03*
X1581947Y-6702D03*
X1545111Y24172D03*
X1580398Y-600D03*
Y5400D03*
X1571500Y-1406D03*
X1556200Y94800D03*
X1545572Y38188D03*
X1579100Y69000D03*
X1577269Y95344D03*
X1535300Y78490D03*
X1590949Y97850D03*
X1583374Y81319D03*
X1574780Y90992D03*
X1587359Y84348D03*
X1545250Y88360D03*
X1546370Y84180D03*
X1592715Y70817D03*
X1575018Y71213D03*
X1556810Y71760D03*
X1541413Y155259D03*
X1541765Y114000D03*
X1541421Y106742D03*
X1580275Y101041D03*
X1553500Y157000D03*
X1552171Y133000D03*
X1563108Y126423D03*
X1582500Y109900D03*
X1577700Y140149D03*
X1567520Y133354D03*
X1549000Y115571D03*
X1549187Y104713D03*
X1589200Y121800D03*
X1589622Y112876D03*
X1557981Y141470D03*
X1541390Y136498D03*
X1573153Y103721D03*
X1576606Y104392D03*
X1588500Y106788D03*
X1588000Y100500D03*
X1542685Y133321D03*
X1574197Y127915D03*
X1531726Y123800D03*
X1576506Y143416D03*
X1572395Y110754D03*
X1558100Y128926D03*
X1554627Y100877D03*
X1558136D03*
X1558100Y138025D03*
Y133526D03*
X1541434Y139871D03*
X1542000Y126246D03*
X1591800Y164900D03*
X1566486Y181270D03*
X1535065Y164300D03*
X1552051Y172053D03*
X1571501Y180031D03*
X1568488Y164058D03*
X1562150Y160700D03*
X1583874Y217746D03*
X1582249Y191716D03*
X1572817Y169910D03*
X1570294Y167384D03*
X1535425Y188016D03*
X1535000Y207200D03*
X1557979Y188844D03*
X1543100Y184128D03*
X1553500Y165400D03*
X1548178Y190880D03*
X1558000Y205100D03*
X1545023Y161675D03*
X1561925Y192675D03*
X1566858Y175192D03*
X1549693Y196707D03*
X1552063Y202031D03*
X1558042Y172448D03*
X1593218Y191776D03*
X1557787Y192236D03*
X1561538Y174649D03*
X1587549Y192000D03*
X1582699Y252646D03*
X1561104Y234255D03*
X1537972Y236000D03*
X1532237Y247801D03*
X1567000Y259560D03*
X1552900Y281700D03*
X1579867Y265445D03*
X1563157Y258164D03*
X1533596Y273504D03*
X1542751Y240477D03*
X1542690Y236050D03*
X1531935Y224160D03*
X1541325Y245090D03*
X1568120Y251710D03*
X1545802Y233529D03*
X1584568Y281339D03*
X1571876Y255800D03*
X1558700Y252000D03*
X1568365Y247761D03*
X1551404Y309376D03*
X1533228Y325000D03*
X1550619Y303087D03*
X1534400Y296029D03*
X1587800Y308200D03*
X1538450Y314300D03*
X1578790Y290920D03*
X1550800Y296200D03*
X1577486Y307621D03*
X1532850Y303950D03*
X1548024Y322145D03*
X1585479Y316610D03*
X1570574Y341776D03*
X1554932Y332171D03*
X1538406Y330157D03*
X1573950Y338050D03*
X1537500Y292800D03*
X1581834Y318591D03*
X1559800Y285300D03*
X1559500Y290300D03*
X1575645Y320664D03*
X1588551Y341410D03*
X1548334Y325497D03*
X1581940Y295820D03*
X1582800Y312100D03*
X1548273Y313227D03*
X1565000Y290500D03*
X1543864Y311399D03*
X1590212Y315425D03*
X1551250Y320303D03*
X1590176Y331844D03*
X1554775Y295328D03*
X1548100Y342200D03*
X1534833Y309798D03*
X1560500Y350000D03*
X1553825Y377514D03*
X1557534Y353400D03*
X1533589Y366361D03*
X1553825Y391034D03*
X1546025D03*
X1532367Y356530D03*
X1581822Y365770D03*
X1569584Y378002D03*
X1563575Y394414D03*
X1557725Y397794D03*
X1571375Y387654D03*
X1569425Y397794D03*
X1550639Y350200D03*
X1563575Y401174D03*
X1569425Y391034D03*
X1553825Y397794D03*
X1542300Y376717D03*
X1546025Y397794D03*
X1551875Y394414D03*
Y387654D03*
X1549950Y404490D03*
X1565525Y384274D03*
X1587684Y362653D03*
X1590154Y354762D03*
X1557725Y377514D03*
X1586500Y354900D03*
X1559675Y401174D03*
X1542125Y397794D03*
X1583208Y404941D03*
X1565525Y391034D03*
X1547975Y394414D03*
X1540175Y387654D03*
Y380894D03*
Y401174D03*
X1542932Y355740D03*
X1547975Y387654D03*
X1571450Y359650D03*
X1536275Y401174D03*
Y387654D03*
X1534325Y384274D03*
X1536275Y380894D03*
X1534325Y397794D03*
X1540175Y394414D03*
X1534325Y391034D03*
X1582600Y389300D03*
X1559675Y387654D03*
Y394414D03*
X1551875Y380894D03*
X1557725Y391034D03*
X1536275Y394414D03*
X1557725Y404554D03*
X1563575Y387654D03*
X1567475Y401174D03*
X1566922Y359681D03*
X1567121Y363217D03*
X1551875Y401174D03*
X1565525Y397794D03*
Y377514D03*
X1559675Y380894D03*
X1571375Y394414D03*
X1532375Y401174D03*
X1563575Y380894D03*
X1546182Y355446D03*
X1534325Y377514D03*
X1542125Y460446D03*
X1538225D03*
X1549925Y467206D03*
X1557725D03*
X1569425Y453686D03*
X1559675Y407934D03*
X1561625Y446926D03*
X1551875Y450306D03*
X1536275Y463826D03*
X1532375D03*
X1534325Y467206D03*
X1538225D03*
X1585560Y421324D03*
X1583773Y436137D03*
X1544075Y463826D03*
X1543850Y451400D03*
X1553825Y411314D03*
X1544150Y409900D03*
X1553825Y440166D03*
Y446926D03*
X1549926Y411312D03*
X1540175Y407934D03*
X1536275D03*
X1532375D03*
X1555775D03*
Y414694D03*
X1565525Y418074D03*
X1561625D03*
Y411314D03*
X1565525D03*
X1561625Y440166D03*
X1557725D03*
X1565525Y424834D03*
X1569425D03*
X1536300Y455200D03*
X1553825Y453686D03*
X1547000Y435650D03*
X1551875Y436786D03*
X1549925Y440166D03*
X1540653Y454588D03*
X1532349Y455200D03*
X1549925Y460446D03*
X1583208Y416752D03*
X1591350Y445300D03*
X1542125Y467206D03*
X1559595Y450631D03*
X1569425Y446926D03*
X1591430Y409440D03*
X1565525Y453686D03*
X1551875Y443546D03*
X1571375Y436786D03*
X1587573Y445300D03*
X1587550Y456550D03*
X1565525Y467206D03*
X1561625D03*
X1567475Y463826D03*
X1569425Y467206D03*
X1553825Y460446D03*
X1567475Y443546D03*
X1571375D03*
X1563575Y450306D03*
X1567475Y436786D03*
X1569425Y440166D03*
X1565525Y460446D03*
X1563575Y463826D03*
X1582300Y446100D03*
X1565525Y446926D03*
X1559675Y457066D03*
X1546025Y460446D03*
X1557725D03*
X1551875Y470586D03*
X1549925Y480726D03*
X1551875Y477346D03*
X1546025Y473966D03*
X1547975Y477346D03*
X1559675Y470586D03*
X1533595Y505530D03*
X1559675Y484106D03*
X1561625Y480726D03*
X1557725Y487486D03*
X1561625D03*
X1567475Y484106D03*
X1563575D03*
X1559675Y477346D03*
X1565525Y487486D03*
X1563575Y477346D03*
X1571375D03*
X1590580Y472370D03*
X1536275Y477346D03*
X1534325Y480726D03*
Y473966D03*
X1538225Y480726D03*
X1532375Y484106D03*
Y477346D03*
X1540175Y470586D03*
X1563575D03*
X1561625Y473966D03*
X1565525D03*
X1567475Y477346D03*
X1584970Y472370D03*
X1542125Y487486D03*
X1540175Y484106D03*
X1546025Y487486D03*
X1551875Y484106D03*
X1538225Y487486D03*
X1542125Y480726D03*
X1544075Y484106D03*
X1547975D03*
X1550990Y586588D03*
X1554358Y587258D03*
X1592934Y592396D03*
X1587610Y579550D03*
X1585155Y538574D03*
X1581730Y537170D03*
X1565389Y585721D03*
X1535565Y591658D03*
X1579900Y606050D03*
X1586700Y620100D03*
X1540477Y620308D03*
X1540700Y613700D03*
X1545407Y598393D03*
X1541384Y601262D03*
X1546075Y618145D03*
X1544050Y615296D03*
X1579680Y610279D03*
X1534968Y597268D03*
X1573500Y619500D03*
X1577000D03*
X1572950Y593950D03*
X1601650Y24160D03*
X1617500Y-14500D03*
X1597800Y24300D03*
X1637482Y21623D03*
X1653100Y11500D03*
X1638550Y7200D03*
X1623900Y4600D03*
X1598602Y3437D03*
X1599000Y61500D03*
X1596050Y75400D03*
X1632006Y94500D03*
X1640900Y66900D03*
X1630826Y88087D03*
X1614997Y84403D03*
X1625075Y80182D03*
X1597867Y93900D03*
X1597987Y79500D03*
X1619000Y38500D03*
X1606579Y86726D03*
X1614169Y95004D03*
X1617347Y94581D03*
X1599500Y75000D03*
X1649900Y78600D03*
X1653000Y77600D03*
X1643500Y80400D03*
X1635337Y73500D03*
X1627489Y74960D03*
X1632020Y97871D03*
X1632000Y73500D03*
X1628788Y97800D03*
X1621100Y69600D03*
X1620900Y81300D03*
X1593241Y134295D03*
X1598300Y116477D03*
X1598449Y120760D03*
X1600000Y104243D03*
X1648000Y100597D03*
X1594452Y111377D03*
X1654685Y121790D03*
X1613741Y112341D03*
X1593756Y129048D03*
X1647852Y197374D03*
X1651000Y178628D03*
X1603300Y185100D03*
X1627326Y182759D03*
X1654015Y217239D03*
X1615362Y213507D03*
X1650600Y186300D03*
X1648349Y182276D03*
X1645700Y214050D03*
X1602185Y180709D03*
X1635351Y185444D03*
X1598006Y192421D03*
X1595291Y166423D03*
X1644290Y196383D03*
X1635621Y208259D03*
X1601870Y270470D03*
X1643106Y233913D03*
X1600810Y266006D03*
X1636914Y270900D03*
X1596300Y250320D03*
X1627024Y253387D03*
X1631300Y280400D03*
X1637281Y260922D03*
X1597201Y238188D03*
X1643775Y246137D03*
X1637281Y254322D03*
X1617498Y273433D03*
X1632128Y225472D03*
X1637269Y264421D03*
X1622000Y279495D03*
X1627043Y256900D03*
X1636684Y283141D03*
X1610290Y265352D03*
X1638216Y246021D03*
X1604222Y268107D03*
X1608764Y322440D03*
X1608850Y343835D03*
X1638086Y319664D03*
X1625400Y327667D03*
X1602776Y331304D03*
X1652991Y321341D03*
X1620159Y332004D03*
X1638063Y326504D03*
X1631015Y328350D03*
X1635355Y324228D03*
X1639040Y316343D03*
X1625846Y286154D03*
X1609172Y339630D03*
X1636800Y287956D03*
X1602215Y363981D03*
X1610140Y358350D03*
X1609271Y348166D03*
X1621727Y395374D03*
X1612825Y405438D03*
X1622100Y400600D03*
X1630400Y391800D03*
X1629300Y385400D03*
X1630750Y404800D03*
X1613452Y387098D03*
X1638991Y352037D03*
X1621800Y381500D03*
Y386300D03*
X1595800Y405900D03*
X1639750Y445477D03*
X1630219Y446000D03*
X1621000Y440500D03*
X1621044Y433364D03*
X1621182Y427091D03*
X1603719Y412000D03*
X1611638Y454809D03*
X1612100Y446000D03*
X1646480Y443880D03*
X1611642Y461877D03*
X1630150Y427663D03*
X1593400Y432200D03*
X1639774Y439486D03*
X1623705Y467855D03*
X1639822Y453140D03*
X1647200Y430450D03*
X1640625Y429460D03*
X1621226Y445026D03*
X1615061Y463157D03*
X1596500Y455500D03*
X1617900Y409900D03*
X1595200Y412700D03*
X1651754Y488025D03*
X1626518Y528029D03*
X1627622Y524928D03*
X1631975Y527700D03*
X1597380Y495416D03*
X1600780D03*
X1617300Y519000D03*
X1625485Y494188D03*
X1623551Y525015D03*
X1621783Y498617D03*
X1620030Y525066D03*
X1594280Y472370D03*
X1645969Y514870D03*
X1617700Y475957D03*
X1614000Y475970D03*
X1639271Y491135D03*
X1639391Y513065D03*
X1629778Y507294D03*
X1642670Y514939D03*
X1629500Y491500D03*
X1649336Y511502D03*
X1641470Y506403D03*
X1644651Y505500D03*
X1649545Y515215D03*
X1601540Y588793D03*
X1622330Y592325D03*
X1594110Y611510D03*
X1619700Y617300D03*
X1617600Y619800D03*
X1680033Y-16711D03*
X1666500Y10500D03*
X1680034Y2863D03*
X1697300Y73296D03*
X1689250Y86000D03*
X1692300Y56900D03*
X1658600Y44700D03*
X1667000Y88000D03*
X1693900Y73300D03*
X1708610Y85121D03*
X1713900Y87900D03*
X1696870Y86093D03*
X1711000Y55525D03*
X1712600Y46100D03*
X1707268Y77668D03*
X1669000Y92000D03*
X1709184Y88811D03*
X1678627Y54616D03*
X1684248Y56746D03*
X1690500Y73950D03*
X1715100Y70500D03*
X1659000Y88000D03*
X1661900Y92400D03*
X1704824Y90049D03*
X1664500Y99000D03*
X1672200Y112200D03*
X1696907Y99077D03*
X1664135Y131239D03*
X1657835D03*
Y156436D03*
X1678400Y103000D03*
X1674800Y103100D03*
X1659643Y213505D03*
X1687550Y213751D03*
X1674912Y183000D03*
X1673530Y209974D03*
X1708350Y175050D03*
X1660800Y181900D03*
X1663400Y179475D03*
X1667140Y182300D03*
X1669849Y193067D03*
X1702400Y193450D03*
X1664321Y195244D03*
X1658082Y195298D03*
X1655978Y207827D03*
X1705666Y198055D03*
X1671688Y182925D03*
X1688046Y174447D03*
X1664390Y201163D03*
X1660440Y200789D03*
X1667356Y213096D03*
X1691439Y174354D03*
X1713000Y185000D03*
X1674019Y175990D03*
X1713596Y175795D03*
X1676750Y206050D03*
X1681116Y238614D03*
X1657500Y259700D03*
X1657567Y264600D03*
X1657498Y269700D03*
Y274700D03*
Y279900D03*
X1715837Y246178D03*
X1715078Y250231D03*
X1657494Y292816D03*
X1657498Y284900D03*
X1664453Y308557D03*
X1660972Y401447D03*
X1660834Y404934D03*
X1660890Y397300D03*
X1673074Y453185D03*
X1675120Y439731D03*
X1679145Y461950D03*
X1667588Y434149D03*
X1668100Y418700D03*
X1678303Y442765D03*
X1667946Y412987D03*
X1673550Y442696D03*
X1714530Y519900D03*
X1710594D03*
X1676800Y483800D03*
X1681650Y510673D03*
X1687606Y500938D03*
X1672265Y473600D03*
X1681115Y525218D03*
X1716490Y506970D03*
X1681500Y482000D03*
X1671050Y487000D03*
Y490850D03*
X1672159Y494042D03*
X1655790Y476593D03*
X1705767Y482434D03*
X1698354Y486873D03*
X1701617Y482706D03*
X1680133Y535489D03*
X1710389Y577787D03*
X1699600Y578100D03*
X1710000Y604500D03*
Y600000D03*
X1701291Y602268D03*
X1741544Y9151D03*
X1749085Y9177D03*
X1744900Y9100D03*
X1725474Y69250D03*
X1746328Y59011D03*
X1760016Y65774D03*
X1771707Y86500D03*
X1767250Y94500D03*
Y89500D03*
X1766333Y59116D03*
X1775000Y53500D03*
X1750400Y47400D03*
X1720100Y46100D03*
X1720500Y52440D03*
X1757998Y73637D03*
X1731350Y92140D03*
X1757772Y90174D03*
X1765015Y119100D03*
X1776828Y155211D03*
X1748425Y119190D03*
X1768886Y156173D03*
X1719000Y190500D03*
X1719080Y236152D03*
X1718820Y249032D03*
X1727896Y246175D03*
X1719080Y232852D03*
X1720651Y246141D03*
X1749462Y232955D03*
X1746900Y249804D03*
X1751900Y249700D03*
X1722251Y250532D03*
X1724181Y246159D03*
X1730996Y442804D03*
X1737150Y450850D03*
X1719089Y472104D03*
X1728700Y470200D03*
X1719560Y501770D03*
X1766100Y521124D03*
X1722347Y471811D03*
X1750800Y516100D03*
X1762715Y521085D03*
X1753807Y548183D03*
X1757478Y548192D03*
X1767529Y566200D03*
X1764300Y570900D03*
X1742200Y552863D03*
X1724899Y584748D03*
X1733000Y557000D03*
X1767141Y555500D03*
X1756578Y586743D03*
X1724250Y588250D03*
X1743000Y574500D03*
X1730759Y548162D03*
X1722500Y562000D03*
X1754897Y578750D03*
X1742381Y588530D03*
X1767500Y559800D03*
X1738498Y554255D03*
X1750399Y603201D03*
X1739714Y604967D03*
X1716950Y603450D03*
X1735000Y621002D03*
X1764823Y613600D03*
X1725133Y614896D03*
X1766400Y599400D03*
X1770600Y600800D03*
X1764912Y618718D03*
X1728341Y614851D03*
X1819800Y2100D03*
X1813913Y2287D03*
X1799462Y8830D03*
X1804462D03*
X1790078Y11860D03*
X1795078Y11900D03*
X1792700Y36871D03*
X1797700Y36804D03*
X1831000Y-16300D03*
X1828874Y-13520D03*
X1815150Y26650D03*
X1779750Y36530D03*
X1791500Y26918D03*
X1808100Y21800D03*
X1813795Y12165D03*
X1819837Y21700D03*
X1786865Y22375D03*
X1823600Y8800D03*
X1797700Y21018D03*
X1837500Y35700D03*
X1838850Y13160D03*
X1836700Y-18900D03*
X1804800Y-1500D03*
X1816723Y9781D03*
X1826414Y35486D03*
X1835600Y3900D03*
X1824240Y83680D03*
X1802119Y56581D03*
X1799438Y44328D03*
X1827000Y94550D03*
X1827150Y97800D03*
X1827100Y81600D03*
X1798454Y82256D03*
X1788216Y59197D03*
X1821350Y98270D03*
X1803300Y39900D03*
X1808363Y40033D03*
X1812352Y36949D03*
X1838500Y40400D03*
X1820457Y39128D03*
X1829580Y38620D03*
X1810100Y114700D03*
X1808226Y136171D03*
X1803509Y128500D03*
X1807818Y124179D03*
X1813118Y127976D03*
X1815026Y121478D03*
X1788000Y129000D03*
X1815883Y133277D03*
X1808313Y111705D03*
X1807509Y128500D03*
X1814900Y116900D03*
X1783252Y109044D03*
X1796500Y120000D03*
X1815348Y143437D03*
X1803058Y143733D03*
X1830316Y102163D03*
X1827500Y144900D03*
X1837090Y149830D03*
X1839667Y151994D03*
X1809810Y155858D03*
X1800792Y122691D03*
X1824990Y103620D03*
X1787373Y120188D03*
X1816418Y127976D03*
X1807166Y147401D03*
X1800420Y148240D03*
X1821261Y170012D03*
X1824200Y176900D03*
X1830415Y196567D03*
X1785500Y164000D03*
X1836100Y179700D03*
X1836900Y165800D03*
X1787000Y175500D03*
X1778900Y165800D03*
X1834103Y176021D03*
X1833629Y170807D03*
X1836932Y170486D03*
X1816125Y169492D03*
X1834400Y216900D03*
X1785500Y168000D03*
X1822877Y235852D03*
X1826085Y236034D03*
X1822638Y232106D03*
X1826662Y232191D03*
X1784440Y232938D03*
X1804388Y249904D03*
X1831700Y252272D03*
X1837857Y468630D03*
X1834100Y523900D03*
X1814852Y519901D03*
X1810350Y525650D03*
X1809700Y506875D03*
X1820400Y501100D03*
X1837200Y525700D03*
X1813500Y526500D03*
X1816584Y530542D03*
X1810200Y513300D03*
X1837300Y472276D03*
X1825900Y523500D03*
X1815200Y501500D03*
X1794100Y521900D03*
X1798250Y529200D03*
X1803900Y491500D03*
X1795200Y525700D03*
X1836600Y521600D03*
X1831600Y529000D03*
X1833700Y497300D03*
X1781300Y537800D03*
X1837475Y573835D03*
X1829051Y591299D03*
X1809600Y582800D03*
X1793660Y560570D03*
X1811100Y586800D03*
X1816458Y587480D03*
X1829300Y572900D03*
X1793100Y578500D03*
X1816020Y571448D03*
X1812802Y578693D03*
X1780394Y561076D03*
X1837534Y579322D03*
X1792805Y574675D03*
X1832500Y539500D03*
X1829000Y536315D03*
X1832200Y567760D03*
X1791349Y589122D03*
X1788300Y585100D03*
X1810863Y560637D03*
X1816175Y567669D03*
X1838224Y586650D03*
X1783700Y576400D03*
X1785050Y584550D03*
X1792100Y566900D03*
X1816330Y545260D03*
X1816100Y576200D03*
X1829176Y584287D03*
X1809309Y555713D03*
X1839126Y583354D03*
X1831500Y544500D03*
Y548000D03*
X1831800Y552300D03*
X1837000Y534900D03*
X1782300Y555900D03*
X1778675Y592224D03*
X1794500Y612500D03*
X1791500Y606500D03*
X1782700Y610900D03*
X1795000Y599600D03*
X1791323Y594030D03*
X1805000Y606500D03*
X1788290Y612006D03*
X1787500Y600500D03*
X1784200Y593924D03*
X1900256Y-14760D03*
X1841060Y35540D03*
X1882999Y7383D03*
X1883041Y15814D03*
X1893094Y-12642D03*
X1876792Y18461D03*
X1876881Y22181D03*
X1878000Y73950D03*
X1843107Y97988D03*
X1848208Y49427D03*
X1889218Y51030D03*
Y46030D03*
Y61030D03*
Y56030D03*
X1842250Y84000D03*
Y90750D03*
X1858600Y74300D03*
X1849426Y90700D03*
Y95500D03*
X1883200Y76600D03*
X1850600Y41348D03*
X1875600Y156300D03*
X1857110Y113600D03*
X1881324Y153250D03*
X1890974Y105600D03*
X1898102Y107325D03*
X1885700Y141200D03*
X1897536Y114600D03*
Y120510D03*
X1887497Y105444D03*
X1878753Y139893D03*
X1867280Y135406D03*
X1881165Y105561D03*
X1885102Y101134D03*
X1866606Y109967D03*
X1857849Y148079D03*
X1872254Y138618D03*
X1872400Y144619D03*
X1871521Y153593D03*
X1888639Y147042D03*
X1893640D03*
X1894855Y142122D03*
X1899855D03*
X1861932Y146431D03*
X1857919Y156123D03*
X1869668Y146750D03*
X1864904Y114735D03*
X1895060Y136099D03*
X1897507Y124450D03*
X1895673Y151800D03*
X1868843Y207920D03*
X1874236Y213800D03*
X1893238Y208042D03*
X1863650Y189750D03*
X1877880Y203780D03*
X1847200Y202050D03*
X1884340Y217866D03*
X1840900Y179700D03*
X1845700D03*
X1896710Y194380D03*
X1882452Y195888D03*
X1901100Y194200D03*
X1889400Y191200D03*
X1886200Y161000D03*
X1875700Y184800D03*
X1864637Y201861D03*
X1876700Y207600D03*
X1872100Y207900D03*
X1861243Y183100D03*
X1862000Y177500D03*
X1884000Y188100D03*
X1884400Y183700D03*
X1858686Y180377D03*
X1858500Y200100D03*
X1864000Y184900D03*
X1878789Y213663D03*
X1891880Y204370D03*
X1856874Y219443D03*
X1864464Y198466D03*
X1885465Y166285D03*
X1855000Y167100D03*
X1850723Y219250D03*
X1865100Y174600D03*
X1877517Y217988D03*
X1840149Y244425D03*
X1843449D03*
X1885000Y227500D03*
X1899816Y235035D03*
X1844444Y224035D03*
X1854374Y248790D03*
X1854720Y253700D03*
X1846517Y253500D03*
X1850220D03*
X1896529Y235080D03*
X1892274D03*
X1842857Y468630D03*
X1878100Y450200D03*
X1868167Y467855D03*
X1863137Y452710D03*
X1859059Y448076D03*
X1858633Y452803D03*
X1901574Y454422D03*
X1875900Y453600D03*
X1867500Y447900D03*
X1859530Y516430D03*
X1842400Y516800D03*
X1841900Y498800D03*
X1900890Y477200D03*
X1864339Y509560D03*
X1863000Y480000D03*
X1859600Y476200D03*
X1852719Y487575D03*
Y492575D03*
X1876945Y471316D03*
X1877407Y479046D03*
X1857450Y473654D03*
X1855206Y471112D03*
X1847000Y487500D03*
X1860000Y495500D03*
X1842764Y528136D03*
X1869914Y517225D03*
X1866688Y517128D03*
X1870100Y561150D03*
X1844018Y586482D03*
X1868200Y590939D03*
X1858528Y544528D03*
X1875850Y567200D03*
X1840690Y557190D03*
X1878500Y553500D03*
X1858500Y540000D03*
X1852250Y547900D03*
X1858681Y568087D03*
X1879862Y581862D03*
X1896899Y557790D03*
X1900729Y569557D03*
X1864580Y537060D03*
X1878736Y533040D03*
X1868110Y536000D03*
X1845407Y533178D03*
X1900250Y533700D03*
X1856573Y576534D03*
X1895523Y586365D03*
X1857812Y557245D03*
X1866800Y588000D03*
X1869800Y557100D03*
X1878875Y565475D03*
X1847070Y537610D03*
X1882300Y565550D03*
X1885100Y584300D03*
X1848900Y590750D03*
X1845000Y590800D03*
X1873510Y541710D03*
X1875600Y588500D03*
X1840700Y563800D03*
X1854530Y533132D03*
X1896358Y595255D03*
X1916078Y-16368D03*
X1918352Y89300D03*
X1923300Y94300D03*
X1920300Y68300D03*
X1917600Y66000D03*
X1948472Y80362D03*
X1933914Y96040D03*
X1946500Y104974D03*
X1940700Y136300D03*
X1908327Y149353D03*
X1904215Y142812D03*
X1909216D03*
X1943752Y137548D03*
X1947078Y139300D03*
X1963400Y141100D03*
X1921264Y153000D03*
X1937900Y153600D03*
X1923800Y151000D03*
X1927000Y152200D03*
X1934256Y99459D03*
X1934544Y127957D03*
X1929000Y158600D03*
X1926952Y156049D03*
X1952726Y102950D03*
X1914500Y113300D03*
X1940500Y157600D03*
X1932998Y119438D03*
X1923329Y99475D03*
X1947000Y142600D03*
X1923837Y118800D03*
X1937728Y99441D03*
X1925358Y140685D03*
X1903150Y217250D03*
X1910123Y217349D03*
X1957334Y201269D03*
X1939300Y204300D03*
X1917568Y201215D03*
X1917024Y193600D03*
X1929700Y163400D03*
X1921500Y193600D03*
X1940240Y169970D03*
X1939550Y165600D03*
X1931483Y199350D03*
X1940647Y161600D03*
X1909421Y208805D03*
X1909438Y204307D03*
X1904042Y204895D03*
X1903917Y201472D03*
X1925400Y196300D03*
X1929090Y193190D03*
X1939400Y198400D03*
X1934100Y193400D03*
X1935600Y176300D03*
X1932837Y186700D03*
X1925000Y192000D03*
X1918489Y212513D03*
X1943500Y209500D03*
X1930500Y209464D03*
X1918143Y219848D03*
X1927064Y207564D03*
X1938400Y178200D03*
X1939200Y194300D03*
X1935600Y198700D03*
X1950981Y191218D03*
X1963300Y191000D03*
X1952717Y198614D03*
X1943217Y221154D03*
Y217645D03*
X1942000Y440500D03*
X1937430Y464785D03*
X1904724Y447930D03*
X1939845Y445055D03*
X1947550Y485350D03*
X1956500Y507470D03*
X1938300Y486250D03*
X1957250Y512050D03*
X1937300Y508900D03*
X1919230Y483430D03*
X1919000Y487210D03*
X1919510Y475100D03*
Y479200D03*
X1939000Y476600D03*
X1956606Y526671D03*
X1957212Y479521D03*
X1957063Y474769D03*
X1945000Y474000D03*
X1948200Y474300D03*
X1928620Y482710D03*
X1956300Y515900D03*
X1959300Y518000D03*
X1908300Y514500D03*
X1942328Y508712D03*
X1963000Y573000D03*
X1921244Y533750D03*
X1951900Y534900D03*
X1963097Y551000D03*
X1934200Y573700D03*
X1935400Y583000D03*
X1940800Y537300D03*
X1945900Y549900D03*
X1923500Y579500D03*
X1948100Y538700D03*
X1923400Y583000D03*
X1923600Y575500D03*
X1926600Y559500D03*
X1923600Y565100D03*
X1923000Y568700D03*
X1959120Y547050D03*
X1958940Y538890D03*
X1961715Y555639D03*
X1918880Y586460D03*
X1961771Y591744D03*
X1962950Y566600D03*
X1956191Y548700D03*
X1962500Y578500D03*
X1958500Y535000D03*
X1907500Y545600D03*
X1907200Y551600D03*
X1932390Y590100D03*
X1959400Y601100D03*
X1934350Y609250D03*
X1923504Y592500D03*
X1911750Y592800D03*
X1927000Y614500D03*
X1914700Y594600D03*
X1963300Y612800D03*
X1938130Y601480D03*
X1967580Y104721D03*
X1972598Y165236D03*
X1967200Y521600D03*
X1964270Y511410D03*
X1968375Y509375D03*
X1972700Y576400D03*
Y549950D03*
X1964890Y534940D03*
X1965400Y619500D03*
X1456000Y360700D03*
X1460400Y353000D03*
X1459111Y356353D03*
X1467597Y363000D03*
X1463870Y367869D03*
X1453900Y353350D03*
X1453251Y356676D03*
X1552500Y358500D03*
X1550417Y362607D03*
G54D85*
X1854501Y195587D03*
X1859854Y501441D03*
X1952756Y589960D03*
X1944882Y582086D03*
X1952756D03*
X1944882Y574212D03*
X1952756D03*
X1944882Y566338D03*
X1952756D03*
X1944882Y558464D03*
Y589960D03*
X1952756Y558464D03*
X1944882Y605708D03*
X1952756D03*
X1944882Y597834D03*
X1952756D03*
G54D79*
X1638131Y475946D03*
G54D65*
X-4488Y425472D03*
X99980Y136909D03*
X1472000Y-5000D03*
Y-15000D03*
X1462000Y-5000D03*
Y-15000D03*
X1452000Y-5000D03*
Y-15000D03*
X1442000Y-5000D03*
Y-15000D03*
X1525000D03*
X1515000D03*
X1505000D03*
X1482000D03*
X1492000Y-5000D03*
Y-15000D03*
X1482000Y-5000D03*
X1575000Y-15000D03*
X1565000D03*
X1555000D03*
X1545000D03*
X1535000D03*
X1713503Y-5000D03*
Y-15000D03*
X1703503Y-5000D03*
Y-15000D03*
X1743503D03*
X1733503Y-5000D03*
Y-15000D03*
X1743503Y-5000D03*
X1779504D03*
X1769504D03*
Y-15000D03*
X1809504D03*
X1799504Y-5000D03*
Y-15000D03*
X1789504Y-5000D03*
Y-15000D03*
X1819504Y-5000D03*
Y-15000D03*
X1809504Y-5000D03*
G54D46*
X40500Y-42250D03*
Y-52250D03*
X60500Y-42250D03*
X80500D03*
X100500D03*
X60500Y-52250D03*
X80500D03*
X100500D03*
X120500Y-42250D03*
X140500D03*
X120500Y-52250D03*
X140500D03*
X467246Y-52301D03*
Y-42301D03*
X487246Y-52301D03*
Y-42301D03*
X507246Y-52301D03*
Y-42301D03*
X527246Y-52301D03*
Y-42301D03*
X547246Y-52301D03*
Y-42301D03*
X567246Y-52301D03*
Y-42301D03*
X798984Y-52057D03*
Y-42057D03*
X818984Y-52057D03*
Y-42057D03*
X838984Y-52057D03*
Y-42057D03*
X858984Y-52057D03*
Y-42057D03*
X878984Y-52057D03*
Y-42057D03*
X898984Y-52057D03*
Y-42057D03*
X1135583Y-52285D03*
Y-42285D03*
X1155583Y-52285D03*
Y-42285D03*
X1392258Y-52257D03*
Y-42257D03*
X1412258Y-52257D03*
Y-42257D03*
X1432258Y-52257D03*
Y-42257D03*
X1452258Y-52257D03*
Y-42257D03*
G54D88*
X1922248Y518328D03*
G54D83*
X1724807Y451179D03*
X1851250Y584622D03*
Y576748D03*
Y568874D03*
Y561000D03*
G54D81*
X1674921Y528523D03*
X1773347D03*
Y545059D03*
G54D73*
X638541Y171945D03*
Y454425D03*
X752641Y159945D03*
X1288068Y171945D03*
Y454425D03*
X1402168Y159945D03*
Y442425D03*
G54D62*
X40512Y458744D03*
G54D57*
X-15748Y116969D03*
Y132717D03*
X787D03*
X28740Y124843D03*
Y140591D03*
G54D64*
X30512Y467244D03*
X40512D03*
G54D84*
X1809665Y618663D03*
X1819665D03*
X1829665D03*
G54D68*
X63093Y202300D03*
X72936D03*
X82779D03*
X1914911Y495775D03*
X1934597D03*
X1924754D03*
G54D59*
X-14488Y434094D03*
X-4488D03*
X5512D03*
X15512D03*
X89980Y145531D03*
X99980D03*
X109980D03*
X119980D03*
G54D75*
X1401516Y23976D03*
G54D53*
X1466694Y375787D03*
G54D55*
X1705772Y567874D03*
G54D67*
X94683Y31978D03*
Y13078D03*
Y69778D03*
Y50878D03*
Y532955D03*
Y514079D03*
Y570755D03*
Y589679D03*
Y551879D03*
Y608555D03*
X637793Y-5822D03*
Y13078D03*
Y69778D03*
Y50878D03*
Y88678D03*
Y532955D03*
Y514079D03*
Y570755D03*
Y589679D03*
Y551879D03*
Y608555D03*
X744293Y-5822D03*
Y31978D03*
Y13078D03*
Y69778D03*
Y88678D03*
Y50878D03*
Y532955D03*
Y514079D03*
Y570755D03*
Y589679D03*
Y551879D03*
Y608555D03*
X1287403Y-5822D03*
Y31978D03*
Y13078D03*
Y69778D03*
Y88678D03*
Y50878D03*
Y532955D03*
Y514079D03*
Y551879D03*
Y608555D03*
G54D58*
X-7874Y216181D03*
Y325315D03*
G54D56*
X0Y0D03*
G54D61*
X18228Y178386D03*
X-1969D03*
X44291D03*
G54D49*
X1866923Y235400D03*
G54D45*
X-3937Y-43307D03*
X1956693D03*
X-13780Y598560D03*
X-3937Y646063D03*
X1956693D03*
G54D54*
X1611283Y615236D03*
G54D48*
X1955506Y454297D03*
X1699600D03*
Y235400D03*
G54D51*
X133563Y183126D03*
Y419626D03*
X783171Y183126D03*
Y419626D03*
G54D52*
X1454685Y338189D03*
X1600355Y527165D03*
G54D78*
X1613069Y302692D03*
G54D70*
X224410Y301378D03*
X500000Y163582D03*
Y439173D03*
X602362Y214764D03*
Y387992D03*
X874016Y301378D03*
X1149606Y163582D03*
Y439173D03*
X1251969Y214764D03*
Y387992D03*
%LPD*%
G75*
G36*
G01X39700Y275175D02*
X39682Y275125D01*
G03Y274169I1318J-478D01*
G01X39700Y274119D01*
Y265878D01*
X39682Y265828D01*
G03Y264872I1318J-478D01*
G01X39700Y264822D01*
Y199600D01*
X37200Y197100D01*
X13300D01*
X12200Y198200D01*
Y232700D01*
X9032Y235868D01*
Y264669D01*
X13796Y269435D01*
Y269436D01*
X14000Y269639D01*
Y337048D01*
X16232Y339280D01*
X38761D01*
X39700Y338341D01*
Y275175D01*
G37*
G36*
G01X53000Y223300D02*
X51800Y224500D01*
Y258900D01*
X59984Y267084D01*
X72912D01*
X74529Y265467D01*
Y265408D01*
X74988Y264949D01*
Y224634D01*
X73654Y223300D01*
X53000D01*
G37*
G36*
G01X312242Y24100D02*
X309621Y26721D01*
Y29648D01*
G03X309622Y29679I-1400J61D01*
G01Y32993D01*
X309600Y33013D01*
Y33900D01*
X308607Y34893D01*
X308715Y35016D01*
G03X309055Y35708I-1040J941D01*
G03X308194Y37260I-1380J249D01*
G01X308068Y37310D01*
Y49322D01*
X308228Y49355D01*
G03Y52103I-278J1374D01*
G01X308068Y52136D01*
Y53504D01*
X308194Y53555D01*
G03Y56159I-519J1302D01*
G01X308068Y56210D01*
Y66398D01*
X308226Y66432D01*
G03X308793Y68906I-298J1370D01*
G02X308897Y69329I378J131D01*
G03X308233Y71781I-905J1071D01*
G01X308067Y71810D01*
Y72475D01*
X308183Y72529D01*
G03X308184Y75071I-591J1271D01*
G01X308068Y75125D01*
Y85796D01*
X308253Y85993D01*
X308326Y86001D01*
G03Y88787I-160J1393D01*
G01X308253Y88795D01*
X308068Y88992D01*
Y91304D01*
X308194Y91354D01*
G03Y93960I-519J1303D01*
G01X308068Y94010D01*
Y94875D01*
X308151Y94959D01*
X309192Y96000D01*
Y106050D01*
X311242Y108100D01*
Y113418D01*
X333374Y135550D01*
Y157464D01*
G03Y169702I-6603J6119D01*
G01Y197394D01*
G02X333889Y197776I400J-1D01*
G03Y200440I439J1332D01*
G02X333374Y200822I-115J383D01*
G01Y213850D01*
X332342Y214882D01*
Y217475D01*
X332484Y217518D01*
G03Y220202I-406J1342D01*
G01X332342Y220245D01*
Y221375D01*
X332484Y221418D01*
G03X333125Y221828I-407J1342D01*
G03X333319Y223412I-1047J932D01*
G01X333296Y223456D01*
Y224704D01*
X333384Y224792D01*
G02X334063Y224570I283J-282D01*
G03X335597Y226104I1395J139D01*
G02X335375Y226783I60J396D01*
G01X335692Y227100D01*
Y227219D01*
X335838Y227260D01*
G03X335619Y230003I-379J1350D01*
G01X335442Y230023D01*
Y230950D01*
X335605Y231113D01*
X335670Y231123D01*
G03X336844Y232297I-212J1386D01*
G01X336854Y232362D01*
X337898Y233406D01*
X338035Y233310D01*
G03X339885Y235393I803J1150D01*
G01X340192Y235700D01*
Y237970D01*
X340198Y238019D01*
G03Y238701I-1360J341D01*
G01X340192Y238725D01*
Y241870D01*
X340198Y241919D01*
G03Y242601I-1360J341D01*
G01X340192Y242625D01*
Y244300D01*
X341492Y245600D01*
X344307D01*
X344354Y245513D01*
G03X346832Y245495I1244J647D01*
G01X346889Y245600D01*
X351066D01*
X351123Y245495D01*
G03X353591I1234J665D01*
G01X353648Y245600D01*
X357826D01*
X357883Y245495D01*
G03X360351I1234J665D01*
G01X360408Y245600D01*
X364586D01*
X364643Y245495D01*
G03X367121Y245513I1234J665D01*
G01X367168Y245600D01*
X368770D01*
X371587Y248417D01*
X373511D01*
X374536Y249442D01*
Y251003D01*
X374792Y251259D01*
X374940Y251112D01*
X374945Y251105D01*
G03X377279Y251397I1072J904D01*
G01X377333Y251510D01*
X377933D01*
G02X378258Y250877I0J-400D01*
G03X380536I1139J-817D01*
G02X380861Y251510I325J233D01*
G01X384693D01*
G02X385018Y250877I0J-400D01*
G03X387296I1139J-817D01*
G02X387621Y251510I325J233D01*
G01X391452D01*
G02X391777Y250877I0J-400D01*
G03X394055I1139J-817D01*
G02X394380Y251510I325J233D01*
G01X398212D01*
G02X398537Y250877I0J-400D01*
G03X400815I1139J-817D01*
G02X401140Y251510I325J233D01*
G01X407790D01*
X409680Y249620D01*
Y214712D01*
X408850Y213881D01*
Y210750D01*
G02X408285Y210386I-400J0D01*
G03Y207832I-579J-1277D01*
G02X408850Y207468I165J-364D01*
G01Y205342D01*
X410112Y204080D01*
Y197272D01*
X413292Y194092D01*
Y134592D01*
X448138Y99746D01*
Y91194D01*
X448032Y91137D01*
G03Y88663I660J-1237D01*
G01X448138Y88606D01*
Y86623D01*
X448022Y86569D01*
G03Y84023I588J-1273D01*
G01X448138Y83969D01*
Y74919D01*
X448021Y74866D01*
G03X447199Y73664I578J-1277D01*
G03X447688Y72523I1400J-75D01*
G02X447699Y71926I-260J-303D01*
G03X447562Y70013I952J-1030D01*
G03X447768Y69807I1089J883D01*
G02Y69198I-260J-305D01*
G03X447255Y67802I859J-1108D01*
G03X448024Y66824I1372J288D01*
G01X448138Y66770D01*
Y56009D01*
G03Y53757I835J-1126D01*
G01Y52364D01*
X448007Y52316D01*
G03Y49684I485J-1316D01*
G01X448138Y49636D01*
Y48332D01*
X448010Y48282D01*
G03Y45668I507J-1307D01*
G01X448138Y45618D01*
Y37144D01*
X447997Y37100D01*
G03Y34422I417J-1339D01*
G01X448138Y34378D01*
Y33303D01*
X447982Y33267D01*
G03Y30533I310J-1367D01*
G01X448138Y30497D01*
Y29509D01*
X447974Y29479D01*
G03Y26721I252J-1379D01*
G01X448138Y26691D01*
Y25696D01*
X446542Y24100D01*
X382541D01*
G02X382153Y24596I0J400D01*
G03X382178Y25147I-1361J338D01*
G03X381626Y26060I-1386J-214D01*
G02Y26685I250J312D01*
G03X379958I-834J1127D01*
G02Y26060I-250J-312D01*
G03X379406Y25147I834J-1127D01*
G03X379431Y24596I1386J-213D01*
G02X379043Y24100I-388J-96D01*
G01X312242D01*
G37*
G36*
G01X394340Y336660D02*
X383356Y347644D01*
G02X383448Y348278I283J283D01*
G03X381546Y350180I-671J1231D01*
G02X380912Y350088I-351J191D01*
G01X380457Y350543D01*
G03X378123Y352045I-1060J918D01*
G01X377285D01*
X377270Y352060D01*
X373904D01*
G03X371370I-1267J-600D01*
G01X367144D01*
G03X364610I-1267J-600D01*
G01X360384D01*
G03X357850I-1267J-600D01*
G01X353624D01*
G03X351090I-1267J-600D01*
G01X346865D01*
G03X344331I-1267J-600D01*
G01X340607D01*
X339252Y353415D01*
G02X339380Y354067I283J283D01*
G03X339957Y356204I-542J1293D01*
G03X337552Y355918I-1119J-844D01*
G03X337545Y355902I1281J-570D01*
G02X336893Y355774I-369J155D01*
G01X336407Y356260D01*
X336526Y356401D01*
G03X334666Y358466I-1068J908D01*
G03X334612Y358427I794J-1156D01*
G01X334473Y358322D01*
X334065Y358730D01*
Y359705D01*
G02X334685Y360039I400J0D01*
G03X336860Y361213I773J1170D01*
G03X334675Y362372I-1402J-4D01*
G02X334066Y362713I-209J341D01*
G01Y363605D01*
G02X334675Y363946I400J0D01*
G03X336860Y365105I783J1163D01*
G03X334685Y366279I-1402J4D01*
G02X334065Y366613I-220J334D01*
G01Y367506D01*
G02X334685Y367840I400J0D01*
G03Y370180I773J1170D01*
G02X334065Y370514I-220J334D01*
G01Y371405D01*
G02X334685Y371739I400J0D01*
G03Y374079I773J1170D01*
G02X334065Y374413I-220J334D01*
G01Y375305D01*
G02X334685Y375639I400J0D01*
G03X336860Y376813I773J1170D01*
G03X334675Y377972I-1402J-4D01*
G02X334066Y378313I-209J341D01*
G01Y379205D01*
G02X334675Y379546I400J0D01*
G03Y381872I783J1163D01*
G02X334066Y382213I-209J341D01*
G01Y383105D01*
G02X334675Y383446I400J0D01*
G03Y385772I783J1163D01*
G02X334066Y386113I-209J341D01*
G01Y387424D01*
X334545Y387904D01*
X336374Y389733D01*
Y472171D01*
X310076Y498468D01*
Y508397D01*
G02X310583Y508782I400J0D01*
G03Y511446I438J1332D01*
G02X310076Y511831I-107J385D01*
G01Y513872D01*
X309034Y514914D01*
Y517712D01*
X309039Y517734D01*
G03Y518380I-1364J323D01*
G01X309034Y518402D01*
Y527738D01*
G03Y529988I-836J1125D01*
G01Y532162D01*
G03Y534038I-1042J938D01*
G01Y536612D01*
X309039Y536634D01*
G03Y537280I-1364J323D01*
G01X309034Y537302D01*
Y547855D01*
X309039Y547877D01*
G03Y548523I-1364J323D01*
G01X309034Y548545D01*
Y550954D01*
G03Y553046I-934J1046D01*
G01Y555512D01*
X309039Y555534D01*
G03Y556180I-1364J323D01*
G01X309034Y556202D01*
Y565814D01*
G03Y567672I-1050J929D01*
G01Y569962D01*
G03Y571838I-1042J938D01*
G01Y574412D01*
X309039Y574434D01*
G03X309073Y574645I-1363J328D01*
G03X309065Y574944I-1398J112D01*
G01X309052Y575042D01*
X309477Y575467D01*
X309701Y575243D01*
X309670Y575131D01*
G03X310898Y576154I1351J-374D01*
G02X310801Y576791I186J354D01*
G01X312410Y578400D01*
X357192D01*
X359678Y580886D01*
X360489Y581696D01*
X372181D01*
X374699Y579178D01*
X375622D01*
G02X375904Y578495I0J-400D01*
G03X377880I988J-995D01*
G02X378162Y579178I282J283D01*
G01X378361D01*
X380239Y577300D01*
X447390D01*
X447630Y577060D01*
Y576048D01*
X447537Y575955D01*
X447520Y575944D01*
G03X447027Y575380I771J-1171D01*
G01X447024Y575374D01*
X446968Y575276D01*
X446889Y574933D01*
X446881Y574692D01*
X446914Y574450D01*
X447117Y573905D01*
X447893Y573129D01*
Y572650D01*
X447896Y572647D01*
Y570570D01*
X447762Y570523D01*
G03Y567877I464J-1323D01*
G01X447896Y567830D01*
Y556744D01*
X447248Y556096D01*
Y550455D01*
X447231Y550416D01*
G03Y549270I1279J-573D01*
G01X447248Y549231D01*
Y549214D01*
X447266Y549196D01*
X447280Y549171D01*
G03X447838Y548613I1230J672D01*
G01X447863Y548599D01*
X448642Y547820D01*
X448902Y547559D01*
Y539268D01*
X448292Y538658D01*
Y538127D01*
X448134Y538093D01*
G03X447538Y535643I298J-1370D01*
G02X447578Y535065I-255J-308D01*
G03X447680Y532967I979J-1004D01*
G02X447640Y532328I-259J-305D01*
G03X447293Y530309I770J-1172D01*
G03X448132Y529782I1117J847D01*
G01X448292Y529749D01*
Y516650D01*
X448167Y516600D01*
G03X447445Y514659I525J-1300D01*
G02X447237Y514105I-356J-182D01*
G03X448348Y511533I498J-1311D01*
G02X448902Y511164I154J-369D01*
G01Y503211D01*
X416436Y470744D01*
Y375900D01*
X406830Y366294D01*
Y358180D01*
X403740Y355090D01*
X402410D01*
X401500Y354180D01*
Y352030D01*
X403850Y349680D01*
X418370D01*
X420244Y347806D01*
G03X420505Y347474I1220J691D01*
G01Y344946D01*
X421963Y343488D01*
X431401D01*
X431898Y342991D01*
Y337611D01*
X430947Y336660D01*
X394340D01*
G37*
G36*
G01X961850Y24100D02*
X959000Y26950D01*
Y29000D01*
X959700Y29700D01*
Y32800D01*
X958184Y34316D01*
G02X958204Y34900I283J283D01*
G03X957802Y37260I-921J1057D01*
G01X957676Y37310D01*
Y49322D01*
X957836Y49355D01*
G03Y52103I-278J1374D01*
G01X957676Y52136D01*
Y53504D01*
X957802Y53555D01*
G03Y56159I-519J1302D01*
G01X957676Y56210D01*
Y66398D01*
X957834Y66432D01*
G03X958401Y68906I-298J1370D01*
G02X958505Y69329I378J131D01*
G03X957842Y71781I-905J1071D01*
G01X957676Y71810D01*
Y72475D01*
X957792Y72529D01*
G03Y75071I-592J1271D01*
G01X957676Y75125D01*
Y85796D01*
X957861Y85993D01*
X957934Y86001D01*
G03X959159Y87611I-160J1393D01*
G03X958139Y88748I-1385J-217D01*
G01X958087Y88762D01*
X957950Y88899D01*
Y91424D01*
G03X958615Y93096I-667J1233D01*
G03X957263Y94059I-1332J-439D01*
G02X956858Y94458I-5J400D01*
G01Y95716D01*
X957030Y95889D01*
X958250Y97109D01*
Y106050D01*
X960250Y108050D01*
Y112818D01*
X982982Y135550D01*
Y157464D01*
G03Y169702I-6603J6119D01*
G01Y197394D01*
G02X983497Y197776I400J-1D01*
G03Y200440I439J1332D01*
G02X982982Y200822I-115J383D01*
G01Y213850D01*
X981950Y214882D01*
Y217475D01*
X982092Y217518D01*
G03Y220202I-406J1342D01*
G01X981950Y220245D01*
Y221375D01*
X982092Y221418D01*
G03X983058Y223049I-406J1342D01*
G01X983048Y223096D01*
X983100Y223288D01*
Y224900D01*
X983492Y225292D01*
X983709Y225076D01*
X983689Y224972D01*
G03X983738Y224260I1377J-263D01*
G03X985560Y223397I1328J449D01*
G03X985205Y226104I-494J1312D01*
G02X984983Y226783I60J396D01*
G01X985300Y227100D01*
Y227219D01*
X985446Y227260D01*
G03X985227Y230003I-379J1350D01*
G01X985050Y230023D01*
Y230950D01*
X985213Y231113D01*
X985278Y231123D01*
G03X986452Y232297I-212J1386D01*
G01X986462Y232362D01*
X987506Y233406D01*
X987644Y233310D01*
G03X989596Y235262I802J1150D01*
G01X989500Y235400D01*
X989800Y235700D01*
Y237996D01*
G03Y238724I-1354J364D01*
G01Y241896D01*
G03Y242624I-1354J364D01*
G01Y244300D01*
X991100Y245600D01*
X993915D01*
X993962Y245513D01*
G03X996440Y245495I1244J647D01*
G01X996497Y245600D01*
X1000674D01*
X1000731Y245495D01*
G03X1003199I1234J665D01*
G01X1003256Y245600D01*
X1007434D01*
X1007491Y245495D01*
G03X1009959I1234J665D01*
G01X1010016Y245600D01*
X1014194D01*
X1014251Y245495D01*
G03X1016729Y245513I1234J665D01*
G01X1016776Y245600D01*
X1018250D01*
X1019518Y246868D01*
X1019543Y246882D01*
G03X1020092Y247431I-678J1227D01*
G01X1020106Y247456D01*
X1021118Y248468D01*
X1023217D01*
X1023878Y249129D01*
Y251105D01*
X1023937Y251164D01*
G02X1024532Y251131I283J-283D01*
G03X1026887Y251397I1093J878D01*
G01X1026941Y251510D01*
X1027541D01*
G02X1027866Y250877I0J-400D01*
G03X1030144I1139J-817D01*
G02X1030469Y251510I325J233D01*
G01X1034301D01*
G02X1034626Y250877I0J-400D01*
G03X1036904I1139J-817D01*
G02X1037229Y251510I325J233D01*
G01X1041060D01*
G02X1041385Y250877I0J-400D01*
G03X1043663I1139J-817D01*
G02X1043988Y251510I325J233D01*
G01X1047820D01*
G02X1048145Y250877I0J-400D01*
G03X1050423I1139J-817D01*
G02X1050748Y251510I325J233D01*
G01X1057570D01*
X1059500Y249580D01*
Y215242D01*
X1058458Y214200D01*
Y210750D01*
G02X1057893Y210386I-400J0D01*
G03Y207832I-579J-1277D01*
G02X1058458Y207468I165J-364D01*
G01Y205342D01*
X1059720Y204080D01*
Y197272D01*
X1062900Y194092D01*
Y134592D01*
X1097746Y99746D01*
Y91194D01*
X1097640Y91137D01*
G03Y88663I660J-1237D01*
G01X1097746Y88606D01*
Y86623D01*
X1097630Y86569D01*
G03Y84023I588J-1273D01*
G01X1097746Y83969D01*
Y74919D01*
X1097629Y74866D01*
G03X1096807Y73664I578J-1277D01*
G03X1097296Y72523I1400J-75D01*
G02X1097307Y71926I-260J-303D01*
G03X1097170Y70013I952J-1030D01*
G03X1097376Y69807I1089J883D01*
G02Y69198I-260J-305D01*
G03X1096863Y67802I859J-1108D01*
G03X1097632Y66824I1372J288D01*
G01X1097746Y66770D01*
Y56009D01*
G03Y53757I835J-1126D01*
G01Y52364D01*
X1097615Y52316D01*
G03Y49684I485J-1316D01*
G01X1097746Y49636D01*
Y48332D01*
X1097618Y48282D01*
G03Y45668I507J-1307D01*
G01X1097746Y45618D01*
Y37144D01*
X1097605Y37100D01*
G03Y34422I417J-1339D01*
G01X1097746Y34378D01*
Y33303D01*
X1097590Y33267D01*
G03Y30533I310J-1367D01*
G01X1097746Y30497D01*
Y29509D01*
X1097582Y29479D01*
G03Y26721I252J-1379D01*
G01X1097746Y26691D01*
Y25696D01*
X1096150Y24100D01*
X1031481D01*
G03X1031202Y24333I-1031J-950D01*
G02X1031190Y24991I221J333D01*
G03X1029648Y24967I-789J1159D01*
G02X1029660Y24309I-221J-333D01*
G03X1029419Y24100I792J-1157D01*
G01X961850D01*
G37*
G36*
G01X1023490Y352630D02*
X1023478Y352642D01*
X1023001D01*
X1022954Y352669D01*
G03X1021491Y352642I-709J-1209D01*
G01X1016239D01*
G03X1014731I-754J-1182D01*
G01X1009479D01*
G03X1007971I-754J-1182D01*
G01X1002719D01*
G03X1001211I-754J-1182D01*
G01X995960D01*
G03X994452I-754J-1182D01*
G01X990797D01*
X990132Y353307D01*
Y356055D01*
G02X990819Y356333I400J0D01*
G03Y358285I1007J976D01*
G02X990132Y358563I-287J278D01*
G01Y359955D01*
G02X990819Y360233I400J0D01*
G03Y362185I1007J976D01*
G02X990134Y362421I-287J278D01*
G01X989794Y362761D01*
X989817Y362867D01*
G03X988153Y364531I-1371J293D01*
G01X988047Y364508D01*
X987584Y364971D01*
X985974Y366582D01*
X985487Y367069D01*
G02X985599Y367713I283J282D01*
G03X986263Y369740I-533J1297D01*
G03X984846Y370395I-1197J-730D01*
G02X984383Y370790I-63J395D01*
G01Y371129D01*
G02X984846Y371524I400J0D01*
G03Y374294I220J1385D01*
G02X984383Y374689I-63J395D01*
G01Y375029D01*
G02X984846Y375424I400J0D01*
G03Y378194I220J1385D01*
G02X984384Y378589I-62J395D01*
G01Y378929D01*
G02X984846Y379324I400J0D01*
G03Y382094I220J1385D01*
G02X984384Y382489I-62J395D01*
G01Y382829D01*
G02X984846Y383224I400J0D01*
G03Y385994I220J1385D01*
G02X984384Y386389I-62J395D01*
G01Y399483D01*
X984623Y399723D01*
X985974Y401074D01*
Y472171D01*
X958268Y499878D01*
Y511476D01*
X958381Y511530D01*
G03Y514058I-607J1264D01*
G01X958267Y514112D01*
Y517058D01*
G03X958624Y518465I-984J998D01*
G03X958268Y519055I-1341J-407D01*
G01Y527533D01*
X958385Y527586D01*
G03Y530140I-579J1277D01*
G01X958268Y530193D01*
Y531867D01*
G03Y534333I-668J1233D01*
G01Y535959D01*
G03Y537955I-985J998D01*
G01Y547202D01*
G03Y549198I-985J998D01*
G01Y550712D01*
X958372Y550769D01*
G03Y553231I-671J1231D01*
G01X958268Y553288D01*
Y554859D01*
G03Y556855I-985J998D01*
G01Y565515D01*
G03Y567971I-676J1228D01*
G01Y569667D01*
G03Y572133I-668J1233D01*
G01Y573759D01*
G03Y575755I-985J998D01*
G01Y577392D01*
X958508Y577633D01*
X959275Y578400D01*
X1008313D01*
X1011159Y581246D01*
X1022081D01*
X1025227Y578100D01*
X1025183Y577981D01*
G03X1027681Y576745I1317J-481D01*
G03X1027858Y577150I-1180J757D01*
G01X1027897Y577300D01*
X1095610D01*
X1097024Y575886D01*
X1096905Y575762D01*
G03X1097424Y573454I994J-989D01*
G01X1097556Y573406D01*
Y570582D01*
X1097416Y570538D01*
G03Y567862I418J-1338D01*
G01X1097556Y567818D01*
Y554289D01*
G03Y551911I744J-1189D01*
G01Y551133D01*
X1097482Y551092D01*
G03X1097451Y548610I636J-1249D01*
G01X1097556Y548553D01*
Y538045D01*
X1097441Y537991D01*
G03Y535455I599J-1268D01*
G01X1097556Y535401D01*
Y535074D01*
G03X1097170Y532816I604J-1265D01*
G02X1097127Y532239I-297J-268D01*
G03X1097439Y529879I891J-1083D01*
G01X1097556Y529826D01*
Y517049D01*
G02X1097495Y516448I-291J-274D01*
G03X1097053Y514659I805J-1148D01*
G02X1096845Y514105I-356J-182D01*
G03X1096767Y514072I507J-1307D01*
G03X1097116Y511411I576J-1278D01*
G03X1097913Y511513I228J1383D01*
G02X1098456Y511140I143J-373D01*
G01Y503165D01*
X1066036Y470744D01*
Y406300D01*
X1064368Y404632D01*
Y399532D01*
X1062414Y397578D01*
Y395585D01*
G02X1061730Y395304I-400J1D01*
G03Y393414I-1036J-945D01*
G02X1062414Y393133I284J-282D01*
G01Y391686D01*
G02X1061730Y391405I-400J1D01*
G03Y389515I-1036J-945D01*
G02X1062414Y389234I284J-282D01*
G01Y387786D01*
G02X1061730Y387505I-400J1D01*
G03Y385615I-1036J-945D01*
G02X1062414Y385334I284J-282D01*
G01Y383886D01*
G02X1061730Y383605I-400J1D01*
G03Y381715I-1036J-945D01*
G02X1062414Y381434I284J-282D01*
G01Y379986D01*
G02X1061730Y379705I-400J1D01*
G03Y377815I-1036J-945D01*
G02X1062414Y377534I284J-282D01*
G01Y376087D01*
G02X1062301Y375807I-400J-1D01*
G01Y375426D01*
X1061982D01*
X1061925Y375530D01*
G03X1061633Y373819I-1231J-670D01*
G02X1062301Y373522I268J-297D01*
G01Y372498D01*
G02X1061693Y372156I-400J0D01*
G03Y369762I-730J-1197D01*
G02X1062301Y369420I208J-342D01*
G01Y367901D01*
X1056790Y362390D01*
X1053420D01*
G03X1051908I-756J-1181D01*
G01X1051048D01*
G02X1050656Y362872I0J400D01*
G03X1047912I-1372J288D01*
G02X1047520Y362390I-392J-82D01*
G01X1046660D01*
G03X1045148I-756J-1181D01*
G01X1044288D01*
G02X1043896Y362872I0J400D01*
G03X1041152I-1372J288D01*
G02X1040760Y362390I-392J-82D01*
G01X1039901D01*
G03X1038389I-756J-1181D01*
G01X1037529D01*
G02X1037137Y362872I0J400D01*
G03X1034739Y362205I-1372J288D01*
G02X1034729Y361649I-293J-273D01*
G01X1034421Y361341D01*
G02X1033749Y361532I-283J283D01*
G03X1032062Y359845I-1364J-323D01*
G02X1032253Y359173I-92J-389D01*
G01X1029678Y356598D01*
X1029553Y356650D01*
G03X1027715Y354812I-548J-1290D01*
G01X1027767Y354687D01*
X1025710Y352630D01*
X1023490D01*
G37*
%LPC*%
G75*
G36*
G01X58175Y255329D02*
G02X56785Y255306I-675J-1229D01*
G03X56753Y256011I-204J344D01*
G02X58183Y256034I692J1445D01*
G03X58175Y255329I184J-355D01*
G37*
G36*
G01X325676Y104251D02*
G03X326253Y104144I338J214D01*
G02X325908Y102270I839J-1123D01*
G03X325331Y102377I-338J-214D01*
G02X325676Y104251I-839J1123D01*
G37*
G36*
G01X364145Y86617D02*
G03X363524I-311J-252D01*
G02Y88383I-1089J883D01*
G03X364145I310J252D01*
G02Y86617I1089J-883D01*
G37*
G36*
G01X376347Y85404D02*
G03Y84850I288J-277D01*
G02X374327I-1010J-973D01*
G03Y85404I-288J277D01*
G02X376347I1010J973D01*
G37*
G36*
G01X358743Y69924D02*
G03Y69346I277J-289D01*
G02X356801I-971J-1011D01*
G03Y69924I-277J289D01*
G02X358743I971J1011D01*
G37*
G36*
G01X358702Y51293D02*
G03Y50699I268J-297D01*
G02X356822I-940J-1040D01*
G03Y51293I-268J297D01*
G02X358702I940J1040D01*
G37*
G36*
G01X363196Y46006D02*
G03X362587I-305J-258D01*
G02Y47822I-1069J908D01*
G03X363196I305J258D01*
G02Y46006I1069J-908D01*
G37*
G36*
G01X359577Y32318D02*
G03X359571Y31740I273J-292D01*
G02X357634Y31760I-979J-1004D01*
G03X357640Y32338I-273J292D01*
G02X359577Y32318I979J1004D01*
G37*
G36*
G01X363887Y91625D02*
G02Y93375I-1095J875D01*
G03X364512I313J250D01*
G02Y91625I1095J-875D01*
G03X363887I-312J-250D01*
G37*
G36*
G01X375007Y75306D02*
G02X373577I-715J-1206D01*
G03Y75994I-204J344D01*
G02X375007I715J1206D01*
G03Y75306I204J-344D01*
G37*
G36*
G01X381727Y61396D02*
G02X380164Y61350I-747J-1186D01*
G03X380145Y62014I-233J326D01*
G02X381708Y62060I747J1186D01*
G03X381727Y61396I233J-326D01*
G37*
G36*
G01X358734Y571001D02*
G03Y570446I288J-278D01*
G02X356714I-1010J-972D01*
G03Y571001I-288J277D01*
G02X358734I1010J972D01*
G37*
G36*
G01X358510Y552100D02*
G03Y551522I277J-289D01*
G02X356568I-971J-1011D01*
G03Y552100I-277J289D01*
G02X358510I971J1011D01*
G37*
G36*
G01X363196Y547006D02*
G03X362587I-305J-258D01*
G02Y548822I-1069J908D01*
G03X363196I305J258D01*
G02Y547006I1069J-908D01*
G37*
G36*
G01X375837Y544726D02*
G03X375845Y545304I-272J293D01*
G02X377784Y545277I984J999D01*
G03X377776Y544699I272J-293D01*
G02X375837Y544726I-984J-999D01*
G37*
G36*
G01X358688Y533045D02*
G03Y532501I293J-272D01*
G02X356634I-1027J-955D01*
G03Y533045I-293J272D01*
G02X358688I1027J955D01*
G37*
G36*
G01X376202Y517883D02*
G03Y517329I288J-277D01*
G02X374182I-1010J-973D01*
G03Y517883I-288J277D01*
G02X376202I1010J973D01*
G37*
G36*
G01X362680Y516142D02*
G03X363262Y516132I296J269D01*
G02X363227Y514210I1003J-980D01*
G03X362645Y514220I-296J-269D01*
G02X362680Y516142I-1003J980D01*
G37*
G36*
G01X363196Y509206D02*
G03X362587I-305J-258D01*
G02Y511022I-1069J908D01*
G03X363196I305J258D01*
G02Y509206I1069J-908D01*
G37*
G36*
G01X975284Y104251D02*
G03X975861Y104144I338J214D01*
G02X975516Y102270I839J-1123D01*
G03X974939Y102377I-338J-214D01*
G02X975284Y104251I-839J1123D01*
G37*
G36*
G01X1013753Y86617D02*
G03X1013132I-311J-252D01*
G02Y88383I-1089J883D01*
G03X1013753I310J252D01*
G02Y86617I1089J-883D01*
G37*
G36*
G01X1025955Y85404D02*
G03Y84850I288J-277D01*
G02X1023935I-1010J-973D01*
G03Y85404I-288J277D01*
G02X1025955I1010J973D01*
G37*
G36*
G01X1008351Y69924D02*
G03Y69346I277J-289D01*
G02X1006409I-971J-1011D01*
G03Y69924I-277J289D01*
G02X1008351I971J1011D01*
G37*
G36*
G01X1008310Y51293D02*
G03Y50699I268J-297D01*
G02X1006430I-940J-1040D01*
G03Y51293I-268J297D01*
G02X1008310I940J1040D01*
G37*
G36*
G01X1012804Y46006D02*
G03X1012195I-305J-258D01*
G02Y47822I-1069J908D01*
G03X1012804I304J258D01*
G02Y46006I1069J-908D01*
G37*
G36*
G01X1009185Y32318D02*
G03X1009179Y31740I273J-292D01*
G02X1007242Y31760I-979J-1004D01*
G03X1007248Y32338I-273J292D01*
G02X1009185Y32318I979J1004D01*
G37*
G36*
G01X1013495Y91625D02*
G02Y93375I-1095J875D01*
G03X1014120I312J250D01*
G02Y91625I1095J-875D01*
G03X1013495I-313J-250D01*
G37*
G36*
G01X1024615Y75306D02*
G02X1023185I-715J-1206D01*
G03Y75994I-204J344D01*
G02X1024615I715J1206D01*
G03Y75306I204J-344D01*
G37*
G36*
G01X1008303Y570999D02*
G03Y570421I277J-289D01*
G02X1006361I-971J-1011D01*
G03Y570999I-277J289D01*
G02X1008303I971J1011D01*
G37*
G36*
G01X1008118Y552100D02*
G03Y551522I277J-289D01*
G02X1006176I-971J-1011D01*
G03Y552100I-277J289D01*
G02X1008118I971J1011D01*
G37*
G36*
G01X1012804Y547006D02*
G03X1012195I-305J-258D01*
G02Y548822I-1069J908D01*
G03X1012804I304J258D01*
G02Y547006I1069J-908D01*
G37*
G36*
G01X1025534Y542016D02*
G03X1025512Y542615I-276J290D01*
G02Y544785I888J1085D01*
G03X1025534Y545384I-254J309D01*
G02X1027388Y545315I966J1016D01*
G03X1027366Y544716I254J-309D01*
G02Y542684I-966J-1016D01*
G03X1027388Y542085I276J-290D01*
G02X1027510Y540027I-888J-1085D01*
G03Y539473I288J-277D01*
G02X1025490I-1010J-973D01*
G03Y540027I-288J277D01*
G02X1025534Y542016I1010J973D01*
G37*
G36*
G01X1008178Y533126D02*
G03Y532548I277J-289D01*
G02X1006236I-971J-1011D01*
G03Y533126I-277J289D01*
G02X1008178I971J1011D01*
G37*
G36*
G01X1025810Y517883D02*
G03Y517329I288J-277D01*
G02X1023790I-1010J-973D01*
G03Y517883I-288J277D01*
G02X1025810I1010J973D01*
G37*
G36*
G01X1012288Y516142D02*
G03X1012870Y516132I296J269D01*
G02X1012835Y514210I1003J-980D01*
G03X1012253Y514220I-296J-269D01*
G02X1012288Y516142I-1003J980D01*
G37*
G36*
G01X1012804Y509206D02*
G03X1012195I-305J-258D01*
G02Y511022I-1069J908D01*
G03X1012804I304J258D01*
G02Y509206I1069J-908D01*
G37*
G54D50*
X388187Y88678D03*
Y50878D03*
Y69778D03*
Y31978D03*
Y551879D03*
Y570755D03*
Y514079D03*
Y532955D03*
X1037797Y50878D03*
Y88678D03*
Y69778D03*
Y31978D03*
Y551879D03*
Y570755D03*
Y514079D03*
Y532955D03*
G54D69*
X19800Y257900D03*
G54D47*
X19904Y254162D03*
X37000Y265350D03*
X33490Y267900D03*
X37000Y275000D03*
X321334Y32100D03*
X334292D03*
X321061Y28014D03*
X327754Y35957D03*
X324407Y28014D03*
Y35957D03*
X314368Y28014D03*
X311021Y35957D03*
X334447D03*
X331100Y28014D03*
X354525Y28022D03*
X354526Y35957D03*
X351179Y28022D03*
X347833Y35957D03*
X344486D03*
Y28022D03*
X337793Y35957D03*
X341140Y28022D03*
X334446Y28014D03*
X317714Y35957D03*
X321192Y51000D03*
X321334Y69900D03*
X334292Y51000D03*
Y69900D03*
X321061Y65814D03*
Y92757D03*
X327754Y73757D03*
Y87392D03*
X324407Y65814D03*
Y89964D03*
Y73757D03*
Y84599D03*
X314368Y65814D03*
Y92657D03*
X311021Y84714D03*
X334447Y73757D03*
Y87392D03*
X331100Y65814D03*
Y89964D03*
X354525Y65822D03*
X354415Y92757D03*
X354526Y73757D03*
X354415Y87392D03*
X351179Y65822D03*
Y89964D03*
X347833Y73757D03*
Y87392D03*
X344486Y84714D03*
Y73757D03*
Y65822D03*
Y89964D03*
X337793Y84599D03*
Y73757D03*
X341140Y65822D03*
Y92757D03*
X334446Y65814D03*
X334447Y92757D03*
X321061Y54857D03*
X327754Y46914D03*
X324407Y54857D03*
Y46914D03*
X314368Y54857D03*
X311021Y46914D03*
X334446D03*
X331100Y54857D03*
X354526D03*
X354525Y46922D03*
X351179Y54857D03*
X347833Y46922D03*
X344486D03*
Y54857D03*
X337793Y46914D03*
X341140Y54857D03*
X334447D03*
X317714Y84714D03*
Y73757D03*
Y46914D03*
X348978Y220809D03*
Y209109D03*
X352357Y211060D03*
X342218Y220809D03*
X338838Y211058D03*
X335458Y216909D03*
X355737Y209109D03*
Y220809D03*
X342218Y205210D03*
X345598Y207159D03*
X342218Y209109D03*
X348978Y205210D03*
Y216909D03*
X352357Y218860D03*
X345598D03*
X342218Y213009D03*
X338838Y214960D03*
X359117Y211060D03*
Y218860D03*
X355737Y216909D03*
Y213009D03*
X342218Y216909D03*
X335458Y220809D03*
X338838Y207158D03*
Y203258D03*
X345598Y211060D03*
X348978Y213009D03*
X352357Y238360D03*
X345598D03*
X338838Y230560D03*
X342218Y224709D03*
X345598Y230559D03*
X338838Y222760D03*
X352357D03*
X348978Y224709D03*
X355737D03*
X348978Y228610D03*
X352357Y230559D03*
X348978Y236409D03*
Y240309D03*
X352357Y234460D03*
X345598Y242260D03*
Y234460D03*
X342218Y240309D03*
Y228610D03*
Y236409D03*
X359117Y230559D03*
X355737Y228610D03*
Y236409D03*
X352357Y242260D03*
X355737Y240309D03*
X345598Y222760D03*
X408184Y32100D03*
X404723Y28022D03*
X401377Y35957D03*
X364565Y28014D03*
Y35942D03*
X361218Y28014D03*
Y35942D03*
X414762Y28021D03*
X398029Y28007D03*
X404723Y35957D03*
X414763D03*
X408069Y28007D03*
X394684Y35957D03*
X411415Y36058D03*
X371042Y46900D03*
X380792Y56500D03*
X408184Y51000D03*
Y69900D03*
X394492Y54700D03*
X404723Y65822D03*
X404722Y89964D03*
X401377Y73757D03*
X401375Y87392D03*
X414763Y65822D03*
X414761Y92757D03*
X398029Y65807D03*
Y89964D03*
X404723Y73757D03*
X404722Y84599D03*
X414763Y73757D03*
X414761Y87392D03*
X408069Y65807D03*
X408068Y92757D03*
X394682Y87392D03*
X404723Y54857D03*
X401377Y46922D03*
X364565Y54842D03*
X361218D03*
X414763Y54857D03*
X398029Y54842D03*
X404723Y46922D03*
X414763D03*
X408069Y54842D03*
X394682Y49592D03*
X380600Y37400D03*
X384992Y81600D03*
X411415Y84714D03*
X411416Y73757D03*
Y46922D03*
X394682Y68492D03*
X386292Y98800D03*
X401375Y103116D03*
X414819D03*
X408126D03*
X362497Y209109D03*
Y220809D03*
X369257D03*
X382777D03*
Y209109D03*
X376017Y220809D03*
Y209109D03*
X389537D03*
Y220809D03*
X396296Y209109D03*
Y220809D03*
X407706D03*
X372637Y207159D03*
X399676D03*
X372637Y211060D03*
X392916D03*
X389537Y213009D03*
X396296D03*
X369257D03*
X396296Y216909D03*
X376017D03*
X365877Y218860D03*
X372637D03*
X362497Y216909D03*
X382777Y213009D03*
X399676Y218860D03*
X386157Y211060D03*
X407706Y216909D03*
X379397Y207159D03*
X369257Y216909D03*
X382777D03*
X379397Y218860D03*
X392916D03*
X362497Y213009D03*
X386157Y218860D03*
X389537Y216909D03*
X376017Y213009D03*
X399676Y211060D03*
X379397Y238360D03*
X386157D03*
X389537Y248109D03*
X376017D03*
X382777D03*
X359117Y238360D03*
X365877D03*
X372637D03*
X392916D03*
X396296Y248109D03*
X407706D03*
X396296Y244209D03*
Y240309D03*
X376017Y224709D03*
X372637Y222760D03*
X365877D03*
X369257Y224709D03*
X362497D03*
X386157Y222760D03*
X396296Y228610D03*
X389537Y224709D03*
X399676Y222760D03*
X382777Y224709D03*
X379397Y222760D03*
X359117D03*
X392916D03*
X396296Y224709D03*
X379397Y230559D03*
X365877Y242260D03*
X407706Y236409D03*
X372637Y234460D03*
X365877D03*
X372637Y230559D03*
X365877D03*
X369257Y236409D03*
X362497D03*
X369257Y228610D03*
X362497D03*
X382777D03*
X389537Y236409D03*
X399676Y230559D03*
Y234460D03*
X382777Y236409D03*
X392916Y230559D03*
X407706Y224709D03*
Y228610D03*
X376017Y236409D03*
X369257Y240309D03*
X376017D03*
X386157Y230559D03*
X372637Y242260D03*
X379397Y234460D03*
X399676Y238360D03*
X359117Y242260D03*
X362497Y240309D03*
X359117Y234460D03*
X386157D03*
X392916D03*
X389537Y228610D03*
X396296Y236409D03*
X376017Y228610D03*
X399676Y242260D03*
X389537Y240309D03*
X382777D03*
X392916Y242260D03*
X386157D03*
X379397D03*
X389537Y244209D03*
X382777D03*
X376017D03*
X392916Y246160D03*
X386157D03*
X379397D03*
X372637D03*
X407706Y244209D03*
X399676Y246160D03*
X433508Y32100D03*
X421368D03*
X438189Y35957D03*
X431494Y28007D03*
X444880Y28022D03*
X444882Y35957D03*
X428149D03*
X421456Y28022D03*
X434842Y35957D03*
X424801Y28007D03*
X438189Y28022D03*
X421368Y51000D03*
X433508D03*
Y69900D03*
X421368D03*
X421455Y46921D03*
X421456Y73757D03*
X438187Y84714D03*
X438189Y73757D03*
X431494Y65807D03*
X444880Y65822D03*
X431494Y89964D03*
X444880D03*
Y84714D03*
X428147Y87392D03*
X428149Y73757D03*
X421456Y65822D03*
X421454Y92757D03*
X434842Y73757D03*
X434840Y87392D03*
X424801Y65807D03*
X438189Y65822D03*
X424801Y89964D03*
X438187D03*
X438189Y46922D03*
X431494Y54842D03*
X444880Y54859D03*
Y46922D03*
X428149D03*
X421456Y54857D03*
X434842Y46922D03*
X424801Y54842D03*
X438187Y54859D03*
X427696Y103100D03*
X421512Y103116D03*
X352357Y359260D03*
X338838D03*
X345598D03*
X355737Y376809D03*
Y388509D03*
X348978Y376809D03*
X342218Y388509D03*
Y376809D03*
X345598Y390460D03*
X352357Y386560D03*
X342218Y384609D03*
X341892Y396301D03*
X345598Y386560D03*
X348978Y388509D03*
X342218Y380709D03*
X351192Y402800D03*
X345598Y378760D03*
X348978Y380709D03*
X345598Y367060D03*
X348978Y372909D03*
X342218D03*
X338838Y374860D03*
Y370959D03*
Y378760D03*
X352357D03*
Y374860D03*
X359117Y386560D03*
X355737Y380709D03*
X359117Y374860D03*
X355737Y372909D03*
X348978Y369010D03*
X352357Y367060D03*
X355737Y384609D03*
X345598Y355360D03*
X348978Y357309D03*
Y361209D03*
X345598Y363160D03*
X342218Y357309D03*
Y369010D03*
Y361209D03*
X352357Y363160D03*
X359117D03*
X355737Y361209D03*
Y369010D03*
X352357Y355360D03*
X355737Y357309D03*
X348978Y384609D03*
X345598Y374860D03*
X338838Y363160D03*
X324187Y499793D03*
X321061Y518157D03*
Y529014D03*
X327754Y512792D03*
X324407Y529014D03*
Y515364D03*
Y509999D03*
X326922Y497170D03*
X314368Y518057D03*
X334447Y512792D03*
X331100Y529014D03*
Y515364D03*
X354525Y529022D03*
X354526Y518157D03*
X354307Y512792D03*
X351179Y515364D03*
Y529022D03*
X347833Y512792D03*
X344486Y510114D03*
Y529022D03*
Y515364D03*
X337793Y509999D03*
X341140Y529022D03*
Y518157D03*
X334446Y529014D03*
X334447Y518157D03*
X317714Y510114D03*
X321334Y533100D03*
X321123Y552000D03*
X321334Y570900D03*
X334292Y533100D03*
Y552000D03*
Y570900D03*
X327754Y536957D03*
X324407D03*
X311021D03*
X334447D03*
X354526D03*
X347833D03*
X344486D03*
X337793D03*
X321061Y566814D03*
Y555857D03*
X327754Y547914D03*
Y574757D03*
X324407Y555857D03*
Y566814D03*
Y547914D03*
Y574757D03*
X314368Y566814D03*
Y555857D03*
X311021Y547914D03*
X334446D03*
X334447Y574757D03*
X331100Y555857D03*
Y566814D03*
X354526Y555857D03*
X354525Y566822D03*
Y547922D03*
X354526Y574757D03*
X351179Y555857D03*
Y566822D03*
X347833Y547922D03*
Y574757D03*
X344486Y547922D03*
Y574757D03*
Y566822D03*
Y555857D03*
X337793Y547914D03*
Y574757D03*
X341140Y555857D03*
Y566822D03*
X334447Y555857D03*
X334446Y566814D03*
X317714Y536957D03*
Y547914D03*
Y574757D03*
X388407Y345160D03*
X395166D03*
X401926D03*
X379397Y359260D03*
X386157Y351460D03*
Y359260D03*
X389537Y353409D03*
X372637Y359260D03*
X365877D03*
X359117D03*
X376017Y376809D03*
X369257D03*
X382777Y388509D03*
X369257D03*
X362497D03*
X376017D03*
X389537D03*
Y376809D03*
X382777D03*
X362497D03*
X396296Y353409D03*
X405306Y347109D03*
X399676Y351460D03*
X392916D03*
Y359260D03*
X396296Y388509D03*
Y376809D03*
X411086Y374860D03*
X403056Y376809D03*
Y388509D03*
X392916Y355360D03*
X396296Y357309D03*
X389537D03*
X372637Y390460D03*
X396296Y384609D03*
X372637Y386560D03*
X392916D03*
X389537Y384609D03*
X399676Y390460D03*
X376017Y372909D03*
X369257Y384609D03*
X396296Y380709D03*
X369257Y372909D03*
X362497D03*
X372637Y378760D03*
X362497Y380709D03*
X372637Y374860D03*
X365877D03*
X376017Y380709D03*
X365877Y378760D03*
X382777Y384609D03*
X386157Y374860D03*
X399676Y378760D03*
X396296Y369010D03*
X386157Y386560D03*
X389537Y372909D03*
X403056Y380709D03*
X399676Y374860D03*
X379397Y386560D03*
X369257Y380709D03*
X382777D03*
Y372909D03*
X379397Y378760D03*
Y374860D03*
X392916Y378760D03*
X362497Y384609D03*
X359117Y378760D03*
X386157D03*
X392916Y374860D03*
X389537Y380709D03*
X396296Y372909D03*
X376017Y384609D03*
X379397Y367060D03*
X365877Y355360D03*
X403056Y361209D03*
X369257Y369010D03*
X362497D03*
X369257Y361209D03*
X362497D03*
X372637Y367060D03*
X365877D03*
X372637Y363160D03*
X365877D03*
X382777Y369010D03*
X389537Y361209D03*
X399676Y367060D03*
Y363160D03*
X382777Y361209D03*
X392916Y367060D03*
X403056Y372909D03*
Y369010D03*
X376017Y361209D03*
X369257Y357309D03*
X376017D03*
X386157Y367060D03*
X372637Y355360D03*
X379397Y363160D03*
X399676Y359260D03*
X359117Y355360D03*
X362497Y357309D03*
X359117Y367060D03*
X386157Y363160D03*
X392916D03*
X389537Y369010D03*
X396296Y361209D03*
X376017Y369010D03*
X391787Y347109D03*
X398546D03*
X399676Y355360D03*
X382777Y353409D03*
X386157Y355360D03*
X403056Y396309D03*
X411086Y394359D03*
Y390460D03*
X399676Y386560D03*
X411086D03*
Y382660D03*
Y378760D03*
X398546Y402900D03*
X382777Y357309D03*
X379397Y355360D03*
X402892Y400400D03*
X385244Y504027D03*
X363760Y529293D03*
X404723Y529022D03*
X404722Y515364D03*
X401375Y512792D03*
X414761Y518157D03*
X398029Y529007D03*
Y515364D03*
X404722Y509999D03*
X414761Y512792D03*
X408068Y518157D03*
X408069Y529007D03*
X394682Y512792D03*
X411415Y510114D03*
X394587Y529026D03*
X376785Y538305D03*
X408184Y533100D03*
Y552000D03*
Y570900D03*
X401377Y536957D03*
X404723D03*
X414763D03*
X394595Y537058D03*
X404723Y566822D03*
Y555857D03*
X401376Y547922D03*
X401377Y574757D03*
X364565Y566814D03*
Y555842D03*
Y574742D03*
X361218Y566814D03*
X361320Y555842D03*
X361218Y574742D03*
X414763Y566822D03*
Y555857D03*
X398029Y566807D03*
Y555842D03*
X404723Y547922D03*
Y574757D03*
X414763D03*
Y547922D03*
X408069Y566807D03*
Y555842D03*
X394682Y550592D03*
X394684Y574757D03*
X411416Y536957D03*
X411415Y547921D03*
X411416Y574757D03*
X394682Y569492D03*
X438187Y510114D03*
X435192Y499400D03*
X431494Y515364D03*
X444880D03*
Y510114D03*
X428147Y512792D03*
X421456Y529022D03*
X421454Y518157D03*
X434840Y512792D03*
X424801Y515364D03*
X438187D03*
X421368Y533100D03*
X434395Y532904D03*
X433508Y552000D03*
X421368D03*
X433508Y570900D03*
X421368D03*
X421456Y547922D03*
X438189Y536957D03*
X444882D03*
X428149D03*
X434842D03*
X438189Y547922D03*
Y574757D03*
X431494Y566807D03*
X444880Y566822D03*
X444882Y574757D03*
X431494Y555842D03*
X444880Y555859D03*
Y547922D03*
X428149D03*
Y574757D03*
X421456Y555857D03*
Y566822D03*
X434842Y547922D03*
Y574757D03*
X424801Y566807D03*
X438189Y566822D03*
X424801Y555842D03*
X438187Y555859D03*
X970942Y32100D03*
X970669Y28014D03*
X974015D03*
Y35957D03*
X963976Y28014D03*
X960629Y35957D03*
X967322D03*
X970800Y50860D03*
X970942Y69900D03*
X970669Y65814D03*
Y92757D03*
X974015Y65814D03*
Y89964D03*
Y84599D03*
Y73757D03*
X963976Y65814D03*
Y92657D03*
X960629Y84714D03*
X970669Y54857D03*
X974015D03*
Y46914D03*
X963976Y54857D03*
X960629Y46914D03*
X967322Y73757D03*
Y84714D03*
Y46914D03*
X983900Y32100D03*
X977362Y35957D03*
X1014173Y28014D03*
Y35942D03*
X1010826Y28014D03*
Y35942D03*
X984055Y35957D03*
X980708Y28014D03*
X1004133Y28022D03*
X1004134Y35957D03*
X1000787Y28022D03*
X997441Y35957D03*
X994094D03*
Y28022D03*
X987401Y35957D03*
X990748Y28022D03*
X984054Y28014D03*
X983900Y51000D03*
Y69900D03*
X1014350Y73000D03*
X1030400Y56500D03*
X1031600Y42900D03*
X977362Y73757D03*
Y87392D03*
X984055D03*
Y73757D03*
X980708Y65814D03*
Y89964D03*
X1004133Y65822D03*
X1004023Y92757D03*
X1004134Y73757D03*
X1004023Y87392D03*
X1000787Y65822D03*
Y89964D03*
X997441Y73757D03*
Y87392D03*
X994094Y84714D03*
Y73757D03*
Y65822D03*
Y89964D03*
X987401Y84599D03*
Y73757D03*
X990748Y65822D03*
Y92757D03*
X984054Y65814D03*
X984055Y92757D03*
X977362Y46914D03*
X1014173Y54842D03*
X1010826D03*
X984054Y46914D03*
X980708Y54857D03*
X1004134D03*
X1004133Y46922D03*
X1000787Y54857D03*
X997441Y46922D03*
X994094D03*
Y54857D03*
X987401Y46914D03*
X990748Y54857D03*
X984055D03*
X1020650Y46900D03*
X1030300Y63200D03*
X1035900Y98800D03*
X998586Y209109D03*
Y220809D03*
X991826D03*
X985066Y216909D03*
X988446Y211058D03*
X1005345Y209109D03*
Y220809D03*
X1001965Y211060D03*
X1025625Y209109D03*
Y220809D03*
X1012105D03*
Y209109D03*
X1018865Y220809D03*
X1032385D03*
Y209109D03*
X1022245Y207159D03*
X991826Y205210D03*
X1022245Y211060D03*
X995206Y207159D03*
X991826Y209109D03*
X998586Y205210D03*
X1018865Y213009D03*
X998586Y216909D03*
X1001965Y218860D03*
X995206D03*
X991826Y213009D03*
X988446Y214960D03*
X1025625Y216909D03*
X1015485Y218860D03*
X1022245D03*
X1012105Y216909D03*
X1032385Y213009D03*
X1035765Y211060D03*
X1029005Y207159D03*
X1018865Y216909D03*
X1032385D03*
X1029005Y218860D03*
X1008725Y211060D03*
X1012105Y213009D03*
X1008725Y218860D03*
X1005345Y216909D03*
Y213009D03*
X1035765Y218860D03*
X1025625Y213009D03*
X991826Y216909D03*
X985066Y220809D03*
X988446Y207158D03*
Y203258D03*
X995206Y211060D03*
X998586Y213009D03*
X995206Y238360D03*
X1029005D03*
X1008725D03*
X1001965D03*
X1035765D03*
X1032385Y248109D03*
X1025625D03*
X1015485Y238360D03*
X1022245D03*
X988446Y230560D03*
X991826Y224709D03*
X995206Y230559D03*
X1025625Y224709D03*
X988446Y222760D03*
X1022245D03*
X1015485D03*
X1018865Y224709D03*
X1012105D03*
X1035765Y222760D03*
X1001965D03*
X998586Y224709D03*
X1032385D03*
X1029005Y222760D03*
X1008725D03*
X1005345Y224709D03*
X998586Y228610D03*
X1001965Y230559D03*
X998586Y236409D03*
Y240309D03*
X1029005Y230559D03*
X1015485Y242260D03*
X1001965Y234460D03*
X995206Y242260D03*
Y234460D03*
X991826Y240309D03*
Y228610D03*
Y236409D03*
X1022245Y234460D03*
X1015485D03*
X1022245Y230559D03*
X1015485D03*
X1018865Y236409D03*
X1012105D03*
X1018865Y228610D03*
X1012105D03*
X1032385D03*
Y236409D03*
X1025625D03*
X1018865Y240309D03*
X1025625D03*
X1035765Y230559D03*
X1022245Y242260D03*
X1029005Y234460D03*
X1008725Y242260D03*
X1012105Y240309D03*
X1008725Y230559D03*
Y234460D03*
X1005345Y228610D03*
Y236409D03*
X1001965Y242260D03*
X1005345Y240309D03*
X1035765Y234460D03*
X1025625Y228610D03*
X995206Y222760D03*
X1032385Y240309D03*
X1035765Y242260D03*
X1029005D03*
X1032385Y244209D03*
X1025625D03*
X1035765Y246160D03*
X1029005D03*
X1022245D03*
X1057792Y32100D03*
X1083116D03*
X1070976D03*
X1054331Y28022D03*
X1050985Y35957D03*
X1087797D03*
X1064371Y28022D03*
X1081102Y28007D03*
X1094488Y28022D03*
X1094490Y35957D03*
X1047637Y28007D03*
X1054331Y35957D03*
X1077757D03*
X1064371D03*
X1071064Y28022D03*
X1057677Y28007D03*
X1084450Y35957D03*
X1074409Y28007D03*
X1087797Y28022D03*
X1044292Y35957D03*
X1061024D03*
X1057792Y51000D03*
Y69900D03*
X1083116Y51000D03*
X1070976D03*
X1083116Y69900D03*
X1070976D03*
X1044100Y54700D03*
X1071064Y46922D03*
Y73757D03*
X1054331Y65822D03*
X1054330Y89964D03*
X1050985Y73757D03*
X1050983Y87392D03*
X1087797Y73757D03*
X1087795Y84714D03*
X1064371Y65822D03*
X1081102Y65807D03*
X1094488Y65822D03*
X1064369Y92757D03*
X1081102Y89964D03*
X1094488D03*
Y84714D03*
X1047637Y65807D03*
Y89964D03*
X1054331Y73757D03*
X1054330Y84599D03*
X1077755Y87392D03*
X1077757Y73757D03*
X1064371D03*
X1064369Y87392D03*
X1071064Y65822D03*
X1071062Y92757D03*
X1057677Y65807D03*
X1057676Y92757D03*
X1084448Y87392D03*
X1084450Y73757D03*
X1074409Y65807D03*
X1087797Y65822D03*
X1074409Y89964D03*
X1087795D03*
X1044290Y87392D03*
X1054331Y54857D03*
X1050985Y46922D03*
X1087797D03*
X1064371Y54857D03*
X1081102Y54842D03*
X1094488Y54859D03*
Y46922D03*
X1047637Y54842D03*
X1054331Y46922D03*
X1077757D03*
X1064371D03*
X1071064Y54857D03*
X1057677Y54842D03*
X1084450Y46922D03*
X1074409Y54842D03*
X1087795Y54859D03*
X1044290Y49592D03*
X1061024Y73757D03*
X1061023Y84714D03*
X1061024Y46922D03*
X1044290Y68964D03*
X1050983Y103116D03*
X1064427D03*
X1077304Y103100D03*
X1057734Y103116D03*
X1071120D03*
X1045904Y220809D03*
X1057314D03*
X1045904Y209109D03*
X1039145D03*
Y220809D03*
X1049284Y207159D03*
X1042524Y211060D03*
X1039145Y213009D03*
X1045904D03*
Y216909D03*
X1049284Y218860D03*
X1057314Y216909D03*
X1042524Y218860D03*
X1039145Y216909D03*
X1049284Y211060D03*
X1057314Y248109D03*
X1039145D03*
X1045904D03*
X1042524Y238360D03*
X1045904Y244209D03*
Y240309D03*
Y228610D03*
X1039145Y224709D03*
X1049284Y222760D03*
X1042524D03*
X1045904Y224709D03*
X1057314Y236409D03*
X1039145D03*
X1049284Y230559D03*
Y234460D03*
X1042524Y230559D03*
X1057314Y224709D03*
Y228610D03*
X1049284Y238360D03*
X1042524Y234460D03*
X1039145Y228610D03*
X1045904Y236409D03*
X1049284Y242260D03*
X1039145Y240309D03*
X1042524Y242260D03*
X1039145Y244209D03*
X1042524Y246160D03*
X1057314Y244209D03*
X1049284Y246160D03*
X973795Y499793D03*
X970669Y529014D03*
Y518157D03*
X974015Y515364D03*
Y529014D03*
Y509999D03*
X963976Y518057D03*
X960629Y510114D03*
X967322D03*
X970942Y533100D03*
X970731Y552000D03*
X970942Y570900D03*
X974015Y536957D03*
X960629D03*
X970669Y555857D03*
Y566814D03*
X974015Y555857D03*
Y566814D03*
Y547914D03*
Y574757D03*
X963976Y566814D03*
X960629Y574757D03*
X963976Y555857D03*
X960629Y547914D03*
X967322Y536957D03*
Y574757D03*
Y547914D03*
X995206Y359260D03*
X998586Y376809D03*
X991826Y388509D03*
X995206Y390460D03*
X991826Y376809D03*
X1001965Y359260D03*
X1008725D03*
X1015485D03*
X1022245D03*
X1029005D03*
X1032385Y388509D03*
Y376809D03*
X1005345D03*
Y388509D03*
X1001965Y386560D03*
X1025625Y376809D03*
Y388509D03*
X1018865Y376809D03*
X1012105D03*
X1018865Y388509D03*
X1012105D03*
X991826Y384609D03*
X991500Y396301D03*
X1022245Y390460D03*
X995206Y386560D03*
X1022245D03*
X998586Y388509D03*
X991826Y380709D03*
X1000800Y402800D03*
X995206Y378760D03*
X998586Y380709D03*
X1025625Y372909D03*
X1018865Y384609D03*
X995206Y367060D03*
X998586Y372909D03*
X991826D03*
X988446Y374860D03*
Y370959D03*
Y378760D03*
X1018865Y372909D03*
X1012105D03*
X1022245Y378760D03*
X1012105Y380709D03*
X1022245Y374860D03*
X1015485D03*
X1025625Y380709D03*
X1015485Y378760D03*
X1032385Y384609D03*
X1035765Y374860D03*
Y386560D03*
X1029005D03*
X1018865Y380709D03*
X1001965Y378760D03*
Y374860D03*
X1032385Y380709D03*
Y372909D03*
X1029005Y378760D03*
Y374860D03*
X1008725Y386560D03*
X1012105Y384609D03*
X1008725Y378760D03*
X1005345Y380709D03*
X1008725Y374860D03*
X1005345Y372909D03*
X998586Y369010D03*
X1001965Y367060D03*
X1005345Y384609D03*
X1035765Y378760D03*
X1025625Y384609D03*
X995206Y355360D03*
X998586Y357309D03*
X1029005Y367060D03*
X1015485Y355360D03*
X998586Y361209D03*
X995206Y363160D03*
X991826Y369010D03*
X1018865D03*
X1012105D03*
X1018865Y361209D03*
X1012105D03*
X1022245Y367060D03*
X1015485D03*
X1022245Y363160D03*
X1015485D03*
X1032385Y369010D03*
X1025625Y361209D03*
X1018865Y357309D03*
X1001965Y363160D03*
X1025625Y357309D03*
X1035765Y367060D03*
X1022245Y355360D03*
X1029005Y363160D03*
X1008725Y355360D03*
X1012105Y357309D03*
X1008725Y363160D03*
Y367060D03*
X1005345Y361209D03*
Y369010D03*
X1001965Y355360D03*
X1005345Y357309D03*
X1025625Y369010D03*
X998586Y384609D03*
X995206Y374860D03*
X1013500Y529200D03*
X1034200Y506956D03*
X1035750Y503006D03*
X977362Y512792D03*
X976530Y497170D03*
X984055Y512792D03*
X980708Y529014D03*
Y515364D03*
X1004133Y529022D03*
X1004134Y518157D03*
X1003915Y512792D03*
X1000787Y515364D03*
Y529022D03*
X997441Y512792D03*
X994094Y510114D03*
Y529022D03*
Y515364D03*
X987401Y509999D03*
X990748Y529022D03*
Y518157D03*
X984055D03*
X984054Y529014D03*
X983900Y533100D03*
Y552000D03*
Y570900D03*
X977362Y536957D03*
X984055D03*
X1004134D03*
X997441D03*
X994094D03*
X987401D03*
X977362Y547914D03*
Y574757D03*
X1014173Y566814D03*
Y555842D03*
Y574742D03*
X1010826Y566814D03*
X1010928Y555842D03*
X1010826Y574742D03*
X984054Y547914D03*
X984055Y574757D03*
X980708Y555857D03*
Y566814D03*
X1004134Y555857D03*
X1004133Y566822D03*
Y547922D03*
X1004134Y574757D03*
X1000787Y555857D03*
Y566822D03*
X997441Y547922D03*
Y574757D03*
X994094Y547922D03*
Y574757D03*
Y555857D03*
Y566822D03*
X987401Y547914D03*
Y574757D03*
X990748Y555857D03*
Y566822D03*
X984055Y555857D03*
X984054Y566814D03*
X1019800Y555800D03*
X1039145Y388509D03*
X1045904D03*
X1052664D03*
X1039145Y376809D03*
X1045904D03*
X1052664D03*
X1045904Y384609D03*
X1042524Y386560D03*
X1039145Y384609D03*
X1049284Y390460D03*
X1045904Y380709D03*
X1049284Y378760D03*
X1045904Y369010D03*
X1039145Y372909D03*
X1052664Y380709D03*
X1049284Y374860D03*
X1042524Y378760D03*
Y374860D03*
X1039145Y380709D03*
X1045904Y372909D03*
X1049284Y367060D03*
X1042524D03*
X1052664Y372909D03*
Y369010D03*
X1039145D03*
X1052664Y396309D03*
X1049284Y386560D03*
X1048154Y402900D03*
X1052500Y400400D03*
X1054331Y529022D03*
X1054330Y515364D03*
X1050983Y512792D03*
X1087795Y510114D03*
X1084800Y499400D03*
X1064369Y518157D03*
X1081102Y515364D03*
X1094488D03*
Y510114D03*
X1047637Y529007D03*
Y515364D03*
X1054330Y509999D03*
X1077755Y512792D03*
X1064369D03*
X1071062Y518157D03*
X1071064Y529022D03*
X1057677Y529007D03*
X1057676Y518157D03*
X1084448Y512792D03*
X1074409Y515364D03*
X1087795D03*
X1044290Y512792D03*
X1061023Y510114D03*
X1044195Y529026D03*
X1057792Y552000D03*
Y533100D03*
Y570900D03*
X1070976Y552000D03*
Y533100D03*
X1084003Y532904D03*
X1083116Y552000D03*
X1070976Y570900D03*
X1083116D03*
X1071064Y547922D03*
X1050985Y536957D03*
X1087797D03*
X1094490D03*
X1054331D03*
X1077757D03*
X1064371D03*
X1084450D03*
X1044203Y537058D03*
X1054331Y555857D03*
Y566822D03*
X1050984Y547922D03*
X1050985Y574757D03*
X1087797Y547922D03*
Y574757D03*
X1064371Y566822D03*
X1081102Y566807D03*
X1094488Y566822D03*
X1094490Y574757D03*
X1064371Y555857D03*
X1081102Y555842D03*
X1094488Y555859D03*
Y547922D03*
X1047637Y555842D03*
Y566807D03*
X1054331Y547922D03*
Y574757D03*
X1077757Y547922D03*
Y574757D03*
X1064371Y547922D03*
Y574757D03*
X1071064Y555857D03*
Y566822D03*
X1057677Y555842D03*
Y566807D03*
X1084450Y547922D03*
Y574757D03*
X1074409Y566807D03*
X1087797Y566822D03*
X1074409Y555842D03*
X1087795Y555859D03*
X1044290Y550592D03*
X1044292Y574757D03*
X1061024Y536957D03*
Y574757D03*
Y547922D03*
X1044290Y569492D03*
%LPD*%
G75*
G54D10*
X-17936Y-49379D03*
Y-53779D03*
Y-44979D03*
Y-40579D03*
X-18079Y-35764D03*
Y-58764D03*
X-14186Y196989D03*
Y199989D03*
X-14839Y445588D03*
X-14753Y448601D03*
X-17179Y643156D03*
X-17194Y638753D03*
X-17179Y647556D03*
Y660756D03*
Y651956D03*
Y656356D03*
X-13636Y-40479D03*
Y-44879D03*
Y-53679D03*
X-9079Y-50164D03*
X-4679D03*
X-279D03*
X-9079Y-54264D03*
X-4679D03*
X-279D03*
X22964Y-40379D03*
Y-44779D03*
Y-53579D03*
Y-49179D03*
X18964Y-53579D03*
Y-49179D03*
X13964Y-53579D03*
Y-49179D03*
X8964Y-40379D03*
Y-44779D03*
Y-53579D03*
Y-49179D03*
X3964Y-40379D03*
Y-44779D03*
Y-53579D03*
Y-49179D03*
X25921Y-35764D03*
X30321D03*
X43521D03*
X39121D03*
X34721D03*
X8321D03*
X12721D03*
X21521D03*
X17121D03*
X-13679D03*
X-9279D03*
X3921D03*
X-4879D03*
X-479D03*
X17121Y-58764D03*
X21521D03*
X12721D03*
X8321D03*
X34721D03*
X39121D03*
X43521D03*
X30321D03*
X25921D03*
X-479D03*
X-13679D03*
X-4879D03*
X3921D03*
X-13636Y-49279D03*
X-9279Y-58764D03*
X875Y211336D03*
X6074Y211293D03*
X3474Y211263D03*
X875Y208352D03*
X36200Y208600D03*
X33200D03*
X20700D03*
X17700Y211600D03*
X20700D03*
X17700Y208600D03*
X23700Y211600D03*
Y208600D03*
X33200Y211600D03*
X30200D03*
Y208600D03*
X36200Y211600D03*
X6074Y208321D03*
X3474Y208263D03*
X5500Y218500D03*
X-5300Y200191D03*
X-7900D03*
X-2700Y200202D03*
X-11586Y196989D03*
Y199989D03*
X-2600Y232300D03*
X-5246Y232351D03*
X-7846D03*
X20500Y221000D03*
Y224000D03*
X17500Y221000D03*
Y224000D03*
X23500D03*
Y221000D03*
X33300Y224000D03*
Y221000D03*
X30300D03*
Y224000D03*
X36300D03*
Y221000D03*
X-14129Y235221D03*
X-11484Y235215D03*
Y232215D03*
X-14084D03*
X2678Y221018D03*
X5277Y221110D03*
X5173Y224042D03*
X2574Y223963D03*
X-26Y223982D03*
X-11652Y445530D03*
Y448530D03*
X22421Y647556D03*
X26821D03*
X31221D03*
X18021D03*
Y643156D03*
X31221D03*
X26821D03*
X22421D03*
X18006Y638753D03*
X9221Y647556D03*
X13621D03*
Y643156D03*
X9221D03*
X4821D03*
Y647556D03*
X22406Y638753D03*
X26806D03*
X31206D03*
X-12794D03*
X-12779Y647556D03*
Y643156D03*
X40006Y638753D03*
X44406D03*
X35606D03*
X35621Y647556D03*
Y643156D03*
X-9599Y610630D03*
X-3301Y619643D03*
Y601615D03*
X4549Y620682D03*
X4548Y600577D03*
X13801Y624130D03*
Y597130D03*
X23360Y620172D03*
X23352Y601079D03*
X27301Y610630D03*
X18021Y660756D03*
X35621Y656356D03*
X26821Y660756D03*
X18021Y651956D03*
X31221D03*
X22421Y660756D03*
X26821Y651956D03*
X22421D03*
X4821D03*
X13621D03*
X9221D03*
X-8379Y660756D03*
X4821Y656356D03*
X9221D03*
X13621D03*
X-3979D03*
X421D03*
X13621Y660756D03*
X-3979D03*
X421D03*
X4821D03*
X-12779Y651956D03*
X22421Y656356D03*
X26821D03*
X31221D03*
X18021D03*
X-8379D03*
X-12779D03*
X31221Y660756D03*
X35621Y651956D03*
Y660756D03*
X44421D03*
X40021D03*
X-12779D03*
X9221D03*
X107921Y-58764D03*
X102921D03*
X97921D03*
X92921D03*
X87921D03*
X82921D03*
X77921D03*
X72921D03*
X67921D03*
X62921D03*
X57921D03*
X52921D03*
X47921Y-35764D03*
Y-58764D03*
X107921Y-35764D03*
X102921D03*
X97921D03*
X92921D03*
X87921D03*
X82921D03*
X77921D03*
X72921D03*
X67921D03*
X62921D03*
X57921D03*
X52921D03*
X96249Y204722D03*
X64700Y210100D03*
Y212800D03*
X64778Y218062D03*
X58000Y206500D03*
X56900Y197800D03*
X93870Y199131D03*
X97730Y188584D03*
X58200Y230400D03*
Y233400D03*
X55600Y230400D03*
X53000Y230300D03*
Y233300D03*
X55600Y233400D03*
X58200Y227400D03*
X53000Y227300D03*
X55600Y227400D03*
X58200Y239400D03*
X53000Y239300D03*
X55600Y239400D03*
X58200Y236400D03*
X55600D03*
X53000Y236300D03*
X71500Y263300D03*
X68800D03*
X53004Y244632D03*
X55275Y245900D03*
X57875D03*
X57457Y248537D03*
Y251237D03*
X57600Y262800D03*
X57500Y260200D03*
X62800Y265500D03*
X71500Y266000D03*
X65500Y265500D03*
X68800Y266000D03*
X60000Y265500D03*
X76540Y397355D03*
X81900Y398300D03*
X79140Y397355D03*
X98149Y399769D03*
X102456Y393756D03*
X76052Y420935D03*
X78000Y423100D03*
X80100Y425000D03*
X81500Y427400D03*
X79700Y409700D03*
X77400Y407800D03*
X81500Y412100D03*
X84913Y434471D03*
X87013Y436371D03*
X107571Y406291D03*
X48806Y638753D03*
X75206D03*
X106006D03*
X70806D03*
X53206D03*
X66406D03*
X92806D03*
X97206D03*
X101606D03*
X57606D03*
X62006D03*
X79606D03*
X84006D03*
X88406D03*
X53221Y660756D03*
X101621D03*
X97221D03*
X92821D03*
X106021D03*
X48821D03*
X70821D03*
X66421D03*
X62021D03*
X57621D03*
X75221D03*
X88421D03*
X84021D03*
X79621D03*
X167921Y-58764D03*
X162921D03*
X157921D03*
X152921D03*
X147921D03*
X142921D03*
X137921D03*
X132921D03*
X127921D03*
X122921D03*
X117921D03*
X112921D03*
X162921Y-35764D03*
X157921D03*
X152921D03*
X147921D03*
X142921D03*
X137921D03*
X132921D03*
X127921D03*
X122921D03*
X117921D03*
X112921D03*
X167921D03*
X166000Y212900D03*
X168600D03*
X164300Y207870D03*
X160800Y212900D03*
X163400D03*
X157800Y207300D03*
X161216Y209533D03*
Y206933D03*
X154500Y205500D03*
X150600Y212900D03*
X151000Y205500D03*
X140889Y211972D03*
X137615Y212039D03*
X143900Y204600D03*
X147500Y205500D03*
X137300Y204500D03*
X140200Y204400D03*
X153200Y212900D03*
X122044Y162340D03*
X139815Y268974D03*
X137900Y272800D03*
X139800Y237000D03*
X165825Y239543D03*
X168425Y236943D03*
Y239543D03*
X165825Y236943D03*
X163225D03*
X152825D03*
X145025D03*
X147625D03*
X150225D03*
X142425D03*
X163225Y239543D03*
X158025Y236943D03*
X155425D03*
X160625D03*
X142371Y244384D03*
X142466Y268982D03*
X142700Y276200D03*
X136729Y276386D03*
X139683Y276174D03*
X163225Y242143D03*
X168425Y244743D03*
X165825D03*
X163225D03*
X168425Y242143D03*
X165825D03*
X150700Y276800D03*
X169150Y259470D03*
Y255470D03*
X157633Y268727D03*
X162833D03*
X160233D03*
X165433D03*
X168033Y271327D03*
X162833Y276527D03*
Y273927D03*
Y271327D03*
X165433Y276527D03*
Y273927D03*
Y271327D03*
X159983Y276507D03*
X168033Y276527D03*
Y273927D03*
Y268727D03*
X153300Y276800D03*
X139866Y333016D03*
X160233Y306257D03*
Y308857D03*
Y303657D03*
X157518Y335391D03*
X157745Y332800D03*
X139900Y302400D03*
X142433Y301057D03*
X147633D03*
X150233D03*
X145033D03*
X145200Y341300D03*
X148200D03*
X142465Y332940D03*
X152833Y301057D03*
X163233Y306257D03*
Y308857D03*
X168433Y306257D03*
Y308857D03*
Y301057D03*
X165833D03*
X163233D03*
X160633D03*
X158033D03*
X155433D03*
X169150Y287600D03*
Y291600D03*
X165833Y306257D03*
X163233Y303657D03*
X168433D03*
X165833D03*
Y308857D03*
X151000Y341300D03*
X169150Y323600D03*
Y319600D03*
X160501Y332965D03*
X160274Y335556D03*
X165701Y338165D03*
Y335565D03*
X163101Y332965D03*
X168301D03*
X165701D03*
X163101Y335565D03*
X168301Y340765D03*
Y338165D03*
Y335565D03*
X163101Y338165D03*
Y340765D03*
X165701D03*
X154200Y341100D03*
X139767Y364883D03*
X147833Y364457D03*
X142421Y364908D03*
X145033Y364457D03*
X142863Y402829D03*
X140219Y402894D03*
X137619Y402900D03*
X134992D03*
X142818Y400163D03*
X143073Y397194D03*
X140475Y397310D03*
X140218Y400163D03*
X137529Y400296D03*
X134929D03*
X114084Y399937D03*
X122840Y400827D03*
X150633Y364457D03*
X167433Y369657D03*
X169150Y355600D03*
Y351600D03*
X167700Y363900D03*
X161833Y364457D03*
X164633D03*
X159033D03*
X156233D03*
X153433D03*
X164633Y369657D03*
X161833D03*
X161933Y372357D03*
X164733D03*
X167533D03*
X166340Y374785D03*
X167670Y383993D03*
Y387993D03*
X130613Y429647D03*
X123648Y425041D03*
X125328Y427269D03*
X127932Y428571D03*
X110519Y410307D03*
X110199Y413852D03*
X110406Y638753D03*
X145606D03*
X141206D03*
X136806D03*
X132406D03*
X158806D03*
X119206D03*
X123606D03*
X114806D03*
X128006D03*
X163206D03*
X154406D03*
X167606D03*
X150006D03*
X132421Y660756D03*
X145621D03*
X141221D03*
X136821D03*
X123621D03*
X114821D03*
X128021D03*
X110421D03*
X119221D03*
X150021D03*
X167621D03*
X163221D03*
X158821D03*
X154421D03*
X182921Y-58764D03*
X177921D03*
X172921D03*
X227921Y-35764D03*
X222921D03*
X217921D03*
X212921D03*
X207921D03*
X202921D03*
X197921D03*
X192921D03*
X187921D03*
X182921D03*
X177921D03*
X227921Y-58764D03*
X222921D03*
X217921D03*
X212921D03*
X207921D03*
X202921D03*
X197921D03*
X192921D03*
X187921D03*
X172921Y-35764D03*
X211606Y638753D03*
X224806D03*
X220406D03*
X216006D03*
X189606D03*
X198406D03*
X202806D03*
X207206D03*
X176406D03*
X172006D03*
X185206D03*
X180806D03*
X194006D03*
X226500Y649900D03*
X229206Y638753D03*
X224821Y660756D03*
X220421D03*
X198421D03*
X211621D03*
X189621D03*
X202821D03*
X207221D03*
X194021D03*
X185221D03*
X172021D03*
X176421D03*
X180821D03*
X229221D03*
X216021D03*
X292921Y-35764D03*
X287921D03*
X282921D03*
X277921D03*
X272921D03*
X267921D03*
X262921D03*
X257921D03*
X252921D03*
X247921D03*
X242921D03*
X237921D03*
X232921D03*
X292921Y-58764D03*
X287921D03*
X282921D03*
X277921D03*
X272921D03*
X267921D03*
X262921D03*
X257921D03*
X252921D03*
X247921D03*
X242921D03*
X237921D03*
X232921D03*
X290806Y638753D03*
X268806D03*
X273206D03*
X277606D03*
X282006D03*
X260006D03*
X264406D03*
X255606D03*
X251206D03*
X286406D03*
X242406D03*
X246806D03*
X233606D03*
X238006D03*
X286421Y660756D03*
X268821D03*
X282021D03*
X273221D03*
X277621D03*
X264421D03*
X251221D03*
X255621D03*
X260021D03*
X246821D03*
X242421D03*
X238021D03*
X233621D03*
X290821D03*
X352921Y-58764D03*
Y-35764D03*
X347921Y-58764D03*
Y-35764D03*
X342921Y-58764D03*
Y-35764D03*
X337921Y-58764D03*
Y-35764D03*
X332921Y-58764D03*
Y-35764D03*
X327921Y-58764D03*
Y-35764D03*
X322921Y-58764D03*
Y-35764D03*
X317921Y-58764D03*
Y-35764D03*
X312921Y-58764D03*
X307921D03*
Y-35764D03*
X302921Y-58764D03*
Y-35764D03*
X297921D03*
Y-58764D03*
X312921Y-35764D03*
X330406Y638753D03*
X348006D03*
X326006D03*
X312806D03*
X317206D03*
X321606D03*
X352406D03*
X295206D03*
X299606D03*
X308406D03*
X304006D03*
X334806D03*
X339206D03*
X343606D03*
X312821Y660756D03*
X317221D03*
X308421D03*
X304021D03*
X352421D03*
X295221D03*
X326021D03*
X321621D03*
X339221D03*
X299621D03*
X334821D03*
X330421D03*
X343621D03*
X348021D03*
X392921Y-35764D03*
X387921Y-58764D03*
Y-35764D03*
X382921Y-58764D03*
Y-35764D03*
X377921Y-58764D03*
Y-35764D03*
X372921Y-58764D03*
Y-35764D03*
X367921Y-58764D03*
Y-35764D03*
X362921Y-58764D03*
Y-35764D03*
X357921Y-58764D03*
Y-35764D03*
X392921Y-58764D03*
X402921Y-35764D03*
X397921Y-58764D03*
Y-35764D03*
X412921Y-58764D03*
Y-35764D03*
X407921Y-58764D03*
Y-35764D03*
X402921Y-58764D03*
X380885Y273876D03*
Y270876D03*
X382494Y278904D03*
X371094D03*
X378294D03*
X375294D03*
X368094D03*
X389694D03*
X392694D03*
X385945Y278480D03*
X407094Y278910D03*
X414207D03*
X411288D03*
X404094D03*
X400842Y278914D03*
X368094Y295904D03*
X371094D03*
X385494D03*
X375294D03*
X378294D03*
X382494D03*
X389694D03*
X392694D03*
X365693Y311893D03*
X391144Y324173D03*
X388394D03*
X385494D03*
X411294Y295904D03*
X414294D03*
X407094D03*
X404094D03*
X399894D03*
X396894D03*
Y324173D03*
X408894D03*
X411894D03*
X405894D03*
X414894D03*
X393894D03*
X402894D03*
X399894D03*
X383206Y638753D03*
X387606D03*
X392006D03*
X396406D03*
X400806D03*
X405206D03*
X409606D03*
X414006D03*
X370006D03*
X365606D03*
X374406D03*
X378806D03*
X356806D03*
X361206D03*
X374421Y660756D03*
X387621D03*
X383221D03*
X400821D03*
X396421D03*
X392021D03*
X405221D03*
X409621D03*
X414021D03*
X361221D03*
X365621D03*
X356821D03*
X370021D03*
X378821D03*
X477921Y-58764D03*
Y-35764D03*
X472921Y-58764D03*
Y-35764D03*
X467921Y-58764D03*
Y-35764D03*
X462921Y-58764D03*
Y-35764D03*
X457921Y-58764D03*
Y-35764D03*
X452921Y-58764D03*
Y-35764D03*
X447921Y-58764D03*
Y-35764D03*
X442921Y-58764D03*
Y-35764D03*
X437921Y-58764D03*
Y-35764D03*
X432921Y-58764D03*
X422921Y-35764D03*
X417921Y-58764D03*
Y-35764D03*
X432921D03*
X427921Y-58764D03*
Y-35764D03*
X422921Y-58764D03*
X432643Y264508D03*
X418523Y278910D03*
X428694D03*
X432894D03*
X425694D03*
X435894Y278938D03*
X443094Y278904D03*
X440094D03*
X421523Y278944D03*
X451675Y291739D03*
X449148Y292841D03*
X446209Y292842D03*
X451816Y295904D03*
X435894D03*
X418494D03*
X443094D03*
X440094D03*
X446383Y295841D03*
X428694Y295904D03*
X432894D03*
X425694D03*
X421494D03*
X418494Y324173D03*
X451267Y324476D03*
X448694Y323949D03*
X421494Y324173D03*
X446094Y323904D03*
X425694Y324173D03*
X428694D03*
X432894D03*
X435894D03*
X455226Y291686D03*
X454922Y295841D03*
X466806Y638753D03*
X462406D03*
X475606D03*
X471206D03*
X418406D03*
X422806D03*
X427206D03*
X440406D03*
X436006D03*
X431606D03*
X449206D03*
X458006D03*
X453606D03*
X444806D03*
X458021Y660756D03*
X449221D03*
X462421D03*
X466821D03*
X471221D03*
X418421D03*
X475621D03*
X453621D03*
X422821D03*
X427221D03*
X440421D03*
X431621D03*
X436021D03*
X444821D03*
X537921Y-58764D03*
Y-35764D03*
X532921Y-58764D03*
Y-35764D03*
X527921Y-58764D03*
Y-35764D03*
X522921Y-58764D03*
Y-35764D03*
X517921Y-58764D03*
Y-35764D03*
X512921Y-58764D03*
Y-35764D03*
X507921Y-58764D03*
Y-35764D03*
X502921Y-58764D03*
Y-35764D03*
X497921Y-58764D03*
Y-35764D03*
X492921Y-58764D03*
Y-35764D03*
X487921Y-58764D03*
Y-35764D03*
X482921Y-58764D03*
Y-35764D03*
X480006Y638753D03*
X484406D03*
X488806D03*
X493206D03*
X497606D03*
X510806D03*
X537206D03*
X519606D03*
X524006D03*
X532806D03*
X528406D03*
X515206D03*
X502006D03*
X506406D03*
X524021Y660756D03*
X480021D03*
X484421D03*
X497621D03*
X493221D03*
X488821D03*
X519621D03*
X532821D03*
X537221D03*
X528421D03*
X515221D03*
X510821D03*
X506421D03*
X502021D03*
X597921Y-35764D03*
Y-58764D03*
X592921Y-35764D03*
Y-58764D03*
X587921Y-35764D03*
Y-58764D03*
X582921Y-35764D03*
Y-58764D03*
X577921Y-35764D03*
Y-58764D03*
X572921Y-35764D03*
Y-58764D03*
X567921Y-35764D03*
Y-58764D03*
X562921Y-35764D03*
Y-58764D03*
X557921Y-35764D03*
Y-58764D03*
X552921Y-35764D03*
Y-58764D03*
X547921D03*
Y-35764D03*
X542921Y-58764D03*
Y-35764D03*
X590006Y638753D03*
X572406D03*
X559206D03*
X568006D03*
X563606D03*
X550406D03*
X581206D03*
X585606D03*
X576806D03*
X598806D03*
X594406D03*
X601500Y649500D03*
X554806Y638753D03*
X541606D03*
X546006D03*
X559221Y660756D03*
X546021D03*
X554821D03*
X598821D03*
X572421D03*
X568021D03*
X563621D03*
X585621D03*
X541621D03*
X594421D03*
X576821D03*
X590021D03*
X581221D03*
X550421D03*
X637921Y-58764D03*
X632921Y-35764D03*
Y-58764D03*
X627921Y-35764D03*
Y-58764D03*
X622921Y-35764D03*
Y-58764D03*
X617921Y-35764D03*
Y-58764D03*
X612921Y-35764D03*
Y-58764D03*
X607921Y-35764D03*
Y-58764D03*
X602921Y-35764D03*
Y-58764D03*
X652921Y-35764D03*
Y-58764D03*
X647921Y-35764D03*
Y-58764D03*
X642921Y-35764D03*
Y-58764D03*
X637921Y-35764D03*
X662921D03*
Y-58764D03*
X657921Y-35764D03*
Y-58764D03*
X638406Y638753D03*
X634006D03*
X642806D03*
X629606D03*
X616406D03*
X612006D03*
X603206D03*
X625206D03*
X651606D03*
X647206D03*
X660406D03*
X620806D03*
X656006D03*
X607606D03*
X607621Y660756D03*
X638421D03*
X647221D03*
X616421D03*
X634021D03*
X612021D03*
X620821D03*
X625221D03*
X629621D03*
X642821D03*
X603221D03*
X656021D03*
X660421D03*
X651621D03*
X692921Y-58764D03*
X687921Y-35764D03*
Y-58764D03*
X682921Y-35764D03*
Y-58764D03*
X677921Y-35764D03*
Y-58764D03*
X672921Y-35764D03*
Y-58764D03*
X667921Y-35764D03*
Y-58764D03*
X697921Y-35764D03*
Y-58764D03*
X692921Y-35764D03*
X722921D03*
Y-58764D03*
X717921Y-35764D03*
Y-58764D03*
X712921Y-35764D03*
Y-58764D03*
X707921Y-35764D03*
Y-58764D03*
X702921Y-35764D03*
Y-58764D03*
X704466Y-7874D03*
X690966Y-21374D03*
X700525Y1668D03*
X700517Y-17425D03*
X681713Y-17927D03*
X690966Y5626D03*
X681714Y2178D03*
X673864Y-16889D03*
X667566Y-7874D03*
X673864Y1139D03*
X695606Y638753D03*
X673606D03*
X708806D03*
X704406D03*
X700006D03*
X722006D03*
X717606D03*
X713206D03*
X664806D03*
X669206D03*
X686806D03*
X682406D03*
X678006D03*
X691206D03*
X690966Y624130D03*
Y597130D03*
X700525Y620172D03*
X700517Y601079D03*
X704466Y610630D03*
X667566D03*
X673864Y619643D03*
Y601615D03*
X681714Y620682D03*
X681713Y600577D03*
X664821Y660756D03*
X695621D03*
X708821D03*
X700021D03*
X704421D03*
X669221D03*
X686821D03*
X691221D03*
X678021D03*
X673621D03*
X682421D03*
X722021D03*
X717621D03*
X713221D03*
X777921Y-58764D03*
X772921Y-35764D03*
Y-58764D03*
X767921Y-35764D03*
Y-58764D03*
X762921Y-35764D03*
Y-58764D03*
X757921Y-35764D03*
Y-58764D03*
X752921Y-35764D03*
Y-58764D03*
X787921Y-35764D03*
Y-58764D03*
X782921Y-35764D03*
Y-58764D03*
X777921Y-35764D03*
X747921D03*
Y-58764D03*
X742921Y-35764D03*
Y-58764D03*
X737921Y-35764D03*
Y-58764D03*
X732921Y-35764D03*
Y-58764D03*
X727921Y-35764D03*
Y-58764D03*
X786674Y211463D03*
X785920Y204763D03*
X786300Y207400D03*
X787200Y244200D03*
Y271900D03*
X787100Y241100D03*
X773419Y270414D03*
X787200Y276400D03*
X787100Y303900D03*
X753098Y338316D03*
X744698Y332816D03*
X787000Y308300D03*
X787400Y340400D03*
X741774Y376463D03*
X785400Y372400D03*
X757500Y374000D03*
X770406Y638753D03*
X779206D03*
X774806D03*
X730806D03*
X726406D03*
X739606D03*
X735206D03*
X748406D03*
X744006D03*
X766006D03*
X761606D03*
X757206D03*
X752806D03*
X783606D03*
X744021Y660756D03*
X735221D03*
X779221D03*
X770421D03*
X774821D03*
X726421D03*
X730821D03*
X739621D03*
X748421D03*
X783621D03*
X757221D03*
X761621D03*
X752821D03*
X766021D03*
X842921Y-35764D03*
X837921Y-58764D03*
Y-35764D03*
X832921Y-58764D03*
X847921D03*
Y-35764D03*
X842921Y-58764D03*
X832921Y-35764D03*
X827921Y-58764D03*
Y-35764D03*
X822921Y-58764D03*
Y-35764D03*
X817921Y-58764D03*
Y-35764D03*
X812921Y-58764D03*
Y-35764D03*
X807921Y-58764D03*
Y-35764D03*
X802921Y-58764D03*
Y-35764D03*
X797921D03*
Y-58764D03*
X792921Y-35764D03*
Y-58764D03*
X816900Y216300D03*
X816874Y212863D03*
X814274D03*
X811674D03*
X808818Y211179D03*
X808618Y208579D03*
X803200Y213100D03*
X800600D03*
X794474Y211463D03*
X791874D03*
X789274D03*
X788522Y204343D03*
X791122Y204339D03*
X789432Y236947D03*
X789400Y273700D03*
X811983Y244843D03*
Y242243D03*
X814583Y239643D03*
X815432Y237000D03*
X814583Y244843D03*
Y242243D03*
X812832Y237000D03*
X811983Y239643D03*
X802432Y237000D03*
X799832D03*
X792032D03*
X794632D03*
X810232D03*
X797232D03*
X805032D03*
X807632D03*
X791000Y244400D03*
X793600D03*
X816800Y234300D03*
X816900Y230900D03*
X817000Y252500D03*
X789800Y276400D03*
X792400D03*
X801991Y276557D03*
X804591D03*
X792191Y269101D03*
X789591D03*
X814891Y271657D03*
Y274257D03*
Y276857D03*
Y269057D03*
X812291D03*
Y274257D03*
Y276857D03*
Y271657D03*
X817000Y255100D03*
Y257700D03*
X817491Y276857D03*
Y274257D03*
Y271657D03*
Y269057D03*
X817183Y242243D03*
Y239643D03*
Y244843D03*
X818032Y237000D03*
X788600Y306100D03*
X789500Y301200D03*
X797300D03*
X799900D03*
X810300D03*
X802500D03*
X812900D03*
X807700D03*
X805100D03*
X815500D03*
X811991Y308957D03*
Y306357D03*
Y303757D03*
X814591Y306357D03*
Y308957D03*
Y303757D03*
X792900Y308400D03*
X789900D03*
X794700Y301200D03*
X792100D03*
X793000Y340400D03*
X790300Y340300D03*
X816991Y337357D03*
Y334757D03*
Y339957D03*
X814391D03*
Y337357D03*
Y334757D03*
X811791Y337357D03*
Y339957D03*
Y334757D03*
X791879Y332798D03*
X794600Y332600D03*
X816938Y319888D03*
Y323888D03*
X817100Y317000D03*
X818100Y301200D03*
X817191Y303757D03*
Y306357D03*
Y308957D03*
X789860Y364947D03*
X816591Y369857D03*
Y372457D03*
X811391Y369857D03*
X813991D03*
Y372457D03*
X811391D03*
X790900Y372300D03*
X788300Y372400D03*
X802759Y364575D03*
X816672Y358809D03*
X795310Y364721D03*
X816593Y356210D03*
X807959Y364575D03*
X805359D03*
X810559D03*
X815759D03*
X813159D03*
X816900Y361400D03*
X792610Y364821D03*
X816591Y375057D03*
X792238Y396753D03*
X789600Y396809D03*
X811515Y397289D03*
X808915D03*
X813648Y395557D03*
X815472Y390442D03*
X814877Y393138D03*
X792000Y399409D03*
X789400D03*
X849606Y638753D03*
X836406D03*
X832006D03*
X796806D03*
X801206D03*
X792406D03*
X827606D03*
X818806D03*
X823206D03*
X810006D03*
X788006D03*
X845206D03*
X814406D03*
X805606D03*
X840806D03*
X849621Y660756D03*
X832021D03*
X810021D03*
X818821D03*
X836421D03*
X788021D03*
X814421D03*
X801221D03*
X805621D03*
X823221D03*
X827621D03*
X840821D03*
X796821D03*
X792421D03*
X845221D03*
X907921Y-58764D03*
Y-35764D03*
X902921Y-58764D03*
Y-35764D03*
X897921Y-58764D03*
Y-35764D03*
X892921Y-58764D03*
Y-35764D03*
X887921Y-58764D03*
Y-35764D03*
X882921Y-58764D03*
Y-35764D03*
X877921Y-58764D03*
Y-35764D03*
X872921Y-58764D03*
Y-35764D03*
X867921Y-58764D03*
Y-35764D03*
X862921Y-58764D03*
Y-35764D03*
X857921Y-58764D03*
Y-35764D03*
X852921Y-58764D03*
Y-35764D03*
X858406Y638753D03*
X854006D03*
X884806D03*
X880406D03*
X876006D03*
X871606D03*
X867206D03*
X911206D03*
X906806D03*
X889206D03*
X898006D03*
X902406D03*
X893606D03*
X862806D03*
X854021Y660756D03*
X858421D03*
X862821D03*
X898021D03*
X902421D03*
X871621D03*
X884821D03*
X893621D03*
X867221D03*
X889221D03*
X911221D03*
X906821D03*
X880421D03*
X876021D03*
X937921Y-35764D03*
X932921Y-58764D03*
Y-35764D03*
X927921Y-58764D03*
Y-35764D03*
X922921Y-58764D03*
Y-35764D03*
X917921Y-58764D03*
Y-35764D03*
X912921Y-58764D03*
Y-35764D03*
X942921D03*
X967921D03*
X962921Y-58764D03*
Y-35764D03*
X957921Y-58764D03*
Y-35764D03*
X952921Y-58764D03*
Y-35764D03*
X947921Y-58764D03*
Y-35764D03*
X942921Y-58764D03*
X972921D03*
Y-35764D03*
X967921Y-58764D03*
X937921D03*
X924406Y638753D03*
X920006D03*
X915606D03*
X972806D03*
X968406D03*
X964006D03*
X917100Y649300D03*
X942006Y638753D03*
X937606D03*
X933206D03*
X928806D03*
X959606D03*
X955206D03*
X950806D03*
X946406D03*
X959621Y660756D03*
X964021D03*
X968421D03*
X972821D03*
X920021D03*
X915621D03*
X924421D03*
X946421D03*
X942021D03*
X937621D03*
X933221D03*
X928821D03*
X955221D03*
X950821D03*
X1002921Y-58764D03*
Y-35764D03*
X997921Y-58764D03*
Y-35764D03*
X992921Y-58764D03*
Y-35764D03*
X987921Y-58764D03*
Y-35764D03*
X982921Y-58764D03*
Y-35764D03*
X977921Y-58764D03*
Y-35764D03*
X1032921Y-58764D03*
Y-35764D03*
X1027921Y-58764D03*
Y-35764D03*
X1022921Y-58764D03*
Y-35764D03*
X1017921Y-58764D03*
Y-35764D03*
X1012921Y-58764D03*
Y-35764D03*
X1007921Y-58764D03*
Y-35764D03*
X1030489Y270889D03*
Y273889D03*
X1027902Y278904D03*
X1020702D03*
X1017702D03*
X1024902D03*
X1032102D03*
X1017567Y295859D03*
X1024767D03*
X1020567D03*
X1031967D03*
X1027767D03*
X1015293Y311955D03*
X1003606Y638753D03*
X1012406D03*
X977206D03*
X990406D03*
X986006D03*
X994806D03*
X1016806D03*
X1021206D03*
X981606D03*
X999206D03*
X1025606D03*
X1008006D03*
X1030006D03*
X1034406D03*
X999221Y660756D03*
X1034421D03*
X1030021D03*
X1008021D03*
X1012421D03*
X1003621D03*
X1016821D03*
X977221D03*
X981621D03*
X1021221D03*
X1025621D03*
X994821D03*
X986021D03*
X990421D03*
X1067921Y-58764D03*
Y-35764D03*
X1062921Y-58764D03*
Y-35764D03*
X1057921Y-58764D03*
Y-35764D03*
X1052921Y-58764D03*
Y-35764D03*
X1047921Y-58764D03*
Y-35764D03*
X1042921Y-58764D03*
Y-35764D03*
X1037921Y-58764D03*
Y-35764D03*
X1092921Y-58764D03*
Y-35764D03*
X1087921Y-58764D03*
Y-35764D03*
X1082921Y-58764D03*
Y-35764D03*
X1077921Y-58764D03*
Y-35764D03*
X1072921Y-58764D03*
Y-35764D03*
X1042302Y278904D03*
X1039302D03*
X1056602Y278910D03*
X1035814Y278775D03*
X1049867Y278999D03*
X1053459Y278910D03*
X1060958D03*
X1075302D03*
X1078302D03*
X1082330D03*
X1070926D03*
X1063652D03*
X1067783D03*
X1082432Y264620D03*
X1085518Y278910D03*
X1089702Y278904D03*
X1039167Y295859D03*
X1042167D03*
X1034967D03*
X1046367D03*
X1056567D03*
X1049367D03*
X1053567D03*
X1038720Y324174D03*
X1044220D03*
X1035820D03*
X1050220D03*
X1047220D03*
X1053220D03*
X1056220D03*
X1041470D03*
X1059220D03*
X1060767Y295859D03*
X1095756Y292841D03*
X1082367Y295859D03*
X1085367D03*
X1075167D03*
X1078167D03*
X1089567D03*
X1092567D03*
X1095567Y295841D03*
X1070967Y295859D03*
X1063767D03*
X1067967D03*
X1062220Y324174D03*
X1095402Y323904D03*
X1083220Y324174D03*
X1076020D03*
X1079020D03*
X1071820D03*
X1065220D03*
X1068820D03*
X1096006Y638753D03*
X1078406D03*
X1082806D03*
X1074006D03*
X1069606D03*
X1091606D03*
X1052006D03*
X1038806D03*
X1087206D03*
X1060806D03*
X1056406D03*
X1065206D03*
X1043206D03*
X1047606D03*
X1078421Y660756D03*
X1060821D03*
X1087221D03*
X1038821D03*
X1091621D03*
X1052021D03*
X1074021D03*
X1065221D03*
X1096021D03*
X1056421D03*
X1043221D03*
X1047621D03*
X1082821D03*
X1069621D03*
X1157921Y-58764D03*
Y-35764D03*
X1152921Y-58764D03*
Y-35764D03*
X1147921Y-58764D03*
Y-35764D03*
X1142921Y-58764D03*
Y-35764D03*
X1137921Y-58764D03*
Y-35764D03*
X1132921Y-58764D03*
Y-35764D03*
X1127921Y-58764D03*
Y-35764D03*
X1122921Y-58764D03*
Y-35764D03*
X1117921Y-58764D03*
Y-35764D03*
X1112921Y-58764D03*
Y-35764D03*
X1107921Y-58764D03*
Y-35764D03*
X1102921Y-58764D03*
Y-35764D03*
X1097921Y-58764D03*
Y-35764D03*
X1104256Y291841D03*
X1101615Y292447D03*
X1098756Y292841D03*
X1101567Y295859D03*
X1104221Y295696D03*
X1098567Y295841D03*
X1112490Y312723D03*
X1112515Y315369D03*
X1101200Y324013D03*
X1098402Y324017D03*
X1135606Y638753D03*
X1126806D03*
X1144406D03*
X1140006D03*
X1118006D03*
X1122406D03*
X1153206D03*
X1157606D03*
X1104806D03*
X1100406D03*
X1131206D03*
X1148806D03*
X1109206D03*
X1113606D03*
X1157621Y660756D03*
X1148821D03*
X1122421D03*
X1126821D03*
X1100421D03*
X1118021D03*
X1140021D03*
X1113621D03*
X1109221D03*
X1153221D03*
X1144421D03*
X1104821D03*
X1131221D03*
X1135621D03*
X1217921Y-58764D03*
Y-35764D03*
X1212921Y-58764D03*
Y-35764D03*
X1207921Y-58764D03*
Y-35764D03*
X1202921Y-58764D03*
Y-35764D03*
X1197921Y-58764D03*
Y-35764D03*
X1192921Y-58764D03*
Y-35764D03*
X1187921Y-58764D03*
Y-35764D03*
X1182921Y-58764D03*
Y-35764D03*
X1177921Y-58764D03*
Y-35764D03*
X1172921Y-58764D03*
Y-35764D03*
X1167921Y-58764D03*
Y-35764D03*
X1162921Y-58764D03*
Y-35764D03*
X1188406Y638753D03*
X1214806D03*
X1197206D03*
X1201606D03*
X1192806D03*
X1170806D03*
X1162006D03*
X1166406D03*
X1206006D03*
X1219206D03*
X1179606D03*
X1175206D03*
X1210406D03*
X1184006D03*
X1184021Y660756D03*
X1219221D03*
X1192821D03*
X1188421D03*
X1201621D03*
X1179621D03*
X1214821D03*
X1206021D03*
X1166421D03*
X1210421D03*
X1170821D03*
X1162021D03*
X1175221D03*
X1197221D03*
X1232921Y-58764D03*
Y-35764D03*
X1227921Y-58764D03*
Y-35764D03*
X1222921Y-58764D03*
Y-35764D03*
X1252921Y-58764D03*
Y-35764D03*
X1247921Y-58764D03*
Y-35764D03*
X1242921Y-58764D03*
Y-35764D03*
X1237921Y-58764D03*
Y-35764D03*
X1257921D03*
X1272921Y-58764D03*
Y-35764D03*
X1267921Y-58764D03*
Y-35764D03*
X1262921Y-58764D03*
Y-35764D03*
X1257921Y-58764D03*
X1277921D03*
Y-35764D03*
X1263206Y638753D03*
X1223606D03*
X1228006D03*
X1258806D03*
X1241206D03*
X1236806D03*
X1250006D03*
X1245606D03*
X1276406D03*
X1254406D03*
X1280806D03*
X1272006D03*
X1267606D03*
X1232406D03*
X1228021Y660756D03*
X1232421D03*
X1280821D03*
X1245621D03*
X1236821D03*
X1223621D03*
X1276421D03*
X1241221D03*
X1272021D03*
X1258821D03*
X1250021D03*
X1254421D03*
X1263221D03*
X1267621D03*
X1342921Y-35764D03*
Y-58764D03*
X1317921D03*
X1312921Y-35764D03*
Y-58764D03*
X1307921Y-35764D03*
Y-58764D03*
X1302921Y-35764D03*
Y-58764D03*
X1297921D03*
Y-35764D03*
X1292921Y-58764D03*
Y-35764D03*
X1287921Y-58764D03*
Y-35764D03*
X1282921Y-58764D03*
Y-35764D03*
X1322921D03*
Y-58764D03*
X1317921Y-35764D03*
X1337921D03*
Y-58764D03*
X1332921Y-35764D03*
Y-58764D03*
X1327921Y-35764D03*
Y-58764D03*
X1324806Y638753D03*
X1298406D03*
X1285206D03*
X1294006D03*
X1302806D03*
X1333606D03*
X1338006D03*
X1320406D03*
X1311606D03*
X1329206D03*
X1307206D03*
X1342406D03*
X1289606D03*
X1316006D03*
X1329221Y660756D03*
X1311621D03*
X1316021D03*
X1333621D03*
X1342421D03*
X1285221D03*
X1324821D03*
X1338021D03*
X1298421D03*
X1289621D03*
X1294021D03*
X1320421D03*
X1302821D03*
X1307221D03*
X1402921Y-58764D03*
X1397921D03*
X1402921Y-35764D03*
X1392921Y-58764D03*
X1397921Y-35764D03*
X1387921Y-58764D03*
X1392921Y-35764D03*
X1382921Y-58764D03*
X1387921Y-35764D03*
X1377921Y-58764D03*
X1382921Y-35764D03*
X1372921Y-58764D03*
X1377921Y-35764D03*
X1367921Y-58764D03*
X1362921Y-35764D03*
Y-58764D03*
X1357921Y-35764D03*
Y-58764D03*
X1352921Y-35764D03*
Y-58764D03*
X1347921Y-35764D03*
Y-58764D03*
X1395913Y-7874D03*
X1402211Y1139D03*
Y-16889D03*
X1351206Y638753D03*
X1360006D03*
X1404506Y638853D03*
X1355606Y638753D03*
X1386906Y638853D03*
X1364406Y638753D03*
X1391306Y638853D03*
X1346806Y638753D03*
X1400106Y638853D03*
X1382006Y638753D03*
X1377606D03*
X1373206D03*
X1395706Y638853D03*
X1368806Y638753D03*
X1402211Y601615D03*
Y619643D03*
X1395913Y610630D03*
X1368821Y660756D03*
X1346821D03*
X1355621D03*
X1360021D03*
X1364421D03*
X1351221D03*
X1404521Y660856D03*
X1400121D03*
X1395721D03*
X1386921D03*
X1377621Y660756D03*
X1382021D03*
X1373221D03*
X1391321Y660856D03*
X1407921Y-58764D03*
X1412921Y-35764D03*
X1407921D03*
X1442921Y-58764D03*
X1447921Y-35764D03*
X1437921Y-58764D03*
X1442921Y-35764D03*
X1432921Y-58764D03*
X1437921Y-35764D03*
X1427921Y-58764D03*
X1432921Y-35764D03*
X1422921Y-58764D03*
X1427921Y-35764D03*
X1417921Y-58764D03*
X1422921Y-35764D03*
X1412921Y-58764D03*
X1417921Y-35764D03*
X1462921Y-58764D03*
X1457921D03*
X1462921Y-35764D03*
X1452921Y-58764D03*
X1457921Y-35764D03*
X1447921Y-58764D03*
X1452921Y-35764D03*
X1410061Y2178D03*
X1410060Y-17927D03*
X1419313Y5626D03*
Y-21374D03*
X1428872Y1668D03*
X1428864Y-17425D03*
X1432813Y-7874D03*
X1422106Y638853D03*
X1466106D03*
X1448506D03*
X1457306D03*
X1417706D03*
X1413306D03*
X1461706D03*
X1452906D03*
X1408906D03*
X1444106D03*
X1435306D03*
X1426506D03*
X1430906D03*
X1439706D03*
X1432813Y610630D03*
X1428864Y601079D03*
X1428872Y620172D03*
X1419313Y597130D03*
Y624130D03*
X1410060Y600577D03*
X1410061Y620682D03*
X1457321Y660856D03*
X1417721D03*
X1413321D03*
X1408921D03*
X1422121D03*
X1426521D03*
X1435321D03*
X1444121D03*
X1439721D03*
X1430921D03*
X1448521D03*
X1452921D03*
X1466121D03*
X1461721D03*
X1502921Y-58764D03*
X1507921Y-35764D03*
X1497921Y-58764D03*
X1502921Y-35764D03*
X1492921Y-58764D03*
X1497921Y-35764D03*
X1487921Y-58764D03*
X1492921Y-35764D03*
X1482921Y-58764D03*
X1487921Y-35764D03*
X1477921Y-58764D03*
X1482921Y-35764D03*
X1472921Y-58764D03*
X1477921Y-35764D03*
X1467921Y-58764D03*
X1472921Y-35764D03*
X1467921D03*
X1527921Y-58764D03*
X1522921D03*
X1527921Y-35764D03*
X1517921Y-58764D03*
X1522921Y-35764D03*
X1512921Y-58764D03*
X1517921Y-35764D03*
X1507921Y-58764D03*
X1512921Y-35764D03*
X1496906Y638853D03*
X1492506D03*
X1501706Y638753D03*
X1506106D03*
X1514906D03*
X1483706Y638853D03*
X1523706Y638753D03*
X1510506D03*
X1488106Y638853D03*
X1474906D03*
X1519306Y638753D03*
X1479306Y638853D03*
X1528106Y638753D03*
X1470506Y638853D03*
X1496921Y660856D03*
X1483721D03*
X1488121D03*
X1492521D03*
X1479321D03*
X1510521Y660756D03*
X1528121D03*
X1523721D03*
X1501721D03*
X1506121D03*
X1514921D03*
X1519321D03*
X1474921Y660856D03*
X1470521D03*
X1587921Y-58764D03*
X1582921D03*
X1587921Y-35764D03*
X1532921D03*
X1542921D03*
X1532921Y-58764D03*
X1537921Y-35764D03*
X1577921Y-58764D03*
X1582921Y-35764D03*
X1572921Y-58764D03*
X1577921Y-35764D03*
X1567921Y-58764D03*
X1572921Y-35764D03*
X1562921Y-58764D03*
X1567921Y-35764D03*
X1557921Y-58764D03*
X1562921Y-35764D03*
X1552921Y-58764D03*
X1557921Y-35764D03*
X1547921Y-58764D03*
X1552921Y-35764D03*
X1542921Y-58764D03*
X1547921Y-35764D03*
X1537921Y-58764D03*
X1580121Y647556D03*
X1555106Y638753D03*
X1555121Y647556D03*
X1590121D03*
X1590106Y638753D03*
X1590121Y643156D03*
X1585121Y647556D03*
X1585106Y638753D03*
X1585121Y643156D03*
X1565121Y647556D03*
X1570121Y643156D03*
X1570106Y638753D03*
X1565106D03*
X1565121Y643156D03*
X1570121Y647556D03*
X1560121D03*
X1560106Y638753D03*
X1560121Y643156D03*
X1575121D03*
X1575106Y638753D03*
X1575121Y647556D03*
X1555121Y643156D03*
X1580106Y638753D03*
X1580121Y643156D03*
X1550121Y647556D03*
X1541306Y638753D03*
X1545706D03*
X1550106D03*
X1550121Y643156D03*
X1536906Y638753D03*
X1532506D03*
X1565121Y651956D03*
X1570121Y660756D03*
Y656356D03*
X1565121Y660756D03*
X1555121Y651956D03*
X1590121Y660756D03*
Y656356D03*
Y651956D03*
X1585121Y660756D03*
Y656356D03*
Y651956D03*
X1580121Y660756D03*
Y656356D03*
Y651956D03*
X1560121Y660756D03*
Y656356D03*
Y651956D03*
X1555121Y660756D03*
Y656356D03*
X1570121Y651956D03*
X1575121D03*
Y656356D03*
Y660756D03*
X1565121Y656356D03*
X1550121Y651956D03*
Y656356D03*
X1541321Y660756D03*
X1550121D03*
X1545721D03*
X1532521D03*
X1536921D03*
X1642921Y-35764D03*
Y-58764D03*
X1637921Y-35764D03*
Y-58764D03*
X1632921Y-35764D03*
Y-58764D03*
X1627921D03*
X1622921D03*
X1627921Y-35764D03*
X1617921Y-58764D03*
X1622921Y-35764D03*
X1612921Y-58764D03*
X1617921Y-35764D03*
X1607921Y-58764D03*
X1612921Y-35764D03*
X1602921Y-58764D03*
X1607921Y-35764D03*
X1597921Y-58764D03*
X1602921Y-35764D03*
X1592921Y-58764D03*
X1597921Y-35764D03*
X1592921D03*
X1647921D03*
Y-58764D03*
X1625106Y638753D03*
X1625121Y647556D03*
X1630121Y643156D03*
X1630106Y638753D03*
X1630121Y647556D03*
X1635121Y643156D03*
X1635106Y638753D03*
X1635121Y647556D03*
X1640121Y643156D03*
Y647556D03*
X1640106Y638753D03*
X1650121Y647556D03*
X1650106Y638753D03*
X1650121Y643156D03*
X1645121Y647556D03*
X1645106Y638753D03*
X1645121Y643156D03*
X1625121D03*
X1620121Y647556D03*
X1620106Y638753D03*
X1620121Y643156D03*
X1615121Y647556D03*
X1615106Y638753D03*
X1615121Y643156D03*
X1610121Y647556D03*
X1610106Y638753D03*
X1610121Y643156D03*
X1605121Y647556D03*
X1605106Y638753D03*
X1605121Y643156D03*
X1600121Y647556D03*
X1600106Y638753D03*
X1600121Y643156D03*
X1595121Y647556D03*
X1595106Y638753D03*
X1595121Y643156D03*
X1625121Y651956D03*
Y660756D03*
X1630121Y651956D03*
Y656356D03*
Y660756D03*
X1635121Y651956D03*
Y656356D03*
Y660756D03*
X1625121Y656356D03*
X1640121D03*
Y651956D03*
X1650121Y660756D03*
Y656356D03*
Y651956D03*
X1645121Y660756D03*
Y656356D03*
Y651956D03*
X1640121Y660756D03*
X1620121D03*
Y656356D03*
Y651956D03*
X1615121Y660756D03*
Y656356D03*
Y651956D03*
X1610121Y660756D03*
Y656356D03*
Y651956D03*
X1605121Y660756D03*
Y656356D03*
Y651956D03*
X1600121Y660756D03*
Y656356D03*
Y651956D03*
X1595121Y660756D03*
Y656356D03*
Y651956D03*
X1692921Y-40764D03*
X1702921Y-54764D03*
X1687921D03*
X1682921D03*
X1677921D03*
X1672921D03*
X1692921D03*
X1697921D03*
X1707921D03*
X1712921D03*
X1697921Y-40764D03*
X1692921Y-50764D03*
X1687921D03*
X1682921D03*
X1677921D03*
X1672921D03*
X1712921D03*
X1707921D03*
X1702921D03*
X1697921Y-45764D03*
X1707921D03*
X1702921D03*
X1712921D03*
X1697921Y-50764D03*
X1667921Y-35764D03*
X1712921D03*
Y-58764D03*
X1707921Y-35764D03*
Y-58764D03*
X1702921Y-35764D03*
Y-58764D03*
X1697921Y-35764D03*
Y-58764D03*
X1687921Y-40764D03*
X1672921Y-45764D03*
X1677921D03*
X1682921D03*
Y-40764D03*
X1687921Y-45764D03*
X1692921D03*
X1667921Y-58764D03*
X1662921Y-35764D03*
Y-58764D03*
X1657921Y-35764D03*
Y-58764D03*
X1652921Y-35764D03*
Y-58764D03*
X1712921Y-40764D03*
X1707921D03*
X1702921D03*
X1677921D03*
X1672921D03*
X1677921Y-35764D03*
Y-58764D03*
X1672921Y-35764D03*
Y-58764D03*
X1682921Y-35764D03*
Y-58764D03*
X1692921Y-35764D03*
Y-58764D03*
X1687921Y-35764D03*
Y-58764D03*
X1690121Y647556D03*
X1710121D03*
X1710106Y638753D03*
X1710121Y643156D03*
X1705121Y647556D03*
X1705106Y638753D03*
X1695121Y643156D03*
X1695106Y638753D03*
X1695121Y647556D03*
X1700121Y643156D03*
X1700106Y638753D03*
X1685121Y647556D03*
X1685106Y638753D03*
X1685121Y643156D03*
X1680121Y647556D03*
X1680106Y638753D03*
X1680121Y643156D03*
X1675121Y647556D03*
X1675106Y638753D03*
X1675121Y643156D03*
X1670121Y647556D03*
X1670106Y638753D03*
X1670121Y643156D03*
X1665121Y647556D03*
X1665106Y638753D03*
X1665121Y643156D03*
X1660121Y647556D03*
X1660106Y638753D03*
X1660121Y643156D03*
X1655121Y647556D03*
X1655106Y638753D03*
X1655121Y643156D03*
X1690121D03*
X1690106Y638753D03*
X1700121Y647556D03*
X1705121Y643156D03*
X1690121Y656356D03*
Y651956D03*
X1710121Y660756D03*
Y656356D03*
Y651956D03*
X1705121Y660756D03*
Y656356D03*
Y651956D03*
X1690121Y660756D03*
X1695121Y651956D03*
Y656356D03*
Y660756D03*
X1685121Y651956D03*
X1680121Y660756D03*
Y656356D03*
Y651956D03*
X1675121Y660756D03*
Y656356D03*
Y651956D03*
X1670121Y660756D03*
Y656356D03*
Y651956D03*
X1665121Y660756D03*
Y656356D03*
Y651956D03*
X1660121Y660756D03*
Y656356D03*
Y651956D03*
X1655121Y660756D03*
Y656356D03*
Y651956D03*
X1685121Y660756D03*
Y656356D03*
X1700121Y651956D03*
Y656356D03*
Y660756D03*
X1737921Y-50764D03*
X1722921Y-45764D03*
X1727921D03*
X1732921D03*
X1747921D03*
X1752921D03*
X1727921Y-54764D03*
X1757921D03*
X1717921D03*
X1722921D03*
X1767921Y-40764D03*
Y-50764D03*
X1762921D03*
X1757921D03*
X1762921Y-54764D03*
X1752921D03*
X1747921D03*
X1742921D03*
X1737921D03*
X1732921D03*
X1772921D03*
X1767921D03*
X1762921Y-40764D03*
X1772921D03*
X1722921Y-50764D03*
X1717921D03*
X1732921D03*
X1757921Y-40764D03*
X1717921Y-45764D03*
Y-58764D03*
X1742921Y-50764D03*
X1747921D03*
X1752921D03*
X1742921Y-58764D03*
X1737921Y-35764D03*
Y-58764D03*
X1732921Y-35764D03*
Y-58764D03*
X1727921Y-35764D03*
Y-58764D03*
X1722921Y-35764D03*
Y-58764D03*
X1717921Y-35764D03*
X1757921Y-45764D03*
X1762921D03*
X1742921D03*
X1752921Y-40764D03*
X1747921D03*
X1742921D03*
X1737921D03*
X1732921D03*
X1727921D03*
X1722921D03*
X1717921D03*
X1727921Y-50764D03*
X1767921Y-45764D03*
X1772921D03*
X1737921D03*
X1772921Y-35764D03*
Y-58764D03*
X1767921Y-35764D03*
Y-58764D03*
X1762921Y-35764D03*
Y-58764D03*
X1757921Y-35764D03*
Y-58764D03*
X1752921Y-35764D03*
Y-58764D03*
X1747921Y-35764D03*
Y-58764D03*
X1742921Y-35764D03*
X1772921Y-50764D03*
X1775121Y643156D03*
Y647556D03*
X1775106Y638753D03*
X1730121Y647556D03*
X1730106Y638753D03*
X1730121Y643156D03*
X1725121Y647556D03*
X1725106Y638753D03*
X1725121Y643156D03*
X1720121Y647556D03*
X1720106Y638753D03*
X1720121Y643156D03*
X1715121Y647556D03*
X1715106Y638753D03*
X1715121Y643156D03*
X1770121Y647556D03*
X1770106Y638753D03*
X1770121Y643156D03*
X1765121Y647556D03*
X1765106Y638753D03*
X1765121Y643156D03*
X1760121Y647556D03*
X1760106Y638753D03*
X1760121Y643156D03*
X1755121Y647556D03*
X1755106Y638753D03*
X1755121Y643156D03*
X1750121Y647556D03*
X1750106Y638753D03*
X1750121Y643156D03*
X1745121Y647556D03*
X1745106Y638753D03*
X1745121Y643156D03*
X1740121Y647556D03*
X1740106Y638753D03*
X1740121Y643156D03*
X1735121Y647556D03*
X1735106Y638753D03*
X1735121Y643156D03*
X1770121Y660756D03*
X1775121D03*
Y656356D03*
Y651956D03*
X1725121Y660756D03*
Y656356D03*
Y651956D03*
X1720121Y660756D03*
Y656356D03*
Y651956D03*
X1715121Y660756D03*
Y656356D03*
Y651956D03*
X1770121D03*
X1765121Y660756D03*
Y656356D03*
Y651956D03*
X1760121Y660756D03*
Y656356D03*
Y651956D03*
X1755121Y660756D03*
Y656356D03*
Y651956D03*
X1750121Y660756D03*
Y656356D03*
Y651956D03*
X1745121Y660756D03*
Y656356D03*
Y651956D03*
X1740121Y660756D03*
Y656356D03*
Y651956D03*
X1735121Y660756D03*
Y656356D03*
Y651956D03*
X1730121Y660756D03*
Y656356D03*
X1770121D03*
X1730121Y651956D03*
X1817921Y-40764D03*
X1832921Y-45764D03*
Y-54764D03*
X1827921D03*
X1822921D03*
X1817921D03*
X1812921D03*
X1807921D03*
X1802921D03*
X1797921D03*
X1792921D03*
X1787921D03*
X1782921D03*
X1777921D03*
X1832921Y-50764D03*
X1827921D03*
X1822921D03*
X1817921D03*
X1812921D03*
X1807921D03*
X1802921D03*
X1797921D03*
X1792921D03*
X1787921D03*
X1782921Y-40764D03*
X1792921D03*
X1802921D03*
X1807921D03*
X1822921D03*
X1827921D03*
X1832921D03*
X1812921D03*
X1797921D03*
X1777921Y-45764D03*
X1782921D03*
X1787921D03*
X1792921D03*
X1797921D03*
X1802921D03*
X1807921D03*
X1812921D03*
X1817921D03*
X1822921D03*
X1787921Y-40764D03*
X1832921Y-35764D03*
Y-58764D03*
X1827921Y-35764D03*
Y-58764D03*
X1822921Y-35764D03*
Y-58764D03*
X1817921Y-35764D03*
Y-58764D03*
X1812921Y-35764D03*
Y-58764D03*
X1807921Y-35764D03*
Y-58764D03*
X1802921Y-35764D03*
Y-58764D03*
X1797921Y-35764D03*
Y-58764D03*
X1792921Y-35764D03*
Y-58764D03*
X1787921Y-35764D03*
Y-58764D03*
X1782921Y-35764D03*
Y-58764D03*
X1777921Y-35764D03*
Y-58764D03*
X1782921Y-50764D03*
X1777921D03*
Y-40764D03*
X1827921Y-45764D03*
X1794992Y61342D03*
X1797664Y61334D03*
X1797645Y64153D03*
X1792382Y61363D03*
X1792363Y64182D03*
X1794973Y64161D03*
X1807891Y62180D03*
X1810563Y62172D03*
X1810693Y59493D03*
X1808021Y59501D03*
X1805411Y59522D03*
X1813393Y59493D03*
X1813363Y62172D03*
X1810578Y56866D03*
X1805282Y56880D03*
X1807916Y56895D03*
X1813278Y56866D03*
X1805281Y62201D03*
X1831148Y144592D03*
X1836200Y153424D03*
X1833000D03*
X1833600Y145900D03*
X1793205Y165531D03*
X1793268Y162774D03*
X1780121Y643156D03*
X1780106Y638753D03*
X1780121Y647556D03*
X1785121Y643156D03*
X1790121D03*
X1835121Y647556D03*
X1835106Y638753D03*
X1835121Y643156D03*
X1830121Y647556D03*
X1830106Y638753D03*
X1830121Y643156D03*
X1825121Y647556D03*
X1825106Y638753D03*
X1825121Y643156D03*
X1820121Y647556D03*
X1820106Y638753D03*
X1820121Y643156D03*
X1815121Y647556D03*
X1815106Y638753D03*
X1815121Y643156D03*
X1810121Y647556D03*
X1810106Y638753D03*
X1810121Y643156D03*
X1805121Y647556D03*
X1805106Y638753D03*
X1805121Y643156D03*
X1800121Y647556D03*
X1800106Y638753D03*
X1800121Y643156D03*
X1795121Y647556D03*
X1795106Y638753D03*
X1795121Y643156D03*
X1790121Y647556D03*
X1790106Y638753D03*
X1785121Y647556D03*
X1785106Y638753D03*
X1800121Y656356D03*
X1780121Y651956D03*
Y656356D03*
Y660756D03*
X1835121D03*
Y656356D03*
Y651956D03*
X1830121Y660756D03*
Y656356D03*
Y651956D03*
X1825121Y660756D03*
Y656356D03*
Y651956D03*
X1820121Y660756D03*
Y656356D03*
Y651956D03*
X1815121Y660756D03*
Y656356D03*
Y651956D03*
X1810121Y660756D03*
Y656356D03*
Y651956D03*
X1805121Y660756D03*
Y656356D03*
Y651956D03*
X1800121Y660756D03*
Y651956D03*
X1795121Y660756D03*
Y656356D03*
Y651956D03*
X1790121Y660756D03*
Y656356D03*
Y651956D03*
X1785121Y660756D03*
Y656356D03*
Y651956D03*
X1857921Y-45764D03*
X1837921D03*
X1897921D03*
X1892921D03*
X1887921D03*
X1882921D03*
X1877921D03*
X1872921D03*
X1867921D03*
X1862921D03*
X1842921Y-54764D03*
X1852921Y-45764D03*
X1847921D03*
X1842921D03*
X1897921Y-54764D03*
X1892921D03*
X1887921D03*
X1882921D03*
X1877921D03*
X1872921D03*
X1867921D03*
X1862921D03*
X1857921D03*
X1852921D03*
X1847921D03*
X1837921D03*
X1897921Y-50764D03*
X1892921D03*
X1887921D03*
X1882921D03*
X1877921D03*
X1872921D03*
X1867921D03*
X1862921D03*
X1857921D03*
X1852921D03*
X1847921D03*
X1842921D03*
X1837921D03*
X1892921Y-40764D03*
X1897921D03*
X1877921D03*
X1882921D03*
X1887921D03*
X1857921D03*
X1862921D03*
X1867921D03*
X1872921D03*
X1837921D03*
X1842921D03*
X1847921D03*
X1852921D03*
Y-35764D03*
Y-58764D03*
X1847921Y-35764D03*
Y-58764D03*
X1842921Y-35764D03*
Y-58764D03*
X1837921Y-35764D03*
Y-58764D03*
X1862921D03*
X1857921Y-35764D03*
Y-58764D03*
X1882921D03*
X1877921Y-35764D03*
Y-58764D03*
X1872921Y-35764D03*
Y-58764D03*
X1867921Y-35764D03*
Y-58764D03*
X1862921Y-35764D03*
X1897921D03*
Y-58764D03*
X1892921Y-35764D03*
Y-58764D03*
X1887921Y-35764D03*
Y-58764D03*
X1882921Y-35764D03*
X1847797Y26331D03*
X1847564Y21636D03*
X1844732Y-7874D03*
X1851030Y1139D03*
Y-16889D03*
X1858880Y2178D03*
X1858879Y-17927D03*
X1868132Y5626D03*
Y-21374D03*
X1877691Y1668D03*
X1877683Y-17425D03*
X1881632Y-7874D03*
X1895121Y647556D03*
X1895106Y638753D03*
X1895121Y643156D03*
X1890121Y647556D03*
X1890106Y638753D03*
X1890121Y643156D03*
X1885121Y647556D03*
X1885106Y638753D03*
X1885121Y643156D03*
X1880121Y647556D03*
X1880106Y638753D03*
X1880121Y643156D03*
X1875121Y647556D03*
X1875106Y638753D03*
X1875121Y643156D03*
X1870121Y647556D03*
X1870106Y638753D03*
X1870121Y643156D03*
X1865121Y647556D03*
X1865106Y638753D03*
X1865121Y643156D03*
X1860121Y647556D03*
X1860106Y638753D03*
X1860121Y643156D03*
X1855121Y647556D03*
X1855106Y638753D03*
X1855121Y643156D03*
X1850121Y647556D03*
X1850106Y638753D03*
X1850121Y643156D03*
X1845121Y647556D03*
X1845106Y638753D03*
X1845121Y643156D03*
X1840121Y647556D03*
X1840106Y638753D03*
X1840121Y643156D03*
X1844732Y610630D03*
X1851030Y619643D03*
Y601615D03*
X1858880Y620682D03*
X1858879Y600577D03*
X1868132Y624130D03*
Y597130D03*
X1877691Y620172D03*
X1877683Y601079D03*
X1881632Y610630D03*
X1895121Y660756D03*
Y656356D03*
Y651956D03*
X1890121Y660756D03*
Y656356D03*
Y651956D03*
X1885121Y660756D03*
Y656356D03*
Y651956D03*
X1880121Y660756D03*
Y656356D03*
Y651956D03*
X1875121Y660756D03*
Y656356D03*
Y651956D03*
X1870121Y660756D03*
Y656356D03*
Y651956D03*
X1865121Y660756D03*
Y656356D03*
Y651956D03*
X1860121Y660756D03*
Y656356D03*
Y651956D03*
X1855121Y660756D03*
Y656356D03*
Y651956D03*
X1850121Y660756D03*
Y656356D03*
Y651956D03*
X1845121Y660756D03*
Y656356D03*
Y651956D03*
X1840121Y660756D03*
Y656356D03*
Y651956D03*
X1927921Y-40764D03*
X1947921Y-45764D03*
X1942921D03*
X1937921D03*
X1932921D03*
X1927921D03*
X1922921D03*
X1917921D03*
X1912921D03*
X1907921D03*
X1902921D03*
X1927921Y-50764D03*
X1932921D03*
Y-40764D03*
X1937921D03*
X1942921D03*
X1947921D03*
X1907921Y-50764D03*
X1902921D03*
X1922921Y-40764D03*
X1917921D03*
X1912921D03*
X1907921D03*
X1902921D03*
X1922921Y-54764D03*
X1917921D03*
X1912921D03*
X1907921D03*
X1902921D03*
X1927921D03*
X1932921D03*
X1937921D03*
X1942921D03*
X1947921D03*
X1952921D03*
X1957921D03*
Y-50764D03*
X1952921D03*
X1947921D03*
X1942921D03*
X1937921D03*
X1922921D03*
X1917921D03*
X1912921D03*
X1957921Y-35764D03*
Y-58764D03*
X1952921Y-35764D03*
Y-58764D03*
X1947921Y-35764D03*
Y-58764D03*
X1942921Y-35764D03*
Y-58764D03*
X1937921Y-35764D03*
Y-58764D03*
X1932921Y-35764D03*
Y-58764D03*
X1927921Y-35764D03*
Y-58764D03*
X1922921Y-35764D03*
Y-58764D03*
X1917921Y-35764D03*
Y-58764D03*
X1912921Y-35764D03*
Y-58764D03*
X1907921Y-35764D03*
Y-58764D03*
X1902921Y-35764D03*
Y-58764D03*
X1960106Y638753D03*
X1955106D03*
X1950106D03*
X1945121Y647556D03*
Y643156D03*
X1945106Y638753D03*
X1940121Y647556D03*
Y643156D03*
X1940106Y638753D03*
X1935121Y647556D03*
Y643156D03*
X1935106Y638753D03*
X1930106D03*
X1925106D03*
X1920121Y647556D03*
X1910121Y643156D03*
X1910106Y638753D03*
X1905121Y647556D03*
Y643156D03*
X1905106Y638753D03*
X1900121Y647556D03*
X1900106Y638753D03*
X1900121Y643156D03*
X1920106Y638753D03*
X1915121Y647556D03*
X1920121Y643156D03*
X1910121Y647556D03*
X1915106Y638753D03*
X1915121Y643156D03*
X1960121Y656356D03*
Y660756D03*
X1955121Y656356D03*
Y660756D03*
X1950121Y651956D03*
Y656356D03*
Y660756D03*
X1945121Y651956D03*
Y656356D03*
Y660756D03*
X1940121Y651956D03*
Y656356D03*
Y660756D03*
X1935121Y651956D03*
Y656356D03*
Y660756D03*
X1930121Y651956D03*
Y656356D03*
Y660756D03*
X1925121Y651956D03*
Y656356D03*
Y660756D03*
X1920121Y651956D03*
Y656356D03*
X1905121Y651956D03*
Y656356D03*
Y660756D03*
X1900121D03*
Y656356D03*
Y651956D03*
X1915121D03*
Y656356D03*
Y660756D03*
X1920121D03*
X1910121D03*
Y656356D03*
Y651956D03*
X1967921Y-45764D03*
X1962921D03*
Y-40764D03*
X1967921D03*
Y-54764D03*
X1962921D03*
X1967921Y-50764D03*
X1962921D03*
X1967921Y-35764D03*
Y-58764D03*
X1962921Y-35764D03*
Y-58764D03*
X1970121Y647556D03*
Y643156D03*
X1970106Y638753D03*
X1965121Y647556D03*
Y643156D03*
X1965106Y638753D03*
X1970121Y651956D03*
Y656356D03*
Y660756D03*
X1965121Y651956D03*
Y656356D03*
Y660756D03*
G54D11*
X0Y0D03*
G54D20*
X72074Y243282D03*
X65180Y243368D03*
X61800Y243400D03*
X68498Y243368D03*
X49560Y649770D03*
Y644670D03*
X54360D03*
X49560Y649570D03*
Y644670D03*
X54360D03*
X49560Y654670D03*
X54360D03*
X49560D03*
X54360D03*
X214820Y649570D03*
Y644670D03*
X210020D03*
X214820Y649770D03*
Y644670D03*
X210020D03*
X214820Y654670D03*
X210020D03*
X214820D03*
X210020D03*
X238282Y649670D03*
Y644770D03*
X243082D03*
X238282Y649870D03*
Y644770D03*
X243082D03*
X238282Y654770D03*
X243082D03*
X238282D03*
X243082D03*
X402404Y649650D03*
Y644550D03*
X397604D03*
X402404Y649450D03*
Y644550D03*
X397604D03*
X402404Y654550D03*
X397604D03*
X402404D03*
X397604D03*
X425750Y649400D03*
Y644500D03*
X430550D03*
X425750Y649600D03*
Y644500D03*
X430550D03*
X425750Y654500D03*
X430550D03*
X425750D03*
X430550D03*
X589871Y649379D03*
Y644279D03*
X585071D03*
X589872Y649180D03*
Y644280D03*
X585072D03*
X589871Y654279D03*
X585071D03*
X589872Y654280D03*
X585072D03*
X613298Y649331D03*
Y644231D03*
X618098D03*
X613298Y649131D03*
Y644231D03*
X618098D03*
X613298Y654231D03*
X618098D03*
X613298D03*
X618098D03*
X905515Y649159D03*
Y644259D03*
X900715D03*
X905515Y649359D03*
Y644259D03*
X900715D03*
X905515Y654259D03*
X900715D03*
X905515D03*
X900715D03*
X928952Y649120D03*
Y644220D03*
X933752D03*
X928952Y649320D03*
Y644220D03*
X933752D03*
X928952Y654220D03*
X933752D03*
X928952D03*
X933752D03*
X1219041Y649348D03*
Y644248D03*
X1214241D03*
X1219041Y649148D03*
Y644248D03*
X1214241D03*
X1219041Y654248D03*
X1214241D03*
X1219041D03*
X1214241D03*
X1242450Y649150D03*
Y644250D03*
X1247250D03*
X1242450Y649350D03*
Y644250D03*
X1247250D03*
X1242450Y654250D03*
X1247250D03*
X1242450D03*
X1247250D03*
X1527739Y644278D03*
D03*
Y654278D03*
D03*
X1532539Y649378D03*
Y644278D03*
Y649178D03*
Y644278D03*
Y654278D03*
D03*
G54D30*
X1887327Y511202D03*
X1929453Y532541D03*
G54D21*
X60512Y467244D03*
X1894100Y493000D03*
X1891086Y602105D03*
G54D12*
G01X38645Y172740D02*
X44291Y178386D01*
G01D02*
X49937Y184032D01*
G01X38645D02*
X44291Y178386D01*
G01D02*
X49937Y172740D01*
G01X-7615D02*
X-1969Y178386D01*
G01D02*
X3677Y184032D01*
G01X-7615D02*
X-1969Y178386D01*
G01D02*
X3677Y172740D01*
G01X12582D02*
X18228Y178386D01*
G01D02*
X23874Y184032D01*
G01X12582D02*
X18228Y178386D01*
G01D02*
X23874Y172740D01*
G01X12129Y430711D02*
X15512Y434094D01*
G01D02*
X18895Y437477D01*
G01X12129D02*
X15512Y434094D01*
G01D02*
X18895Y430711D01*
G01X116597Y142148D02*
X119980Y145531D01*
G01D02*
X123363Y148914D01*
G01X116597D02*
X119980Y145531D01*
G01D02*
X123363Y142148D01*
G01X430749Y-124922D02*
G02I-12000J0D01*
G01X425599D02*
G02I-6850J0D01*
G01X434749D02*
X402749D01*
G01X434749Y-140922D02*
Y-220922D01*
G01D02*
X1729349D01*
G01X434749Y-176422D02*
X1729349D01*
G01X418749Y-140922D02*
Y-108922D01*
G01X434749Y-140922D02*
X1729349D01*
G01X941849D02*
Y-220922D01*
G01X1079349Y-140922D02*
Y-220922D01*
G01X1194349Y-140922D02*
Y-220922D01*
G01X1361849Y-140922D02*
Y-220922D01*
G01X1389729Y21441D02*
X1392264Y23976D01*
G01D02*
X1394799Y26511D01*
G01X1389729D02*
X1392264Y23976D01*
G01D02*
X1394799Y21441D01*
G01X1511383D02*
X1513918Y23976D01*
G01D02*
X1516453Y26511D01*
G01X1511383D02*
X1513918Y23976D01*
G01D02*
X1516453Y21441D01*
G01X1531849Y-140922D02*
Y-220922D01*
G01X1644721Y-2921D02*
X1647327Y-315D01*
G01D02*
X1649933Y2291D01*
G01X1644721D02*
X1647327Y-315D01*
G01D02*
X1649933Y-2921D01*
G01X1729349Y-140922D02*
Y-220922D01*
G01X1757349Y-124922D02*
G02I-12000J0D01*
G01X1752199D02*
G02I-6850J0D01*
G01X1745349Y-140922D02*
Y-108922D01*
G01X1761349Y-124922D02*
X1729349D01*
G01X1947447Y214597D02*
X1950000Y207893D01*
G01X1947447Y203241D02*
X1950000Y207893D01*
G01X1959921Y209074D02*
X1961890Y211043D01*
G01X1950000Y220787D02*
X1953630Y217612D01*
G01X1946370D02*
X1950000Y220787D01*
G01X1947447Y234851D02*
X1950000Y241555D01*
G01Y234851D02*
Y241555D01*
G01X1959921Y240374D02*
X1961890Y238405D01*
G01X1946370Y231836D02*
X1950000Y228661D01*
G01D02*
X1953630Y225486D01*
G01X1950000Y228661D02*
X1953630Y231836D01*
G01X1946370Y223962D02*
X1950000Y220787D01*
G01D02*
X1953630Y223962D01*
G01X1929453Y529639D02*
Y532541D01*
G01D02*
Y535443D01*
G01X1925351Y532541D02*
X1929453D01*
G01D02*
X1933555D01*
G01X1967468Y212037D02*
X1970670Y207007D01*
G01X1967468Y201977D02*
X1970670Y207007D01*
G01X1961890Y211043D02*
X1963859Y213012D01*
G01X1961890Y211043D02*
X1963859Y209074D01*
G01X1967468Y237411D02*
X1970670Y242441D01*
G01Y237411D02*
Y242441D01*
G01X1961890Y238405D02*
X1963859Y240374D01*
G01X1961890Y238405D02*
X1963859Y236436D01*
X-20700Y31400D03*
Y25200D03*
Y22300D03*
Y28100D03*
X-20600Y41200D03*
X-20526Y44263D03*
X-20500Y60300D03*
Y57300D03*
X-20700Y48800D03*
X-20726Y37463D03*
X-20800Y34400D03*
X-20500Y54300D03*
Y51300D03*
X-18000Y247400D03*
X-15000D03*
X-18000Y262700D03*
X-15000D03*
X-14690Y471140D03*
X-16726Y503651D03*
X-17084Y467626D03*
X-17300Y530800D03*
X-17397Y564242D03*
X30600Y-12000D03*
X25838Y-20458D03*
X10600Y25100D03*
X1068Y24831D03*
X27102Y25383D03*
X39530Y5205D03*
X45670Y5185D03*
X33370D03*
X45429Y-4669D03*
X33628Y131D03*
X40994Y-7148D03*
X45700Y40D03*
X11539Y31427D03*
X27200Y30600D03*
X27239Y28027D03*
X25600Y32500D03*
X11600Y33944D03*
X26760Y49595D03*
X27800Y86900D03*
X22100Y56400D03*
X27800Y89900D03*
Y83900D03*
X30400Y89800D03*
Y86800D03*
Y83800D03*
X10925Y56167D03*
X27904Y56294D03*
X30686Y79943D03*
X23530Y94840D03*
X11030D03*
X13530D03*
X16030D03*
X18530D03*
X22380Y92670D03*
X21030Y94840D03*
X2380Y92670D03*
X4880D03*
X7380D03*
X9880D03*
X12380D03*
X14880D03*
X17380D03*
X19880D03*
X3530Y94840D03*
X6030D03*
X8530D03*
X-1000Y81500D03*
X24880Y92670D03*
X25870Y80880D03*
X28294Y80889D03*
X32500Y81791D03*
X25100Y56300D03*
X-1190Y53240D03*
X25886Y71467D03*
X25925Y75867D03*
X26185Y67017D03*
X27488Y64671D03*
X11925Y65311D03*
X27625Y73967D03*
X27525Y69367D03*
X11925Y67811D03*
X11864Y62794D03*
X24064Y61894D03*
X15111Y62553D03*
X27564Y61894D03*
X11600Y36444D03*
X25900Y40300D03*
X27564Y59394D03*
X24064D03*
X25700Y36200D03*
X27300Y34300D03*
Y38300D03*
X27208Y42313D03*
X27239Y47027D03*
X25700Y44400D03*
X27525Y77867D03*
X44200Y139400D03*
X44300Y144800D03*
X44200Y130700D03*
Y116800D03*
X44100Y97800D03*
X44200Y111500D03*
X44300Y102700D03*
Y125600D03*
X44600Y154100D03*
X7995Y285385D03*
X32450Y454050D03*
X35100Y453900D03*
X35900Y423500D03*
X43550Y431300D03*
X20075Y424850D03*
X12025Y427900D03*
X7025D03*
X2025D03*
X21397Y439354D03*
Y444354D03*
X18836Y441785D03*
X7736D03*
X-6104Y461190D03*
X5000Y469000D03*
X10443Y490649D03*
X40132Y499800D03*
X24400Y519500D03*
X280Y524350D03*
X40185Y482918D03*
X37568Y482836D03*
X26780Y488910D03*
X21000Y495800D03*
X13300Y509600D03*
X13600Y504300D03*
X4000Y509500D03*
X2485Y498185D03*
X13700Y498500D03*
X24591Y479139D03*
X35896Y557668D03*
X33396D03*
X38696D03*
X-10200Y558200D03*
X21700Y532300D03*
X19100D03*
X27000D03*
X1040Y531218D03*
X21948Y566700D03*
X19448D03*
X27114Y557563D03*
X24748Y566700D03*
X0Y566800D03*
X29400Y532300D03*
X46400Y536290D03*
Y539790D03*
X43505Y538714D03*
X43241Y535965D03*
X41500Y533800D03*
X29914Y557563D03*
X45880Y554710D03*
Y557820D03*
X46560Y581000D03*
Y577500D03*
X1500Y540600D03*
X15787Y551700D03*
X17100Y545400D03*
X13639Y534683D03*
Y537183D03*
X15800Y543300D03*
X15600Y539100D03*
X17139Y534683D03*
Y537183D03*
X17100Y541200D03*
X17035Y549558D03*
X15800Y547500D03*
X17139Y553683D03*
X1500Y543100D03*
X1439Y538083D03*
X15800Y579500D03*
Y575300D03*
X17108Y585513D03*
X17156Y581481D03*
X17100Y577400D03*
X17139Y573183D03*
X1500Y576600D03*
X17139Y570683D03*
X1500Y579100D03*
X1439Y574083D03*
X15770Y587700D03*
X15800Y583500D03*
X27495Y591409D03*
X-12450Y590965D03*
X30212Y591417D03*
X35085Y591621D03*
X32609Y591538D03*
X46500Y595190D03*
X43190Y598410D03*
X43210Y595180D03*
X43190Y601910D03*
X17139Y589683D03*
X65800Y14200D03*
X59061Y476D03*
X61152Y-12752D03*
X59281Y-20641D03*
X99102Y-12010D03*
X105892Y8700D03*
X62076Y5575D03*
X76247Y1189D03*
X84202Y-11395D03*
X81702D03*
X79202D03*
X73611Y1158D03*
X71111D03*
X68611D03*
X73574Y-1437D03*
X71074D03*
X68574D03*
X79500Y-16600D03*
X55713Y-5095D03*
X76165Y-1415D03*
X106200Y26500D03*
X102100Y73800D03*
X105892Y45290D03*
X52500Y67200D03*
Y63700D03*
Y60700D03*
Y37700D03*
Y34700D03*
Y43700D03*
Y40700D03*
Y57700D03*
X71050Y89600D03*
X48700Y90700D03*
Y95500D03*
X61300Y89800D03*
X81861Y93392D03*
X108385Y84291D03*
X63737Y130602D03*
X48900Y132600D03*
X68592D03*
X85250Y127680D03*
X77730Y126860D03*
X63858Y97620D03*
X66600Y102360D03*
X62422Y109413D03*
X68000Y111000D03*
X48900Y123500D03*
X62524Y123395D03*
X68584Y123900D03*
X68654Y118680D03*
X48800Y118900D03*
X48700Y109600D03*
X48600Y104900D03*
X63582Y116409D03*
X62502Y105100D03*
X52500Y152000D03*
X60300Y151500D03*
X70800Y151400D03*
X48800Y137600D03*
X63878Y144800D03*
X68632Y137800D03*
X63888Y140064D03*
X107254Y128041D03*
X106698Y215610D03*
X100500Y188600D03*
X97500Y185700D03*
X104800D03*
X102400D03*
X99900D03*
X77650Y178150D03*
X73500Y191500D03*
X107750Y238730D03*
X83300Y267400D03*
X108000Y249330D03*
X53400Y277582D03*
Y274500D03*
X48800Y282600D03*
Y285100D03*
X53500Y307300D03*
X85300Y335750D03*
X69500Y322000D03*
X103500Y302100D03*
X99770Y325249D03*
X67400Y391690D03*
X67230Y397380D03*
X67710Y402040D03*
X55616Y368998D03*
X52000Y354500D03*
X61000Y383000D03*
X57500Y388100D03*
X77300Y390600D03*
X107224Y393848D03*
X76500Y368300D03*
X76300Y358400D03*
X82037Y358542D03*
X70600Y368400D03*
X82100Y368300D03*
X70900Y358300D03*
X51500Y406000D03*
X57471Y410749D03*
X64007Y408276D03*
X63630Y424280D03*
X63600Y429000D03*
X51890Y424470D03*
Y418970D03*
X103100Y411800D03*
X72603Y474072D03*
X60300Y508650D03*
X51607Y511747D03*
X74480Y504480D03*
X79630Y504580D03*
X60000Y526500D03*
X79400Y502150D03*
X74600Y502064D03*
X77000Y502133D03*
X49800Y524300D03*
X76996Y504587D03*
X60700Y521900D03*
X57936Y516012D03*
X60202Y495342D03*
X57302Y495442D03*
X105958Y518550D03*
X106392Y537000D03*
X105392Y574800D03*
X105412Y556580D03*
X105000Y614533D03*
X82459Y618932D03*
X105352Y594770D03*
X101898Y611483D03*
X150391Y14814D03*
X163427Y14714D03*
X157084Y14814D03*
X160431Y-1801D03*
X153738Y9114D03*
X150391Y-7851D03*
X163391D03*
X157084D03*
X153738Y-1751D03*
X160431Y9114D03*
X126616Y14714D03*
X136756Y16900D03*
X120273Y16839D03*
X132959Y14814D03*
X141880Y17114D03*
X147045Y9114D03*
X130163D03*
X141856Y9100D03*
X136780Y9098D03*
X123620Y9114D03*
X126580Y-7851D03*
X132959Y-7700D03*
X120273Y-9901D03*
X141893Y-9864D03*
X136806Y-9650D03*
X136780Y-1801D03*
X123620D03*
X130313Y-1751D03*
X141906Y-2050D03*
X147045Y-1751D03*
X169770Y14814D03*
X167124Y-1751D03*
X169770Y-7700D03*
X166974Y9114D03*
X169770Y30100D03*
X120273Y27899D03*
X141893Y27936D03*
X136806Y28150D03*
X126580Y29949D03*
X132959Y30100D03*
X157084Y29949D03*
X163391D03*
X150391D03*
X169770Y90364D03*
X166974Y84714D03*
Y73849D03*
Y46914D03*
X169770Y52614D03*
X167124Y36049D03*
X169770Y67900D03*
X157084Y67749D03*
X163391D03*
X130313Y73849D03*
X123620Y73799D03*
X141906Y73550D03*
X136780Y73799D03*
X126580Y67749D03*
X132959Y67900D03*
X141880Y54914D03*
X123620Y35983D03*
X141856Y46900D03*
X141906Y35750D03*
X136806Y65950D03*
X141893Y65736D03*
X136756Y54700D03*
X136780Y35999D03*
X130313Y35983D03*
X123620Y46914D03*
X132959Y52614D03*
X126616Y52514D03*
X147045Y46914D03*
Y36049D03*
X120273Y54839D03*
Y92500D03*
X126616Y90314D03*
X132959Y90414D03*
X141880Y92714D03*
X163427Y90314D03*
X157084Y90414D03*
X150391D03*
X160431Y84714D03*
X153738D03*
X136756Y92500D03*
X141856Y84700D03*
X136780Y84698D03*
X123620Y84714D03*
X147045D03*
X130163D03*
Y46914D03*
X136780Y46898D03*
X120273Y66000D03*
X147045Y73849D03*
X153738Y36049D03*
Y73849D03*
X160431Y73799D03*
X157084Y52614D03*
X160431Y35999D03*
X150391Y67749D03*
Y52614D03*
X163427Y52514D03*
X160431Y46914D03*
X153738D03*
X156954Y192872D03*
X154454Y193021D03*
X151810Y192670D03*
X124895Y212033D03*
X153788Y187309D03*
X156928Y190053D03*
X148900Y180400D03*
X148800Y185300D03*
Y182900D03*
X148900Y190100D03*
X148800Y187700D03*
X113800Y180500D03*
X116900D03*
X151359Y187700D03*
X156294Y187625D03*
X151300Y190200D03*
X141263Y215216D03*
X125563Y218616D03*
X137763Y217716D03*
X128500Y218700D03*
X141263Y217716D03*
X137763Y215216D03*
X154130Y190186D03*
X169150Y223600D03*
Y227600D03*
X112904Y237218D03*
X122820Y244133D03*
X123074Y275948D03*
X113100Y269163D03*
X125624Y223633D03*
Y221133D03*
X141263Y234216D03*
X141200Y229600D03*
X141211Y225615D03*
X141300Y221700D03*
X139763Y231700D03*
Y227600D03*
Y223700D03*
X139582Y219800D03*
X128200Y250700D03*
X125563Y250616D03*
X141263Y249716D03*
Y247216D03*
X137763D03*
Y249716D03*
X125624Y255633D03*
X141300Y253700D03*
X139631Y251900D03*
X125624Y253133D03*
X137763Y279216D03*
X141263Y266216D03*
X139763Y255700D03*
Y259600D03*
X139800Y263700D03*
X141313Y257533D03*
X141263Y279216D03*
X141200Y261600D03*
X137300Y337200D03*
X118800Y298400D03*
X123301Y308044D03*
X110180Y280920D03*
X109960Y313190D03*
X119050Y341625D03*
X113000Y304000D03*
X113100Y333106D03*
X125624Y287633D03*
X128200Y282600D03*
X141263Y311216D03*
X137763D03*
X141263Y281716D03*
X139730Y284200D03*
X139763Y288200D03*
Y292000D03*
Y296000D03*
X125624Y285133D03*
X141200Y286100D03*
X141261Y290076D03*
X141300Y294000D03*
X141263Y298216D03*
X137763Y281716D03*
X125563Y282616D03*
X141211Y325515D03*
X128200Y314800D03*
X141263Y330216D03*
X139763Y327800D03*
X141300Y317500D03*
Y321500D03*
X139582Y315800D03*
X139763Y319400D03*
X125563Y314616D03*
X141263Y313716D03*
X137763D03*
X139763Y323600D03*
X125624Y317133D03*
Y319633D03*
X109640Y376070D03*
X113500Y369000D03*
X110670Y344500D03*
X112600Y366300D03*
X122300Y372100D03*
X119300Y400900D03*
X110397Y402603D03*
X109924Y393848D03*
X141289Y349488D03*
X128100Y346700D03*
X141300Y353300D03*
X141200Y357200D03*
X137763Y345716D03*
X141263D03*
Y343216D03*
X125624Y349133D03*
X137763Y343216D03*
X141263Y362216D03*
X139582Y347800D03*
X139763Y351400D03*
Y355200D03*
Y359500D03*
X125624Y351633D03*
X125563Y346616D03*
X141300Y381800D03*
X139763Y384000D03*
X125624Y381133D03*
X141263Y394216D03*
Y390416D03*
X141261Y385876D03*
X139736Y392300D03*
X125563Y378616D03*
X137763Y375216D03*
X141263D03*
Y377716D03*
X137763D03*
X139631Y379900D03*
X128500Y378700D03*
X139900Y388000D03*
X125624Y383633D03*
X117363Y417416D03*
X130163Y510114D03*
X147045D03*
X132959Y515814D03*
X126616Y515714D03*
X120273Y517900D03*
X136780Y510098D03*
X136756Y517900D03*
X141856Y510100D03*
X141880Y518114D03*
X123620Y510114D03*
X150391Y515814D03*
X169770Y515764D03*
X163427Y515714D03*
X166974Y510114D03*
X160431D03*
X157084Y515814D03*
X153738Y510114D03*
X141893Y528936D03*
X136806Y529150D03*
X141906Y536750D03*
X132959Y553614D03*
X126616Y553514D03*
X130163Y547914D03*
X123620D03*
X136780Y547898D03*
X141856Y547900D03*
X147045Y537049D03*
Y547914D03*
X120210Y529200D03*
X130313Y537049D03*
X132959Y531100D03*
X126580Y530949D03*
X123620Y536999D03*
X136780D03*
X123620Y574799D03*
X130313Y574849D03*
X132959Y568900D03*
X126580Y568749D03*
X141856Y585700D03*
X141906Y574550D03*
X136780Y574799D03*
Y585698D03*
X120092Y566900D03*
X136806Y566950D03*
X147045Y585714D03*
Y574849D03*
X141880Y555914D03*
X120273Y555700D03*
X136756D03*
X141893Y566736D03*
X130163Y585714D03*
X123620D03*
X150391Y530949D03*
Y553614D03*
X166974Y537049D03*
X163391Y530949D03*
X160431Y536999D03*
X169770Y553564D03*
X163427Y553514D03*
X166974Y547914D03*
X160431D03*
X157084Y530949D03*
X153738Y537049D03*
X157084Y553614D03*
X153738Y547914D03*
X169770Y531100D03*
X150391Y568749D03*
X163391D03*
X160431Y585714D03*
X166974D03*
Y574849D03*
X160431Y574799D03*
X169770Y568900D03*
X157084Y568749D03*
X153738Y585714D03*
Y574849D03*
X147045Y612649D03*
X123620Y612599D03*
X136780D03*
X130313Y612649D03*
X160431Y612599D03*
X166974Y612649D03*
X153738D03*
X126616Y591314D03*
X116992Y590700D03*
X132959Y591414D03*
X136756Y593500D03*
X141880Y593714D03*
X132959Y606700D03*
X126580Y606549D03*
X120092Y604900D03*
X141906Y612350D03*
X136806Y604750D03*
X141893Y604536D03*
X150391Y591414D03*
Y606549D03*
X163427Y591314D03*
X163391Y606549D03*
X169770Y606700D03*
Y591364D03*
X157084Y591414D03*
Y606549D03*
X173591Y-1801D03*
X178691Y17114D03*
X173567Y16900D03*
X178717Y-2050D03*
X183856Y-1751D03*
X173617Y-9650D03*
X178704Y-9864D03*
X178667Y9100D03*
X173591Y9098D03*
X183856Y9114D03*
X178704Y27936D03*
X173617Y28150D03*
X190549Y9114D03*
X197242D03*
X210402Y9098D03*
X210428Y-9650D03*
X193895Y-7851D03*
X187202D03*
X200202D03*
X210402Y-1801D03*
X190549Y-1751D03*
X197242Y-1801D03*
X203935Y-1751D03*
X206581Y-7700D03*
X203785Y9114D03*
X210378Y16900D03*
X210428Y28150D03*
X200202Y29949D03*
X187202D03*
X193895Y14814D03*
Y29949D03*
X200238Y14714D03*
X187202Y14814D03*
X206581D03*
Y30100D03*
X220667Y-1751D03*
X215528Y-2050D03*
X215515Y-9864D03*
X227360Y-1751D03*
X230706Y-7851D03*
X224013D03*
X215478Y9100D03*
X220667Y9114D03*
X227360D03*
X224013Y29949D03*
X230706D03*
Y14814D03*
X224013D03*
X215502Y17114D03*
X215515Y27936D03*
X178691Y92714D03*
X173591Y84698D03*
X178667Y84700D03*
X183856Y84714D03*
X173567Y92500D03*
X183856Y36049D03*
X173591Y46898D03*
X183856Y73849D03*
X178717Y73550D03*
X173591Y73799D03*
X178691Y54914D03*
X173591Y35999D03*
X183856Y46914D03*
X178717Y35750D03*
X178667Y46900D03*
X173567Y54700D03*
X173617Y65950D03*
X178704Y65736D03*
X206581Y52614D03*
X210378Y54700D03*
X210402Y46898D03*
X193895Y67749D03*
X200202D03*
X187202D03*
X203785Y46914D03*
X190549D03*
X197242D03*
X200238Y52514D03*
X193895Y52614D03*
X187202D03*
X190549Y36049D03*
X203935D03*
X197242Y35999D03*
X206581Y67900D03*
X210428Y65950D03*
X210402Y35999D03*
X197242Y73799D03*
X203935Y73849D03*
X210402Y73799D03*
Y84698D03*
X210378Y92500D03*
X190549Y73849D03*
Y84714D03*
X197242D03*
X203785D03*
X193895Y90414D03*
X206581D03*
X200238Y90314D03*
X187202Y90414D03*
X215478Y46900D03*
X215502Y54914D03*
X215515Y65736D03*
X224013Y52614D03*
X220667Y46914D03*
X230706Y52614D03*
X224013Y67749D03*
X230706D03*
X227360Y46914D03*
Y36049D03*
X220667D03*
X215528Y35750D03*
X215502Y92714D03*
X220667Y73849D03*
Y84714D03*
X227360D03*
X230706Y90414D03*
X215478Y84700D03*
X215528Y73550D03*
X227360Y73849D03*
X224013Y90414D03*
X197617Y243089D03*
X191537Y242989D03*
Y240489D03*
X197617Y240589D03*
X191537Y237989D03*
X197617Y238089D03*
X192037Y270750D03*
X194537D03*
X197037D03*
X194537Y299750D03*
X197037D03*
X192037D03*
X194537Y332480D03*
X197037D03*
X192037D03*
X194500Y360200D03*
X197137Y360350D03*
X191900Y360173D03*
X195200Y377800D03*
Y380300D03*
X172697Y407196D03*
X197242Y510114D03*
X200238Y515714D03*
X203785Y510114D03*
X190549D03*
X187202Y515814D03*
X193895D03*
X183856Y510114D03*
X173591Y510098D03*
X173567Y517900D03*
X178691Y518114D03*
X206581Y515814D03*
X210402Y510098D03*
X210378Y517900D03*
X215502Y518114D03*
X215478Y510100D03*
X224013Y515814D03*
X220667Y510114D03*
X227360D03*
X230706Y515814D03*
X193895Y553614D03*
X200238Y553514D03*
X183856Y547914D03*
X190549D03*
X203785D03*
X197242D03*
X190549Y537049D03*
X183856D03*
X187202Y530949D03*
X193895D03*
X197242Y536999D03*
X203935Y537049D03*
X200202Y530949D03*
X206581Y553614D03*
X210402Y547898D03*
X178717Y536750D03*
X173617Y529150D03*
X173591Y536999D03*
X178704Y528936D03*
X178667Y547900D03*
X173591Y547898D03*
X206581Y531100D03*
X210402Y536999D03*
X210428Y529150D03*
X187202Y553614D03*
X178691Y555914D03*
X173567Y555700D03*
X210378D03*
X203935Y574849D03*
X200202Y568749D03*
X197242Y574799D03*
X190549Y585714D03*
X183856D03*
X187202Y568749D03*
X193895D03*
X190549Y574849D03*
X183856D03*
X210402Y585698D03*
X206581Y568900D03*
X210428Y566950D03*
X210402Y574799D03*
X178667Y585700D03*
X178717Y574550D03*
X173591Y574799D03*
Y585698D03*
X173617Y566950D03*
X178704Y566736D03*
X197242Y585714D03*
X203785D03*
X215515Y528936D03*
X215528Y536750D03*
X215478Y547900D03*
X224013Y530949D03*
X220667Y537049D03*
X230706Y530949D03*
X227360Y537049D03*
X230706Y553614D03*
X220667Y547914D03*
X227360D03*
X224013Y553614D03*
X215502Y555914D03*
X220667Y585714D03*
X215528Y574550D03*
X215478Y585700D03*
X215515Y566736D03*
X224013Y568749D03*
X220667Y574849D03*
X230706Y568749D03*
X227360Y574849D03*
Y585714D03*
Y612649D03*
X220667D03*
X203935D03*
X197242Y612599D03*
X190549Y612649D03*
X183856D03*
X210402Y612599D03*
X173591D03*
X187202Y591414D03*
X193895D03*
X187202Y606549D03*
X193895D03*
X200202D03*
X210428Y604750D03*
X206581Y606700D03*
X210378Y593500D03*
X206581Y591414D03*
X178717Y612350D03*
X173617Y604750D03*
X178704Y604536D03*
X173567Y593500D03*
X178691Y593714D03*
X200238Y591314D03*
X224013Y606549D03*
X230706D03*
Y591414D03*
X215515Y604536D03*
X215528Y612350D03*
X215502Y593714D03*
X224013Y591414D03*
X270864Y-1801D03*
X247213D03*
X240746Y-1751D03*
X264171D03*
X252339Y-2050D03*
X234053Y-1801D03*
X257478Y-1751D03*
X243392Y-7700D03*
X260824Y-7851D03*
X252326Y-9864D03*
X237013Y-7851D03*
X247239Y-9650D03*
X267517Y-7851D03*
X252289Y9100D03*
X264171Y9114D03*
X240596D03*
X247213Y9098D03*
X270864Y9114D03*
X234053D03*
X257478D03*
X267517Y14814D03*
Y29949D03*
X247189Y16900D03*
X252326Y27936D03*
X243392Y30100D03*
X247239Y28150D03*
X260824Y29949D03*
X237013D03*
X252313Y17114D03*
X243392Y14814D03*
X260824D03*
X237049Y14714D03*
X284050Y-9650D03*
X289137Y-9864D03*
X273824Y-7851D03*
X280203Y-7700D03*
X289100Y9100D03*
X284024Y9098D03*
X277407Y9114D03*
X277557Y-1751D03*
X289150Y-2050D03*
X284024Y-1801D03*
X273824Y29949D03*
X273860Y14714D03*
X284000Y16900D03*
X280203Y14814D03*
Y30100D03*
X289124Y17114D03*
X284050Y28150D03*
X289137Y27936D03*
X247213Y46898D03*
X257478Y46914D03*
X240596D03*
X243392Y67900D03*
X267517Y67749D03*
Y52614D03*
X270864Y46914D03*
X252326Y65736D03*
X237013Y67749D03*
X260824D03*
X247239Y65950D03*
X243392Y52614D03*
X264171Y46914D03*
X247213Y35999D03*
X257478Y36049D03*
X252339Y35750D03*
X234053Y35999D03*
X240746Y36049D03*
X264171D03*
X237049Y52514D03*
X252289Y46900D03*
X247189Y54700D03*
X252313Y54914D03*
X260824Y52614D03*
X270864Y35999D03*
X234053Y46914D03*
X247213Y73799D03*
Y84698D03*
X264171Y84714D03*
X252339Y73550D03*
X257478Y84714D03*
X240746Y73849D03*
X257478D03*
X234053Y73799D03*
X264171Y73849D03*
X243392Y90414D03*
X252313Y92714D03*
X237049Y90314D03*
X270864Y84714D03*
X247189Y92500D03*
X240596Y84714D03*
X234053D03*
X252289Y84700D03*
X260824Y90414D03*
X267517D03*
X270864Y73799D03*
X273824Y67749D03*
X280203Y67900D03*
X284024Y35999D03*
X277557Y36049D03*
X277407Y46914D03*
X289137Y65736D03*
X284050Y65950D03*
X284024Y46898D03*
X284000Y54700D03*
X289100Y46900D03*
X289150Y35750D03*
X289124Y54914D03*
X280203Y52614D03*
X273860Y90314D03*
X277407Y84714D03*
X289100Y84700D03*
X284024Y84698D03*
X284000Y92500D03*
X289150Y73550D03*
X284024Y73799D03*
X289124Y92714D03*
X280203Y90414D03*
X277407Y73849D03*
X264171Y104284D03*
X267517Y109984D03*
X270864Y104284D03*
X257478D03*
X260824Y109984D03*
X243392Y109534D03*
X252339Y112865D03*
X247213Y113114D03*
X237049Y109884D03*
X240596Y104284D03*
X247239Y105265D03*
X252326Y105051D03*
X234053Y104284D03*
X273860Y109884D03*
X284050Y105265D03*
X289137Y105051D03*
X289150Y112865D03*
X284024Y113114D03*
X280203Y109534D03*
X277407Y104284D03*
X271239Y211060D03*
X284759Y207159D03*
X291519D03*
X274619Y213009D03*
Y216909D03*
X277999Y211060D03*
Y214960D03*
Y203260D03*
Y207159D03*
X281379Y213009D03*
X288139Y216909D03*
X284759Y214960D03*
X291519D03*
Y218860D03*
X281379Y201309D03*
X284759Y199360D03*
X291519D03*
X267859Y244209D03*
Y240309D03*
X271239Y238360D03*
X264179D03*
Y250060D03*
X264092Y222710D03*
X264179Y226660D03*
X271239Y269560D03*
Y273460D03*
Y265660D03*
X267859Y263709D03*
Y259809D03*
X264179Y265660D03*
X267859Y252009D03*
X264179Y253960D03*
X291519Y238360D03*
X284759Y234460D03*
X288139Y232509D03*
X281379D03*
X277999Y234460D03*
X274619Y232509D03*
Y220809D03*
Y224709D03*
Y228610D03*
X277999Y230559D03*
X274619Y244209D03*
X277999Y250060D03*
X274619Y240309D03*
Y248109D03*
Y236409D03*
X291519Y246160D03*
Y250060D03*
X284759Y246160D03*
X291519Y242260D03*
X281379Y220809D03*
X284759Y226660D03*
X288139Y236409D03*
X291519Y234460D03*
Y222760D03*
Y230559D03*
Y226660D03*
X281379Y240309D03*
Y252009D03*
X274619D03*
X277999Y253960D03*
X284759D03*
X291519D03*
X284759Y265660D03*
X291519D03*
Y277360D03*
X281379Y275409D03*
Y271509D03*
X284759Y277360D03*
Y273460D03*
X288139Y275409D03*
Y271509D03*
X277999Y277360D03*
X274619Y255909D03*
Y259809D03*
X277999Y269560D03*
X274619Y275409D03*
Y267609D03*
Y263709D03*
X288139Y255909D03*
X291519Y269560D03*
Y257860D03*
Y261760D03*
X281379Y259809D03*
X288139Y252009D03*
X271239Y328060D03*
X267859Y333909D03*
Y341709D03*
Y330009D03*
X264179Y328060D03*
Y339760D03*
X291519Y285160D03*
Y292959D03*
X284759Y285160D03*
X277999Y308560D03*
Y300760D03*
Y292959D03*
Y285160D03*
X291519Y308560D03*
X284759D03*
Y300760D03*
X291519D03*
X284759Y292959D03*
X291519Y316360D03*
X281379Y318309D03*
X291519Y328060D03*
X288139Y341709D03*
X274619Y330009D03*
Y326110D03*
Y322209D03*
X277999Y328060D03*
X274619Y341709D03*
X277999Y320260D03*
Y316360D03*
X274619Y333909D03*
Y337809D03*
X284759Y324160D03*
X288139Y318309D03*
X284759Y316360D03*
X281379Y337809D03*
X291519Y339760D03*
Y335860D03*
X284759Y331960D03*
X291519D03*
X281379Y326110D03*
X288139D03*
X267559Y369010D03*
X271239Y355360D03*
X267859Y349509D03*
Y353409D03*
X267559Y361209D03*
X264179Y343660D03*
Y355360D03*
X267492Y380709D03*
X271239Y390460D03*
X267859Y388509D03*
X271239Y382660D03*
X284759Y351460D03*
X281379Y345609D03*
X291519Y359260D03*
Y355360D03*
Y351460D03*
X284759Y343660D03*
X274619Y365109D03*
X277999Y363160D03*
Y367060D03*
X274619Y369010D03*
Y361209D03*
Y345609D03*
X277999Y347560D03*
X274619Y353409D03*
Y357309D03*
Y349509D03*
X277999Y343660D03*
X291519Y347560D03*
Y343660D03*
X288139Y365109D03*
X281379D03*
X284759Y363160D03*
X291519D03*
X284759Y370959D03*
X291519Y367060D03*
Y370959D03*
X288139Y361209D03*
X281379Y357309D03*
X288139Y345609D03*
Y380709D03*
Y400209D03*
X274619Y380709D03*
X277999Y394359D03*
X274619Y392410D03*
X277999Y390460D03*
Y386560D03*
X274619Y376809D03*
Y372909D03*
X291519Y374860D03*
X277999Y382660D03*
X284759Y398260D03*
X281379Y396309D03*
X291519Y398260D03*
X284759Y390460D03*
X291519D03*
X281379Y376809D03*
Y384609D03*
X284759Y382660D03*
X291519D03*
Y378760D03*
X264171Y510114D03*
X257478D03*
X260824Y515814D03*
Y491044D03*
X247177Y490514D03*
X252313D03*
X236892Y493400D03*
X243392Y493094D03*
X267584Y491219D03*
X271092Y495944D03*
X257392Y495800D03*
X264192D03*
X233292Y495900D03*
X239492Y498500D03*
X247177Y498514D03*
X252313D03*
X252289Y510100D03*
X267517Y515814D03*
X270864Y510114D03*
X247189Y517900D03*
X252313Y518114D03*
X247213Y510098D03*
X240596Y510114D03*
X243392Y515814D03*
X234053Y510114D03*
X237049Y515714D03*
X284024Y490644D03*
X289124D03*
X273860Y515714D03*
X277557Y495944D03*
X277407Y510114D03*
X289100Y510100D03*
X289124Y518114D03*
X284024Y510098D03*
X280203Y515814D03*
X273992Y491144D03*
X280203Y490644D03*
X284024Y498644D03*
X289124D03*
X284000Y517900D03*
X257478Y537049D03*
X237013Y530949D03*
X252339Y536750D03*
X243392Y531100D03*
X247213Y536999D03*
X252326Y528936D03*
X240746Y537049D03*
X234053Y536999D03*
X267517Y553614D03*
X270864Y547914D03*
X267517Y530949D03*
X270864Y536999D03*
X260824Y553614D03*
X237049Y553514D03*
X243392Y553614D03*
X264171Y547914D03*
X257478D03*
X252289Y547900D03*
X240596Y547914D03*
X247213Y547898D03*
X234053Y547914D03*
X264171Y537049D03*
X260824Y530949D03*
X247189Y555700D03*
X252313Y555914D03*
X270864Y574799D03*
Y585714D03*
X267517Y568749D03*
X247239Y566950D03*
X252326Y566736D03*
X234053Y574799D03*
X240746Y574849D03*
X247213Y574799D03*
X234053Y585714D03*
X237013Y568749D03*
X264171Y585714D03*
X257478D03*
X264171Y574849D03*
X257478D03*
X260824Y568749D03*
X252339Y574550D03*
X252289Y585700D03*
X240596Y585714D03*
X247213Y585698D03*
X243392Y568900D03*
X277407Y537049D03*
X273824Y530949D03*
X273860Y553514D03*
X284024Y547898D03*
X289100Y547900D03*
X280203Y553614D03*
Y531100D03*
X284024Y536999D03*
X289137Y528936D03*
X284050Y529150D03*
X289150Y536750D03*
X277407Y547914D03*
X273824Y568749D03*
X284000Y555700D03*
X289124Y555914D03*
X280203Y568900D03*
X277407Y574849D03*
Y585714D03*
X289100Y585700D03*
X289150Y574550D03*
X284024Y574799D03*
Y585698D03*
X284050Y566950D03*
X289137Y566736D03*
X284024Y612599D03*
X240746Y612649D03*
X247213Y612599D03*
X234053D03*
X257478Y612649D03*
X247239Y604750D03*
X252326Y604536D03*
X260824Y606549D03*
X237013D03*
X243392Y606700D03*
X264171Y612449D03*
X252339Y612350D03*
X267517Y591414D03*
X260824D03*
X237049Y591314D03*
X247189Y593500D03*
X252313Y593714D03*
X243392Y591414D03*
X267517Y606549D03*
X270864Y612399D03*
X273824Y606549D03*
X273860Y591314D03*
X284050Y604750D03*
X289150Y612350D03*
X280203Y606700D03*
Y591414D03*
X277407Y612449D03*
X289124Y593714D03*
X284000Y593500D03*
X289137Y604536D03*
X297635Y-7851D03*
X304328D03*
X300982Y-1751D03*
X294289D03*
Y9114D03*
X300982D03*
X307675Y-1843D03*
X311021Y28014D03*
X307675Y9300D03*
X304328Y29949D03*
X307992Y13200D03*
X297635Y14814D03*
X321192Y13200D03*
X308092Y32100D03*
X297635Y29949D03*
X304328Y14814D03*
X317714Y28014D03*
X327754D03*
X334292Y13200D03*
X347833Y28022D03*
X337793Y28014D03*
X311021Y65814D03*
X317714D03*
X321061Y35957D03*
X307950Y50729D03*
X300982Y36049D03*
X294289Y46914D03*
X304328Y52614D03*
X307675Y35957D03*
X304328Y67749D03*
X297635D03*
X294289Y36049D03*
X300982Y46914D03*
X297635Y52614D03*
X314368Y35957D03*
Y46914D03*
X311021Y54857D03*
X317714D03*
X321061Y46914D03*
X331100D03*
X327754Y65814D03*
X331100Y35957D03*
X327754Y54857D03*
Y92757D03*
X331100Y84714D03*
Y73757D03*
X314368D03*
Y87392D03*
X311021Y89964D03*
X317714D03*
X321061Y87392D03*
Y73757D03*
X307992Y70400D03*
X304278Y90414D03*
X307592Y73800D03*
X300982Y84714D03*
X294289D03*
X300982Y73849D03*
X294289D03*
X308166Y87394D03*
X297635Y90414D03*
X341140Y35957D03*
X337793Y65814D03*
Y54857D03*
X351179Y46922D03*
X347833Y54857D03*
X341140Y46922D03*
X347833Y65822D03*
X351179Y35957D03*
X347833Y92757D03*
X351179Y84599D03*
Y73757D03*
X337793Y89964D03*
X341140Y87392D03*
Y73757D03*
X326592Y105600D03*
X313637Y105725D03*
X300992Y112300D03*
X297642Y107700D03*
X304192Y105000D03*
X294899Y213009D03*
X308418Y201309D03*
X317428Y193507D03*
X301648Y194841D03*
X332078Y218860D03*
X329818Y214958D03*
X298279Y218860D03*
X311798Y211060D03*
Y218860D03*
Y214960D03*
X308418Y213009D03*
X305039Y211060D03*
Y218860D03*
X324200Y201308D03*
X298279Y199360D03*
X294899Y201309D03*
X312918Y205210D03*
X315178Y209109D03*
X298279Y207159D03*
Y203260D03*
Y211060D03*
X318558Y218860D03*
X315178Y216909D03*
Y213009D03*
X301659Y209109D03*
X325318Y211060D03*
X338838Y218860D03*
X345598Y214960D03*
X352357D03*
X334328Y199108D03*
X345598Y203260D03*
X355737Y205210D03*
X294899Y224709D03*
X332078Y242260D03*
Y250060D03*
X328698Y232509D03*
Y220809D03*
X332078Y234460D03*
X298279Y246160D03*
X325318Y250060D03*
X321938Y248109D03*
X305039Y246160D03*
X308418Y244209D03*
X294899D03*
Y248109D03*
X325318Y242260D03*
Y226660D03*
X298279Y234460D03*
X308418Y228610D03*
Y224709D03*
X305039Y230559D03*
X311798Y222760D03*
X308418Y232509D03*
X294899Y228610D03*
X325318Y234460D03*
Y230559D03*
Y222760D03*
X305039Y250060D03*
X318558Y246160D03*
X301659Y248109D03*
X308418Y240309D03*
X315178D03*
X301659D03*
X318558Y242260D03*
X298279Y226660D03*
X318558D03*
X315178Y220809D03*
X321938D03*
X315178Y232509D03*
X301659Y228610D03*
X308418Y236409D03*
X321938D03*
X311798Y238360D03*
X318558D03*
X305039Y226660D03*
X308418Y252009D03*
X298279Y253960D03*
X325318D03*
X308418Y275409D03*
X301659D03*
X308418Y255909D03*
X321938Y275409D03*
X315178Y279310D03*
X318558Y277360D03*
X311798Y261760D03*
X321938Y259809D03*
X301659D03*
X308418Y263709D03*
X325318Y269560D03*
X305039D03*
X318558D03*
X328698Y267609D03*
Y259809D03*
X332078Y269560D03*
X321938Y255909D03*
X308418Y259809D03*
X325318Y273460D03*
Y265660D03*
X301659Y267609D03*
X321938Y263709D03*
X294899Y275409D03*
Y263709D03*
X298279Y265660D03*
X305039Y273460D03*
Y277360D03*
X311798D03*
Y269560D03*
X305039Y265660D03*
X298279Y277360D03*
X328698Y252009D03*
X342218Y244209D03*
Y232509D03*
X355737Y244209D03*
X348978D03*
X345598Y226660D03*
X352357D03*
X348978Y232509D03*
X355737D03*
X338838Y246160D03*
X335458Y248109D03*
X338838Y242260D03*
Y234460D03*
X335458Y236409D03*
X338838Y238360D03*
X355737Y248109D03*
X348978D03*
X338838Y253960D03*
X335458Y252009D03*
X338838Y265660D03*
X335458Y259809D03*
Y267609D03*
X345598Y265660D03*
X348978Y263709D03*
X355737Y259809D03*
X352357Y261760D03*
X345598Y273460D03*
Y269560D03*
X342218Y263709D03*
Y271509D03*
Y259809D03*
Y255909D03*
Y267609D03*
Y279310D03*
Y275409D03*
X311798Y292959D03*
X305039D03*
X321938Y283209D03*
X315178D03*
X318558Y281260D03*
Y292959D03*
X311798Y285160D03*
X328698Y310509D03*
X332078Y300760D03*
X328698Y283209D03*
X332078Y292959D03*
Y281260D03*
X298279Y308560D03*
X321938Y310509D03*
X315178D03*
X305039Y308560D03*
X311798D03*
X305039Y300760D03*
X325318D03*
X311798D03*
X298279D03*
X318558D03*
X325318Y292959D03*
Y281260D03*
X305039Y285160D03*
X298279D03*
Y292959D03*
X318558Y312460D03*
X325318D03*
X308418Y333909D03*
Y341709D03*
X325318Y339760D03*
Y335860D03*
X301659Y337809D03*
X315178Y330009D03*
X301659D03*
X308418Y337809D03*
X305039Y331960D03*
X298279Y328060D03*
Y331960D03*
X311798Y324160D03*
X308418Y330009D03*
X315178Y322209D03*
X321938D03*
X294899Y333909D03*
X305039Y328060D03*
X321938Y330009D03*
Y337809D03*
X328698Y330009D03*
Y326110D03*
Y333909D03*
X325318Y324160D03*
X318558Y320260D03*
X301659Y318309D03*
X308418D03*
X305039Y316360D03*
X332078Y331960D03*
Y339760D03*
X298279Y316360D03*
X294899Y322209D03*
Y318309D03*
X311798Y316360D03*
X308418Y326110D03*
X315178Y314409D03*
X332078Y312460D03*
X335458Y310509D03*
X338838Y300760D03*
Y292959D03*
Y281260D03*
X335458Y283209D03*
X342218Y310509D03*
Y283209D03*
X345598Y335860D03*
Y331960D03*
X342218Y314409D03*
X338838Y312460D03*
Y316360D03*
X335458Y330009D03*
X338838Y331960D03*
Y339760D03*
X345598Y328060D03*
Y339760D03*
X352357Y335860D03*
X348978Y333909D03*
X342218Y322209D03*
Y318309D03*
Y330009D03*
Y326110D03*
Y333909D03*
X355737Y337809D03*
X345598Y320260D03*
Y324160D03*
X308418Y357309D03*
X311798Y359260D03*
X298279Y351460D03*
X294899Y349509D03*
Y353409D03*
X321938Y349509D03*
X318558Y359260D03*
X321938Y361209D03*
X298279Y343660D03*
X315178Y357309D03*
X301659D03*
Y349509D03*
X308418Y361209D03*
Y353409D03*
Y345609D03*
X305039Y347560D03*
X325318Y343660D03*
Y347560D03*
X328698Y365109D03*
X332078Y363160D03*
X328698Y345609D03*
X325318Y355360D03*
X332078Y347560D03*
Y355360D03*
X294899Y369010D03*
X325318Y367060D03*
Y370959D03*
X318558D03*
X308418Y365109D03*
X315178D03*
X325318Y363160D03*
X298279D03*
X305039Y370959D03*
X308418Y369010D03*
X305039Y367060D03*
X301659Y369010D03*
X298279Y370959D03*
X318558Y351460D03*
Y355360D03*
X305039Y351460D03*
X301659Y388509D03*
X308418D03*
X318558Y394359D03*
X324458Y399911D03*
X332078Y378760D03*
X318558Y386560D03*
X325318D03*
X311798Y374860D03*
X325318D03*
X294899Y372909D03*
X308418D03*
X321938Y376809D03*
X318558Y382660D03*
Y378760D03*
X298279D03*
X305039D03*
X308418Y384609D03*
X311798Y382660D03*
Y378760D03*
X315178Y376809D03*
X328698D03*
X294899Y384609D03*
X318558Y390460D03*
X320808Y401941D03*
X298279Y386560D03*
Y390460D03*
X315178Y392410D03*
Y388509D03*
X311798Y386560D03*
X298279Y398260D03*
Y394359D03*
X294899Y396309D03*
X325318Y378760D03*
X321938Y380709D03*
X305039Y394359D03*
X302608Y402421D03*
X345598Y370959D03*
X355737Y353409D03*
X348978D03*
X342218Y365109D03*
X338838Y347560D03*
Y351460D03*
X335458Y349509D03*
X348978D03*
X345598Y343660D03*
X342218Y345609D03*
X355737Y349509D03*
X342218Y353409D03*
X338838Y367060D03*
X348978Y365109D03*
X355737D03*
X352357Y370959D03*
X338838Y382660D03*
X345598D03*
X352357D03*
X348978Y392410D03*
X355737D03*
X294289Y490444D03*
X301092Y490700D03*
X326797Y499767D03*
X317714Y515364D03*
X321061Y512792D03*
X311701Y499136D03*
X331100Y510114D03*
X327754Y518157D03*
X314368Y512792D03*
X311021Y515364D03*
X297835Y497644D03*
X308166Y512794D03*
X300982Y510114D03*
X304278Y515814D03*
X297635D03*
X294289Y510114D03*
X304392Y497300D03*
X337793Y515364D03*
X350882Y509999D03*
X347833Y518157D03*
X341140Y512792D03*
X321061Y536957D03*
X317714Y529014D03*
X331100Y547914D03*
Y536957D03*
X327754Y529014D03*
X321061Y547914D03*
X314368D03*
Y536957D03*
X311021Y529014D03*
X307675Y548200D03*
X304278Y553614D03*
X297635D03*
X300982Y547914D03*
X294289D03*
X307675Y536957D03*
X304328Y530949D03*
X300982Y537049D03*
X297635Y530949D03*
X294289Y537049D03*
X307992Y533100D03*
X308100Y552000D03*
X307992Y570900D03*
X294289Y574849D03*
Y585714D03*
X304328Y568749D03*
X307675Y574757D03*
X300982Y574849D03*
X307848Y588334D03*
X300982Y585714D03*
X297635Y568749D03*
X327754Y555857D03*
X317714D03*
X311021D03*
X327754Y566814D03*
X331100Y574757D03*
X314368D03*
X317714Y566814D03*
X311021D03*
X321061Y574757D03*
X337793Y529014D03*
X351179Y547922D03*
Y536957D03*
X347833Y529022D03*
X341140Y547922D03*
Y536957D03*
X337793Y555857D03*
X347833D03*
X337793Y566814D03*
X341140Y574757D03*
X351179D03*
X347833Y566822D03*
X304328Y606549D03*
X297635D03*
X294289Y612249D03*
X300982D03*
X307675Y611600D03*
X307892Y591000D03*
X321192Y589800D03*
X304278Y591414D03*
X297635D03*
X334292Y589800D03*
X375792Y6500D03*
X377592Y-10880D03*
X380232Y-10900D03*
X380200Y-1200D03*
X378792Y6500D03*
X357492Y14314D03*
X380792Y24933D03*
X357492Y11714D03*
X357872Y28014D03*
X367911D03*
X394192Y-9700D03*
X409522Y-20794D03*
X408184Y13200D03*
X367911Y46914D03*
Y54842D03*
Y35942D03*
X358619Y36031D03*
X358618Y54842D03*
X357872Y65736D03*
X366992Y65950D03*
X357872Y46914D03*
X357965Y92500D03*
X367911Y87500D03*
X368311Y92500D03*
X367742Y73450D03*
X357872Y87500D03*
X358491Y73479D03*
X408069Y35942D03*
X401376Y54842D03*
X408069Y46907D03*
X398029Y35942D03*
Y46907D03*
X411416Y54857D03*
X401375Y92757D03*
X398029Y84800D03*
Y73742D03*
X408068Y87392D03*
X411415Y89964D03*
X408069Y73742D03*
X408126Y105750D03*
X414820Y105800D03*
X401375D03*
X357987Y193507D03*
X378267D03*
X386157Y207159D03*
X382777Y201309D03*
X365877Y214960D03*
X372637D03*
X379397D03*
X359117D03*
X365877Y203260D03*
X376017Y205211D03*
X362497Y205210D03*
X386157Y214960D03*
X415634Y204496D03*
Y212296D03*
X404392Y199100D03*
X415634Y208397D03*
X407706Y209109D03*
X392898Y195041D03*
X392916Y214960D03*
Y203260D03*
X396296Y197359D03*
X399676Y203260D03*
Y214960D03*
X386157Y226660D03*
X389537Y232509D03*
X369257Y244209D03*
X362497D03*
X372637Y226660D03*
X365877D03*
X369257Y232509D03*
X362497D03*
X379397Y226660D03*
X382777Y232509D03*
X376017D03*
X359117Y226660D03*
X372637Y250060D03*
X365877Y253960D03*
X362497Y255909D03*
X359117Y257860D03*
X369257Y252009D03*
X407706Y240309D03*
Y232509D03*
X415634Y247396D03*
Y235696D03*
Y223996D03*
X392916Y226660D03*
X396296Y232509D03*
X399676Y226660D03*
X407448Y338641D03*
X416448D03*
X413948D03*
X410948D03*
X370650Y312441D03*
X378156D03*
X375674D03*
X373162Y312400D03*
X368165Y312504D03*
X359117Y339760D03*
X362497Y341709D03*
X403648Y338341D03*
X401148D03*
X398148D03*
X394648D03*
X379397Y347560D03*
Y370959D03*
X372637D03*
X365877D03*
X359117D03*
X386157D03*
X362497Y353409D03*
X376017D03*
X369257D03*
Y345609D03*
X376017D03*
X372637Y347560D03*
X365877Y343660D03*
X389537Y365109D03*
X382777D03*
X369257D03*
X362497D03*
X376017D03*
X390657Y394359D03*
X391787Y402800D03*
X357987D03*
X369257Y392410D03*
X362497D03*
X379397Y382660D03*
X372637D03*
X365877D03*
X359117D03*
X379397Y390460D03*
X378267Y402800D03*
X376017Y392410D03*
X386157Y382660D03*
X411086Y351460D03*
X392916Y370959D03*
X399676D03*
X396296Y365109D03*
X403056D03*
Y357309D03*
X392916Y382660D03*
Y390460D03*
X399676Y382660D03*
X406568Y402471D03*
X403056Y392410D03*
X386630Y521860D03*
X359042Y515200D03*
X358918Y510114D03*
X366865D03*
Y515152D03*
X401375Y518157D03*
X398029Y509999D03*
X411415Y515364D03*
X408068Y512792D03*
X370080Y555700D03*
X367692Y547914D03*
X357672D03*
X357872Y528942D03*
X367911Y529057D03*
X367692Y536200D03*
X357910Y536727D03*
X356798Y588366D03*
X367211Y555842D03*
X357910D03*
X367192Y566814D03*
X357910D03*
X367192Y574742D03*
X357872D03*
X398029Y536942D03*
X408069Y547907D03*
Y536942D03*
X398029Y547907D03*
X401376Y555842D03*
X411416Y555857D03*
X398029Y574742D03*
X408069D03*
X413324Y623559D03*
X399824D03*
X356798Y590939D03*
X373400Y593800D03*
X376204Y593650D03*
X374039Y611186D03*
X408184Y589800D03*
X447744Y-7180D03*
X451573Y-1801D03*
Y9114D03*
X436392Y-20760D03*
X422892Y-20789D03*
X448226Y28100D03*
X448292Y31900D03*
X433508Y13200D03*
X448292Y13700D03*
X421368Y13200D03*
X448892Y17000D03*
X418108Y28007D03*
X441533D03*
X458266Y-1751D03*
X460912Y-7700D03*
X454533Y-7851D03*
X458116Y9114D03*
X469832Y-2051D03*
X464732Y-1801D03*
X474998Y-1751D03*
X469845Y-9864D03*
X478344Y-7851D03*
X464758Y-9652D03*
X474998Y9114D03*
X464732Y9098D03*
X478344Y29949D03*
X460912Y30100D03*
Y14814D03*
X469832Y17114D03*
X454569Y14714D03*
X454533Y29949D03*
X469792Y9300D03*
X478344Y14814D03*
X469845Y27936D03*
X464792Y28100D03*
X464692Y16900D03*
X434842Y54857D03*
X441533Y54842D03*
X424801Y46907D03*
X431494D03*
X428149Y54857D03*
X441533Y46907D03*
X448414Y35761D03*
X448973Y54883D03*
X451573Y35999D03*
X448627Y68090D03*
X448517Y46975D03*
X448492Y51000D03*
X451573Y46900D03*
X418108Y65807D03*
Y54842D03*
X441533Y65807D03*
X431494Y35942D03*
X441533D03*
X424801D03*
X418108D03*
Y46907D03*
X428147Y92500D03*
X424801Y84800D03*
X431400D03*
X431494Y73742D03*
X441533Y87392D03*
Y92500D03*
Y73742D03*
X418108Y89964D03*
Y84599D03*
Y73742D03*
X424801D03*
X434840Y92500D03*
X448651Y70896D03*
X451573Y84714D03*
Y73799D03*
X448610Y85296D03*
X448599Y73589D03*
X448692Y89900D03*
X474998Y36049D03*
X464732Y46898D03*
X460912Y52614D03*
X458266Y36049D03*
X458116Y46914D03*
X464758Y65950D03*
X474998Y46914D03*
X454533Y67749D03*
X454569Y52514D03*
X469832Y54914D03*
X469792Y47100D03*
Y35800D03*
X464692Y54700D03*
X464732Y35999D03*
X478344Y52614D03*
X460912Y67900D03*
X478344Y67749D03*
X469845Y65736D03*
X458116Y84714D03*
X464708Y92500D03*
X464732Y84698D03*
X469808Y84700D03*
X474998Y73849D03*
X469858Y73550D03*
X474998Y84714D03*
X478344Y90414D03*
X469832Y92714D03*
X460912Y90314D03*
X464732Y73799D03*
X458266Y73849D03*
X454569Y90314D03*
X427696Y105800D03*
X421503D03*
X441743Y199841D03*
X421464Y199583D03*
X446253Y206446D03*
X425974D03*
X453013Y218147D03*
X449633Y212296D03*
Y216196D03*
X422594D03*
X419214Y214247D03*
X436113Y212296D03*
X432733Y214247D03*
X429354Y216196D03*
X432733Y218147D03*
X425974D03*
X429353Y212296D03*
X446253Y218147D03*
X442873Y216196D03*
X439493Y214247D03*
X436113Y216196D03*
X453013Y214247D03*
X439493Y210346D03*
X434983Y198931D03*
X455263Y198050D03*
X473292Y218147D03*
X469913Y216196D03*
X469912Y212296D03*
X475692Y199900D03*
X466533Y218147D03*
X473292Y214247D03*
X476672Y212296D03*
Y216196D03*
X459773Y214247D03*
X466533Y206446D03*
X456393Y216196D03*
X462023Y198327D03*
X456393Y212296D03*
X463153Y216196D03*
X429354Y251296D03*
X453013Y245447D03*
Y229847D03*
Y237647D03*
X449633Y251296D03*
Y247396D03*
Y227896D03*
Y223996D03*
X436113Y243496D03*
X442873D03*
X422594D03*
X425974Y245447D03*
Y249347D03*
X432733D03*
X436113Y251296D03*
X429354Y247396D03*
X422594Y251296D03*
X446253Y245447D03*
X419214Y249347D03*
X432733Y245447D03*
X439493Y237647D03*
X446253D03*
X422594Y223996D03*
Y231797D03*
X419214Y233746D03*
Y237647D03*
X436113Y231797D03*
X439493Y241547D03*
X419214D03*
X436113Y223996D03*
X429354D03*
Y220096D03*
Y227896D03*
X446253Y229847D03*
X432733D03*
X425974D03*
X439493Y233746D03*
X442873Y231797D03*
Y223996D03*
X425974Y237647D03*
X432733D03*
X449633Y220096D03*
X439493Y253247D03*
X449633Y255196D03*
Y259096D03*
X446253Y257147D03*
X442873Y255196D03*
X453013Y257147D03*
Y261047D03*
X448900Y269600D03*
X469913Y251296D03*
X466533Y245447D03*
X473292D03*
X476672Y223996D03*
Y243496D03*
Y251296D03*
X469913Y247396D03*
Y223996D03*
X473292Y229847D03*
X469913Y227896D03*
X466533Y229847D03*
X473292Y237647D03*
X466533D03*
X469913Y220096D03*
X456393Y243496D03*
Y251296D03*
X459773Y233746D03*
Y241547D03*
Y237647D03*
X456393Y223996D03*
Y231797D03*
X476672D03*
X463153Y243496D03*
Y251296D03*
Y231797D03*
Y223996D03*
X476672Y259096D03*
X463153D03*
X458408Y278940D03*
X477792Y272747D03*
X462023Y271097D03*
X458643Y269146D03*
X456393Y262996D03*
Y259096D03*
X459773Y261047D03*
X469913Y255196D03*
X473292Y257147D03*
X466533D03*
X468783Y274997D03*
X469913Y270796D03*
X466533Y264947D03*
X426494Y338361D03*
X430089Y338428D03*
X419400Y338600D03*
X469913Y305896D03*
X477792Y307851D03*
X469913Y286396D03*
X477792Y303947D03*
Y288347D03*
Y315647D03*
Y319547D03*
X458643Y338746D03*
X477792Y327347D03*
X462948Y315251D03*
X455263Y340697D03*
X462848Y312741D03*
X467653Y340996D03*
X474413D03*
Y337096D03*
X469913Y321496D03*
X443993Y358547D03*
X441743Y348497D03*
X440613Y352696D03*
X437233Y358547D03*
X450753Y366347D03*
Y350747D03*
Y358547D03*
X437233Y362447D03*
X423714D03*
X433854Y368296D03*
X427094D03*
X440613Y364396D03*
X427094Y372197D03*
X447373D03*
Y368296D03*
X440613Y372197D03*
Y368296D03*
X443993Y366347D03*
X427094Y356596D03*
X433854Y352696D03*
X437233Y354647D03*
X423714D03*
X430474D03*
X427094Y360496D03*
X433854D03*
X445123Y346546D03*
X427094Y352696D03*
X430474Y385847D03*
X450753Y397547D03*
X440613Y395595D03*
X429354Y399496D03*
X433854Y379996D03*
X423714Y374146D03*
X437233D03*
X430474Y378047D03*
X433854Y376096D03*
X443993Y397546D03*
Y401447D03*
Y393647D03*
X440613Y391696D03*
X443993Y385847D03*
X427094Y376096D03*
X437233Y381947D03*
X447373Y376096D03*
X440613Y379996D03*
X443993Y378047D03*
X423715Y397548D03*
X430474Y393647D03*
X433854Y391696D03*
X423715Y401449D03*
X450753Y385847D03*
Y393647D03*
Y378047D03*
X437233Y389747D03*
Y385847D03*
X423714D03*
X477792Y342947D03*
Y362447D03*
Y354647D03*
Y358547D03*
X457513Y362447D03*
X454133Y372197D03*
Y364396D03*
Y348796D03*
Y352696D03*
X464273Y366347D03*
X474413Y372197D03*
X471033Y366347D03*
X467653Y372197D03*
X474413Y364396D03*
X464273Y350747D03*
X474413Y348796D03*
X471033Y350747D03*
X474413Y352696D03*
X471033Y358547D03*
X464273D03*
X467653Y368296D03*
Y348796D03*
X460893Y372197D03*
Y364396D03*
Y352696D03*
X457513Y354647D03*
Y358547D03*
Y346847D03*
X477792Y389747D03*
X457513D03*
X471033Y393647D03*
X460893Y395595D03*
X464273Y401447D03*
X471033D03*
X460893Y391696D03*
X457513Y385847D03*
Y381947D03*
X460893Y379996D03*
X477792Y381947D03*
X474413Y391696D03*
X464273Y385847D03*
X454133Y391696D03*
Y379996D03*
X471033Y385847D03*
X464273Y393647D03*
X474413Y379996D03*
X471033Y378047D03*
X467653Y376096D03*
X464273Y378047D03*
Y397546D03*
X477792Y385847D03*
X447091Y407782D03*
X428224Y407800D03*
X443993Y405347D03*
X467653Y407296D03*
X464273Y405347D03*
X441533Y512792D03*
Y518057D03*
X433192Y497650D03*
X434840Y518157D03*
X431494Y509999D03*
X424801Y510114D03*
X418108Y515364D03*
Y509999D03*
X428147Y518157D03*
X451573Y510114D03*
X448692Y515300D03*
X447735Y512794D03*
X474998Y510114D03*
X464732Y510098D03*
X460912Y515714D03*
X458116Y510114D03*
X454569Y515714D03*
X478344Y515814D03*
X464708Y517900D03*
X469832Y518114D03*
X418108Y536942D03*
Y547907D03*
X431494D03*
X424801D03*
X441533D03*
X418108Y529007D03*
X431494Y536942D03*
X424801D03*
X441533Y536957D03*
Y529007D03*
X451573Y547914D03*
Y536999D03*
X448510Y549843D03*
X448410Y531156D03*
X448432Y536723D03*
X448692Y553100D03*
X448557Y534061D03*
X451573Y585714D03*
Y574799D03*
X448226Y569200D03*
X448291Y574773D03*
X418108Y555842D03*
X428149Y555857D03*
X434842D03*
X441533Y555842D03*
Y574742D03*
X418108Y566807D03*
X441533D03*
X424801Y574742D03*
X418108D03*
X431494D03*
X464732Y536999D03*
X460912Y553514D03*
X458116Y547914D03*
X454569Y553514D03*
X454533Y530949D03*
X460912Y531100D03*
X458266Y537049D03*
X469845Y528936D03*
X474998Y537049D03*
X464758Y529150D03*
X469858Y536750D03*
X478344Y553614D03*
X464732Y547898D03*
X474998Y547914D03*
X469808Y547900D03*
X478344Y530949D03*
Y568749D03*
X464732Y574799D03*
X469808Y585700D03*
X469858Y574550D03*
X474998Y574849D03*
Y585714D03*
X464732Y585698D03*
X464758Y566950D03*
X469845Y566736D03*
X458266Y574849D03*
X460912Y568900D03*
X458116Y585714D03*
X454533Y568749D03*
X464708Y555700D03*
X469832Y555914D03*
X474998Y612649D03*
X464732Y612599D03*
X458266Y612649D03*
X427324Y623541D03*
X451573Y612599D03*
X447744Y607220D03*
X448692Y590900D03*
X420634Y589800D03*
X433500D03*
X478344Y591414D03*
X464708Y593500D03*
X469832Y593714D03*
X464758Y604750D03*
X469845Y604536D03*
X478344Y606549D03*
X469858Y612350D03*
X460912Y591314D03*
Y606700D03*
X454533Y606549D03*
X454569Y591314D03*
X511809Y-1751D03*
Y9114D03*
X495077Y-1751D03*
X501544Y-1801D03*
X506692Y-2000D03*
X488384Y-1801D03*
X481691Y-1751D03*
X485037Y-7851D03*
X491344D03*
X506657Y-9864D03*
X497723Y-7700D03*
X501592Y-9700D03*
X481691Y9114D03*
X494927D03*
X488384D03*
X501544Y9098D03*
X497723Y14814D03*
X506644Y17114D03*
X506657Y27936D03*
X497723Y30100D03*
X491380Y14714D03*
X506604Y9300D03*
X485037Y14814D03*
X501504Y16900D03*
X485037Y29949D03*
X491344D03*
X501603Y28100D03*
X515155Y-7851D03*
X538355Y9098D03*
X518502Y-1751D03*
X521848Y-7851D03*
X538355Y-1801D03*
X531888Y-1751D03*
X525195Y-1801D03*
X538403Y-9700D03*
X528155Y-7851D03*
X534534Y-7700D03*
X518502Y9114D03*
X531738D03*
X525195D03*
X521848Y14814D03*
Y29949D03*
X528191Y14714D03*
X538315Y16900D03*
X534534Y30100D03*
X515155Y29949D03*
Y14814D03*
X534534D03*
X528155Y29949D03*
X538415Y28100D03*
X488384Y35999D03*
X501492Y54700D03*
X497723Y52614D03*
Y67900D03*
X501544Y46898D03*
X511809Y46914D03*
X491344Y67749D03*
X506657Y65736D03*
X501570Y65950D03*
X481691Y36049D03*
X495077D03*
X506644Y54914D03*
X494927Y46914D03*
X485037Y52614D03*
X481691Y46914D03*
X511809Y36049D03*
X485037Y67749D03*
X488384Y46914D03*
X506603Y35800D03*
X506592Y47000D03*
X501544Y35999D03*
X511809Y84714D03*
X501544Y84698D03*
X494927Y84714D03*
X506670Y73550D03*
X481691Y84714D03*
X488384D03*
X501520Y92500D03*
X506620Y84700D03*
X511809Y73849D03*
X488384Y73799D03*
X481691Y73849D03*
X506644Y92714D03*
X491380Y90314D03*
X497723Y90414D03*
X485037D03*
X495077Y73849D03*
X501544Y73799D03*
X518502Y36049D03*
Y46914D03*
X521848Y67749D03*
X531888Y36049D03*
X538355Y35999D03*
X534534Y52614D03*
X531738Y46914D03*
X525195Y35999D03*
X515155Y67749D03*
Y52614D03*
X521848D03*
X534534Y67900D03*
X538381Y65950D03*
X528155Y67749D03*
X538355Y46898D03*
X538304Y54700D03*
X525195Y46914D03*
X515155Y90414D03*
X534534D03*
X528191Y90314D03*
X521848Y90414D03*
X518502Y73849D03*
Y84714D03*
X531738D03*
X525195D03*
X538355Y84698D03*
X538331Y92500D03*
X531888Y73849D03*
X525195Y73799D03*
X538355D03*
X512024Y104314D03*
X497723Y109564D03*
X501544Y113114D03*
X506670Y112865D03*
X501570Y105265D03*
X491430Y109564D03*
X506657Y105051D03*
X488634Y104314D03*
X495077D03*
X514820Y109564D03*
X521113D03*
X528191Y109914D03*
X534534Y109564D03*
X538355Y113114D03*
X531738Y104314D03*
X525134D03*
X538381Y105265D03*
X518467Y104314D03*
X511592Y206447D03*
Y210346D03*
Y218147D03*
X486812Y214247D03*
Y218147D03*
X498350Y209900D03*
X501452Y212296D03*
X480052Y214247D03*
Y206447D03*
X486812Y210346D03*
X508212Y212296D03*
X518352Y218147D03*
Y206445D03*
X538631Y210346D03*
Y214247D03*
Y206447D03*
X528491Y208397D03*
X525111Y218147D03*
X528491Y216196D03*
X535251Y204496D03*
X525111Y206447D03*
X531871D03*
X521731Y208397D03*
X511592Y241547D03*
Y249347D03*
X486812Y245447D03*
X494692Y247396D03*
X483432Y251296D03*
X501452Y247396D03*
X480052Y237647D03*
X508212Y239596D03*
X498072Y233746D03*
X486812D03*
Y229847D03*
X494692Y235696D03*
X504832Y229847D03*
X486812Y225947D03*
X498072Y222047D03*
Y225947D03*
X486812Y222047D03*
Y237647D03*
X480052Y233746D03*
X504832Y241547D03*
X480052D03*
X486812D03*
X494692Y243496D03*
X483432D03*
X504832Y245447D03*
X501452Y223996D03*
X508212Y231797D03*
Y220096D03*
Y223996D03*
X483432Y235696D03*
Y223996D03*
X494692Y251296D03*
X501452Y274696D03*
X508212Y278596D03*
X484552Y268847D03*
X494692Y255196D03*
X486812Y257147D03*
X504832Y253247D03*
X487932Y278596D03*
Y274696D03*
X494692Y278596D03*
X501452Y266896D03*
Y259096D03*
X483432D03*
X481172Y274696D03*
Y278596D03*
X508212Y270796D03*
X494692D03*
X480052Y261047D03*
X518352Y229847D03*
X521731Y231797D03*
Y235696D03*
Y247396D03*
Y220096D03*
X538631Y225947D03*
Y222047D03*
Y237647D03*
X528491Y247396D03*
Y243496D03*
X538631Y249347D03*
X535251Y235696D03*
X528491Y227896D03*
Y235696D03*
Y220096D03*
X535251Y247396D03*
Y251296D03*
Y239596D03*
X531871Y222047D03*
X525111Y237647D03*
X514972Y247396D03*
Y227896D03*
Y235696D03*
Y239596D03*
Y223996D03*
X535251Y259096D03*
X531871Y261047D03*
X514972Y270796D03*
Y278596D03*
X525111Y253247D03*
X518352D03*
X528491Y274696D03*
X531871Y268847D03*
Y276646D03*
X535251Y266896D03*
X525111Y280547D03*
X521731Y266896D03*
Y259096D03*
Y274696D03*
X538631Y257147D03*
X504832Y307847D03*
X525111Y315647D03*
X494692Y294196D03*
X501452Y290296D03*
Y282496D03*
X491312Y292245D03*
Y300047D03*
X508212Y290296D03*
Y294196D03*
X511592Y307847D03*
Y284447D03*
X481172Y309797D03*
X494692D03*
X481172Y301996D03*
X487932Y309797D03*
X498072Y303947D03*
X487932Y282496D03*
X484552Y300047D03*
Y292245D03*
X494692Y286396D03*
X501452Y298096D03*
X481172Y290296D03*
X508212Y329296D03*
X487932Y317596D03*
X504832Y319547D03*
X484552Y323446D03*
X508212Y317596D03*
Y325396D03*
X491312Y339047D03*
X494692Y337096D03*
X511592Y327347D03*
Y339047D03*
Y331247D03*
Y335147D03*
Y315647D03*
Y323446D03*
X508212Y313696D03*
X481172D03*
X494692Y340996D03*
X504832Y331247D03*
X508212Y337096D03*
Y333196D03*
X504832Y335147D03*
X501452Y333196D03*
X504832Y339047D03*
X501452Y340996D03*
X504832Y315647D03*
X498072Y319547D03*
X504832Y323446D03*
X498072Y327347D03*
X491312Y331247D03*
X511592Y319547D03*
X538631Y311747D03*
X535251Y290296D03*
X514972Y301996D03*
Y290296D03*
Y286396D03*
Y294196D03*
X525111Y284447D03*
X531871Y288347D03*
Y292245D03*
X528491Y294196D03*
X525111Y300047D03*
X531871D03*
X521731Y301996D03*
X528491Y286396D03*
Y298096D03*
X535251Y294196D03*
X538631Y292245D03*
Y288347D03*
Y284447D03*
X531871Y303947D03*
X535251Y301996D03*
X531871Y311747D03*
Y307847D03*
X535251Y309797D03*
X514972Y333196D03*
Y321496D03*
Y317596D03*
Y329296D03*
Y325396D03*
Y337096D03*
X518352Y319547D03*
Y323446D03*
Y315647D03*
X521731Y317596D03*
Y325396D03*
X518352Y327347D03*
Y339047D03*
X531871Y335147D03*
X525111D03*
X528491Y337096D03*
X531871Y327347D03*
X535251Y329296D03*
X538631Y335147D03*
Y339047D03*
X528491Y317596D03*
X531871Y319547D03*
X535251Y321496D03*
X538631Y319547D03*
X504832Y342947D03*
X491312Y370247D03*
X498072Y366347D03*
X494692Y372197D03*
X504832Y366347D03*
X501452Y368296D03*
X487932D03*
X484552Y362447D03*
X498072D03*
X491312D03*
X494692Y360496D03*
X487932D03*
X501452Y344896D03*
X504832Y354647D03*
X494692Y344896D03*
Y348796D03*
X491312Y350747D03*
Y366347D03*
X487932Y372197D03*
X484552Y370247D03*
X481172Y372197D03*
X484552Y366347D03*
X487932Y364396D03*
X494692D03*
X501452D03*
X491312Y358547D03*
X498072Y350747D03*
Y346847D03*
X501452Y360496D03*
X498072Y342947D03*
X491312Y346847D03*
X494692Y356596D03*
X498072Y358547D03*
Y354647D03*
X481172Y344896D03*
Y360496D03*
X484552Y346847D03*
X508212Y352696D03*
Y360496D03*
X504832Y346847D03*
Y358547D03*
X501452Y356596D03*
Y348796D03*
Y352696D03*
X511592Y370247D03*
X481172Y352696D03*
X484552Y393647D03*
X481172Y391696D03*
X484552Y385847D03*
X498072Y393647D03*
X494692Y391696D03*
X491312Y385847D03*
X498072D03*
X508212Y387796D03*
X501452Y391696D03*
Y395597D03*
X491312Y389747D03*
X504832Y381947D03*
Y378047D03*
X501452Y379996D03*
X481172Y395596D03*
X511592Y378047D03*
Y397546D03*
X491312Y378047D03*
X484552D03*
X481172Y379996D03*
X487932Y376096D03*
X491312Y381947D03*
Y374146D03*
X498072Y397546D03*
X487932Y403396D03*
Y399496D03*
X491312Y397546D03*
X487932Y395597D03*
X514972Y372197D03*
Y356596D03*
X521731Y360496D03*
Y356596D03*
Y348796D03*
X518352Y342947D03*
Y362447D03*
X521731Y372197D03*
X518352Y370247D03*
X525111Y354647D03*
X531871Y346847D03*
X535251Y356596D03*
X538631Y366347D03*
X528491Y364396D03*
X525111Y342947D03*
X514972Y403396D03*
Y379996D03*
X531871Y374146D03*
X521731Y399496D03*
X518352Y397546D03*
Y389747D03*
X535251Y383896D03*
X525111Y381947D03*
X538631Y393647D03*
Y378047D03*
X528491Y403396D03*
X531871Y401447D03*
Y389747D03*
X525111Y393647D03*
X484552Y405347D03*
X538750Y406200D03*
X511712Y495800D03*
X488384Y495887D03*
X494777D03*
X491380Y493744D03*
X506644Y490867D03*
X501560D03*
X497723Y493494D03*
X506620Y510100D03*
X506644Y518114D03*
X501544Y510098D03*
X485037Y515814D03*
X481691Y510114D03*
X491380Y515714D03*
X511809Y510114D03*
X497723Y515814D03*
X494927Y510114D03*
X488384D03*
X501520Y517900D03*
X506644Y498867D03*
X501560D03*
X514755Y491044D03*
X521048Y491144D03*
X538370Y490609D03*
X528241Y490944D03*
X534534Y490794D03*
X515155Y515814D03*
X530792Y495787D03*
X524595D03*
X517892Y495800D03*
X534534Y515814D03*
X528191Y515714D03*
X531738Y510114D03*
X525195D03*
X538355Y510098D03*
X538331Y517900D03*
X521848Y515814D03*
X518502Y510114D03*
X538370Y498609D03*
X506670Y536750D03*
X501570Y529150D03*
X506657Y528936D03*
X501544Y536999D03*
X511809Y547914D03*
Y537049D03*
X491380Y553514D03*
X497723Y553614D03*
X485037D03*
X506620Y547900D03*
X501544Y547898D03*
X481691Y547914D03*
X494927D03*
X488384D03*
X481691Y537049D03*
X491344Y530949D03*
X488384Y536999D03*
X495077Y537049D03*
X497723Y531100D03*
X485037Y530949D03*
Y568749D03*
X481691Y574849D03*
Y585714D03*
X501544Y585698D03*
Y574799D03*
X506657Y566736D03*
X501570Y566950D03*
X506670Y574550D03*
X506620Y585700D03*
X488384Y585714D03*
X511809D03*
Y574849D03*
X494927Y585714D03*
X491344Y568749D03*
X501520Y555700D03*
X506644Y555914D03*
X497723Y568900D03*
X488384Y574799D03*
X495077Y574849D03*
X515155Y553614D03*
Y530949D03*
X534534Y531100D03*
X531888Y537049D03*
X528155Y530949D03*
X525195Y536999D03*
X538355D03*
X538381Y529150D03*
X525195Y547914D03*
X531738D03*
X538355Y547898D03*
X534534Y553614D03*
X528191Y553514D03*
X518502Y547914D03*
X521848Y553614D03*
X518502Y537049D03*
X521848Y530949D03*
X515155Y568749D03*
X538331Y555700D03*
X518502Y585714D03*
Y574849D03*
X521848Y568749D03*
X538355Y585698D03*
Y574799D03*
X538381Y566950D03*
X531738Y585714D03*
X525195D03*
X534534Y568900D03*
X525195Y574799D03*
X528155Y568749D03*
X531888Y574849D03*
X525195Y612599D03*
X518502Y612649D03*
X538355Y612599D03*
X531888Y612649D03*
X501544Y612599D03*
X495077Y612649D03*
X488384Y612599D03*
X511809Y612649D03*
X497723Y591414D03*
X486250Y591020D03*
X491380Y591314D03*
X501520Y593500D03*
X506644Y593714D03*
X501570Y604750D03*
X506657Y604536D03*
X491344Y606549D03*
X497723Y606700D03*
X485037Y607230D03*
X506670Y612350D03*
X480950Y612430D03*
X515155Y606549D03*
Y591414D03*
X521848D03*
Y606549D03*
X534534Y591414D03*
X528191Y591314D03*
X538331Y593500D03*
X538381Y604750D03*
X534534Y606700D03*
X528155Y606549D03*
X562006Y9114D03*
X568549D03*
X555313D03*
X548620D03*
X571345Y-7700D03*
X551966Y-7851D03*
X564966D03*
X558659D03*
X562006Y-1801D03*
X555313Y-1751D03*
X568699D03*
X548620D03*
X543503Y-2000D03*
X543468Y-9864D03*
X543455Y17114D03*
X564992Y14714D03*
X543415Y9300D03*
X558659Y14814D03*
Y29949D03*
X551966Y14814D03*
Y29949D03*
X564966D03*
X571345Y14814D03*
Y30100D03*
X543468Y27936D03*
X575166Y9098D03*
X602163Y16999D03*
X575214Y-9700D03*
X575166Y-1801D03*
X580279Y-9864D03*
X580314Y-2000D03*
X588777Y-7851D03*
X598817Y-9901D03*
X595470Y-7851D03*
X592124Y-1751D03*
X598817D03*
X585431D03*
X602163Y-9901D03*
X598817Y9157D03*
X592124Y9114D03*
X585431D03*
X575182Y16900D03*
X575192Y28100D03*
X580192Y9300D03*
X588777Y29949D03*
X580279Y27936D03*
X595470Y29949D03*
Y14814D03*
X598817Y27899D03*
X588777Y14814D03*
X580266Y17114D03*
X562006Y46914D03*
X551966Y52614D03*
X565352Y52864D03*
X548620Y46914D03*
Y36049D03*
X558659Y52614D03*
X568699Y36049D03*
X555313D03*
X562006Y35999D03*
X551966Y67749D03*
X564966D03*
X571345Y52614D03*
Y67900D03*
X558659Y67749D03*
X568549Y46914D03*
X555313D03*
X543468Y65736D03*
X543404Y47000D03*
X543415Y35800D03*
X543455Y54914D03*
Y92714D03*
X548620Y84714D03*
X568549D03*
X555313D03*
X562006D03*
X543481Y73550D03*
X543431Y84700D03*
X548620Y73849D03*
X568699D03*
X562006Y73799D03*
X555313Y73849D03*
X558659Y90414D03*
X551966D03*
X571345D03*
X575166Y46898D03*
Y35999D03*
X575192Y65950D03*
X585431Y46914D03*
X595470Y52614D03*
X588777D03*
X585431Y36049D03*
X592124D03*
X598817D03*
Y46957D03*
X592124Y46914D03*
X598817Y65699D03*
X595470Y67749D03*
X588777D03*
X580266Y54914D03*
X580192Y35750D03*
X580279Y65736D03*
X602163Y65699D03*
X592124Y84714D03*
X585431D03*
X598817Y84757D03*
X580242Y84700D03*
X580266Y92714D03*
X588777Y90414D03*
X602163Y92599D03*
X575166Y73799D03*
X575142Y92500D03*
X575166Y84698D03*
X595470Y90414D03*
X585431Y73849D03*
X592124D03*
X598817D03*
X580292Y73550D03*
X548620Y104314D03*
X555313D03*
X558659Y110014D03*
X551966D03*
X543481Y112865D03*
X543468Y105051D03*
X602100Y109600D03*
X555531Y216196D03*
X557000Y206800D03*
X548771Y212296D03*
X552151Y214247D03*
X547800Y201400D03*
X545391Y210346D03*
X552151Y218147D03*
Y225947D03*
X558911Y222047D03*
X552151Y233746D03*
X548771Y235696D03*
X558911Y229847D03*
X552151D03*
X562591Y220096D03*
X564084Y235685D03*
X545391Y225947D03*
Y222047D03*
Y233746D03*
X542011Y239596D03*
Y247396D03*
X552151Y241547D03*
X548771Y239596D03*
X552151Y249347D03*
X555531Y247396D03*
X562591Y251296D03*
X548771Y243496D03*
X562591D03*
X572930Y232750D03*
Y228130D03*
X552151Y257147D03*
X562591Y255196D03*
X548771D03*
X573200Y262600D03*
X573100Y258600D03*
X548771Y266896D03*
X558911Y264947D03*
X563800Y275900D03*
X559211Y280547D03*
X548771Y278596D03*
X558911Y272747D03*
X555531Y274696D03*
X564500Y264800D03*
Y268800D03*
X552151Y261047D03*
X545391Y272747D03*
Y280547D03*
Y264947D03*
Y268847D03*
X542011Y274696D03*
X580360Y234590D03*
Y230060D03*
X545391Y307847D03*
X555831Y309797D03*
Y305896D03*
X548771Y309797D03*
X555831Y298096D03*
X552151Y284447D03*
X548771Y286396D03*
X552151Y288347D03*
Y296147D03*
X558145Y286727D03*
X545391Y296147D03*
Y288347D03*
Y292245D03*
Y300047D03*
X542011Y294196D03*
Y298096D03*
X545391Y303947D03*
X548771Y313696D03*
X561971Y317320D03*
X548771Y325396D03*
X558911Y335147D03*
X555531Y333196D03*
X562591D03*
X548771Y340996D03*
X561966Y325502D03*
X559211Y319547D03*
X552151Y323446D03*
X545391Y319547D03*
X542011Y321496D03*
X545391Y335147D03*
Y331247D03*
Y315647D03*
X552151Y350747D03*
X558911Y342947D03*
X559212Y370247D03*
X548771Y368296D03*
X562591Y352696D03*
Y344896D03*
X563200Y356596D03*
X545391Y354647D03*
Y346847D03*
X542011Y368296D03*
X545391Y366347D03*
Y358547D03*
X542011Y360496D03*
Y348796D03*
X559212Y374146D03*
X555531Y387797D03*
X559212Y381947D03*
Y393647D03*
X552151Y378047D03*
X545391Y397546D03*
Y385847D03*
X542011Y376096D03*
X573867Y459903D03*
X575614Y461694D03*
X584076Y443828D03*
X588285Y448306D03*
X586136Y446335D03*
X558659Y493444D03*
X551366Y490744D03*
X543455Y490909D03*
X555313Y510114D03*
X548492Y495800D03*
X554792Y495887D03*
X543431Y510100D03*
X543455Y518114D03*
X551966Y515814D03*
X548620Y510114D03*
X543455Y498909D03*
X568549Y510114D03*
X562006D03*
X571345Y515814D03*
X558659D03*
X582912Y468948D03*
X581032Y467202D03*
X575166Y510098D03*
X575142Y517900D03*
X580266Y518114D03*
X580242Y510100D03*
X598817Y510157D03*
X595470Y515814D03*
X588777D03*
X602163Y517999D03*
X592124Y510114D03*
X585431D03*
X543468Y528936D03*
X543481Y536750D03*
X543431Y547900D03*
X548620Y547914D03*
X551966Y553614D03*
X548620Y537049D03*
X551966Y530949D03*
X558659D03*
X555313Y537049D03*
X562006Y536999D03*
X564966Y530949D03*
X568699Y537049D03*
X571345Y553614D03*
Y531100D03*
X558659Y553614D03*
X555313Y547914D03*
X568549D03*
X562006D03*
X543455Y555914D03*
X571345Y568900D03*
X564966Y568749D03*
X562006Y574799D03*
X555313Y585714D03*
Y574849D03*
X558659Y568749D03*
X568549Y585714D03*
X562006D03*
X568699Y574849D03*
X551966Y568749D03*
X548620Y574849D03*
Y585714D03*
X543481Y574550D03*
X543431Y585700D03*
X543468Y566736D03*
X575166Y547898D03*
X575192Y529150D03*
X575166Y536999D03*
X598817Y547957D03*
X592124Y547914D03*
X595470Y530949D03*
X580242Y547900D03*
X580279Y528936D03*
X580292Y536750D03*
X592124Y537049D03*
X588777Y530949D03*
X598817Y528899D03*
Y537049D03*
X602163Y528899D03*
X585431Y547914D03*
Y537049D03*
X588777Y553614D03*
X595470D03*
X580279Y566736D03*
X585431Y574849D03*
Y585714D03*
X598817Y585757D03*
Y574849D03*
Y566699D03*
X592124Y585714D03*
X595470Y568749D03*
X588777D03*
X592124Y574849D03*
X575142Y555700D03*
X575192Y566950D03*
X575166Y585698D03*
Y574799D03*
X580266Y555914D03*
X580292Y574550D03*
X580242Y585700D03*
X575166Y612599D03*
X585431Y612649D03*
X592124D03*
X598817D03*
X555313D03*
X562006Y612599D03*
X568699Y612649D03*
X548620D03*
X571345Y591414D03*
X558659D03*
X571345Y606700D03*
X558659Y606549D03*
X564966D03*
X551966D03*
Y591414D03*
X543455Y593714D03*
X543468Y604536D03*
X543481Y612350D03*
X580292D03*
X580266Y593714D03*
X595470Y591414D03*
X588777D03*
X598817Y604499D03*
X595470Y606549D03*
X588777D03*
X575192Y604750D03*
X575142Y593500D03*
X602163Y593599D03*
Y604499D03*
X580279Y604536D03*
X620092Y13078D03*
X620192Y31978D03*
Y-5822D03*
X647317Y-1310D03*
X660676Y-2600D03*
X651300Y20000D03*
X659200Y31500D03*
X651300Y17500D03*
X620070Y50878D03*
X620192Y69778D03*
X620092Y88678D03*
X663500Y48000D03*
X663700Y65600D03*
X663476Y45296D03*
X616115Y108339D03*
X622200Y112200D03*
X616167Y118627D03*
X605300Y124600D03*
X630000Y126572D03*
X624500Y129400D03*
X626900Y128300D03*
X633580Y125560D03*
X661700Y142300D03*
X636481Y124951D03*
X635951Y127419D03*
X661053Y115971D03*
X658490Y115432D03*
X650307Y115518D03*
X647809Y116121D03*
X645311Y116724D03*
X650120Y122700D03*
X660900Y123650D03*
Y126650D03*
X647120Y122700D03*
X657900Y126650D03*
Y123650D03*
X651920Y125750D03*
X656111Y121550D03*
X653111D03*
X654558Y115101D03*
X640043Y117728D03*
X639100Y124200D03*
X638800Y126700D03*
X648690Y125590D03*
X643674Y123573D03*
X644950Y125750D03*
X641950D03*
X642899Y117112D03*
X632500Y238500D03*
Y235000D03*
X632692Y248172D03*
X632532Y241717D03*
X630200Y248100D03*
X633308Y263808D03*
X662800Y248600D03*
X643500Y272262D03*
X659900Y256900D03*
Y269200D03*
X652000Y284500D03*
X663200Y298600D03*
X644800Y292150D03*
X654500Y298600D03*
X652100Y288300D03*
X639045Y299555D03*
X639100Y309500D03*
X649000Y339400D03*
X638790Y329500D03*
X639350Y339980D03*
X639100Y319500D03*
X655900Y307700D03*
X656300Y312300D03*
X660700Y307700D03*
X655900Y316500D03*
X656000Y329800D03*
X655900Y320500D03*
X656000Y325100D03*
X660900Y329800D03*
X664100Y348000D03*
X648800D03*
X658900D03*
X662936Y367171D03*
X659936Y364171D03*
X662936D03*
X654000Y348000D03*
X634200Y436800D03*
X637300Y437200D03*
X625430Y490100D03*
X607012Y465997D03*
X623660Y466746D03*
X632113Y496892D03*
X619392Y514700D03*
X656900Y482290D03*
X649600Y492400D03*
X660500Y492000D03*
X652000Y513900D03*
X655000D03*
X661500D03*
X658500D03*
X620192Y532978D03*
X618892Y555800D03*
X618292Y574300D03*
X651750Y584150D03*
X653100Y587000D03*
X618192Y593600D03*
X620033Y608878D03*
X660230Y598170D03*
X674300Y9847D03*
X671800D03*
X669300D03*
X673900Y23100D03*
X671400D03*
X668900D03*
X690000Y15300D03*
X683800Y24856D03*
X670430Y29253D03*
X716858Y-14448D03*
X717720Y23279D03*
X715114Y26395D03*
X704500Y26300D03*
X714337Y7852D03*
Y5352D03*
Y2852D03*
X718555Y-16147D03*
X666500Y48000D03*
X665100Y68600D03*
X668100D03*
X666700Y65600D03*
X678020Y69870D03*
X678300Y92630D03*
Y95130D03*
X675630Y94988D03*
X681300Y95130D03*
Y92630D03*
X684300D03*
X687400Y93900D03*
X673830Y83050D03*
X676430D03*
X676500Y80500D03*
X673900D03*
X674010Y77970D03*
X676610D03*
X692200Y83800D03*
X695000Y67000D03*
X699880Y66840D03*
X724200Y64730D03*
X722460Y69550D03*
X713680Y60910D03*
X700360Y72160D03*
X694910Y72220D03*
X713050Y63650D03*
X710440Y63710D03*
X704880Y66750D03*
X697747Y72184D03*
X723700Y67400D03*
X713620Y58270D03*
X715800Y59490D03*
Y57000D03*
X713590Y53260D03*
X713610Y55730D03*
X700640Y69500D03*
X703120Y69380D03*
X702380Y66840D03*
X697440Y66900D03*
X699800Y89100D03*
X713830Y82730D03*
X692000Y45000D03*
Y48500D03*
X697500D03*
Y45000D03*
X664700Y142800D03*
X675600Y144900D03*
Y150000D03*
X679900Y128200D03*
X682400Y127085D03*
X684900D03*
X673566Y116724D03*
X676494Y116940D03*
X668665Y118185D03*
X671249Y118744D03*
X677896Y119093D03*
X674896D03*
X715505Y155076D03*
X720700Y154750D03*
X725650Y155000D03*
X691583Y200124D03*
X689033D03*
X686533D03*
Y196624D03*
X689033D03*
X691583D03*
X715550Y158880D03*
X705550D03*
X710550D03*
X709200Y198700D03*
X720369Y205199D03*
X716557Y198557D03*
X692513Y213800D03*
X692673Y206200D03*
X692500Y210100D03*
X690861Y211917D03*
Y215717D03*
X692400Y218100D03*
X690861Y204317D03*
Y208117D03*
X706500Y217400D03*
Y214900D03*
X719315Y239104D03*
X669900Y224000D03*
X672500Y224100D03*
X678454Y278000D03*
X675380Y246340D03*
X678000Y246400D03*
X668100Y232200D03*
X667240Y246600D03*
X672530Y246300D03*
X677400Y232300D03*
X674300Y232200D03*
X675200Y224100D03*
X667600Y250200D03*
X688643Y225980D03*
X688388Y231280D03*
X678400Y224100D03*
X690380Y252240D03*
X690939Y266630D03*
X693530Y261240D03*
X690660Y264000D03*
X690704Y271324D03*
X671100Y232200D03*
X701800Y246480D03*
X669750Y246350D03*
X710572Y244773D03*
X719360Y241504D03*
X710627Y242061D03*
X702000Y243900D03*
X722050Y221150D03*
X707653Y226347D03*
X718300Y227400D03*
X700900Y264100D03*
X694361Y223317D03*
Y220817D03*
X690861D03*
Y223317D03*
X672300Y269200D03*
X672200Y256800D03*
X706561Y219917D03*
X719900Y269300D03*
X725500Y279300D03*
X725300Y269400D03*
X719600Y279400D03*
X704175Y287275D03*
X704214Y290775D03*
X680000Y281900D03*
X672150Y288350D03*
X695300Y338100D03*
X695400Y328000D03*
X684100Y338200D03*
X695400Y318000D03*
X695800Y308000D03*
X696088Y297069D03*
X704500Y293800D03*
X707130Y310150D03*
X718200Y295000D03*
X706300Y318400D03*
X678200Y307800D03*
X672700Y307700D03*
X667100D03*
X678100Y324800D03*
X672200Y329800D03*
X678100Y329600D03*
X666900Y329700D03*
X678200Y313700D03*
Y319300D03*
X679000Y348000D03*
X688600Y365100D03*
X671936Y367171D03*
X665936Y370171D03*
X684900Y348000D03*
X674600D03*
X671936Y370171D03*
X665936Y367171D03*
X668936Y370171D03*
Y367171D03*
X665936Y364171D03*
X668936D03*
X669093Y348120D03*
X671936Y373171D03*
X668936D03*
X670300Y375600D03*
X713900Y347800D03*
X698560Y374430D03*
X713900Y342800D03*
Y352800D03*
Y350300D03*
Y345300D03*
X690040Y412030D03*
X685600Y432500D03*
X690600D03*
Y437500D03*
X703876Y414949D03*
X705850Y417093D03*
X710600Y420267D03*
X710423Y417423D03*
X708346Y415859D03*
X708011Y419078D03*
X712980Y417900D03*
X713493Y420449D03*
X723748Y499091D03*
X676900Y489400D03*
X666500Y487600D03*
Y484600D03*
X669500D03*
Y481600D03*
X664610Y512810D03*
X685050Y503970D03*
X704500Y512850D03*
X716267Y522020D03*
X703028Y495600D03*
X709028D03*
X706028D03*
X703028Y492600D03*
X706028D03*
X674200Y588900D03*
X690100Y575860D03*
X689193Y573493D03*
X693126Y581380D03*
X671599Y573493D03*
X671791Y588920D03*
X674099Y573493D03*
X669099D03*
X668891Y588900D03*
X713650Y540750D03*
X715650Y542250D03*
Y545250D03*
X713650Y546750D03*
X708000Y553250D03*
X720200Y551750D03*
X715650Y551250D03*
X696000Y553250D03*
X715650Y548250D03*
X713650Y549750D03*
X723200Y551750D03*
X699000Y553250D03*
X702000D03*
X705000D03*
X713650Y543750D03*
X723200Y554750D03*
X706500Y555750D03*
X703500D03*
X700500D03*
X720200Y554750D03*
X709500Y555750D03*
X712600Y571900D03*
X716300Y569400D03*
X707500Y587800D03*
X691900Y531350D03*
Y534850D03*
X697500Y534750D03*
Y531250D03*
X725173Y598171D03*
X724106Y609550D03*
X721106D03*
X708900Y589850D03*
X706100D03*
X732600Y3600D03*
X755500Y8700D03*
X753600Y-4300D03*
X736715Y33487D03*
X734201Y33510D03*
X726250Y23550D03*
X731457Y8471D03*
X732335Y6000D03*
X786414Y-9650D03*
X779771Y9114D03*
X773228D03*
Y-1801D03*
X779921Y-1751D03*
X776188Y-7851D03*
X769881Y-9901D03*
X782567Y-7700D03*
X786388Y9098D03*
Y-1801D03*
X786414Y28150D03*
X769881Y27899D03*
X782567Y14814D03*
Y30100D03*
X769881Y16839D03*
X776224Y14714D03*
X776188Y29949D03*
X786364Y16900D03*
X736631Y36122D03*
X736655Y38531D03*
X731887Y40916D03*
X734155Y38531D03*
X734131Y36122D03*
X731843Y43571D03*
X756100Y36200D03*
X755500Y46700D03*
X737800Y55800D03*
X751708Y73800D03*
X755500Y84361D03*
X786388Y35999D03*
X786364Y54700D03*
X786388Y46898D03*
X773228Y46914D03*
X779771D03*
X776188Y67749D03*
X769881Y66000D03*
X782567Y67900D03*
Y52614D03*
X769881Y54839D03*
X779921Y35983D03*
X773228D03*
X776224Y52514D03*
X769881Y92500D03*
X773228Y84714D03*
X779771D03*
X776224Y90314D03*
X782567Y90414D03*
X779921Y73849D03*
X773228Y73799D03*
X786414Y65950D03*
X786388Y73799D03*
X786364Y92500D03*
X786388Y84698D03*
X730600Y154984D03*
X746000Y150500D03*
X740718Y150957D03*
X769100Y102900D03*
X758400Y156200D03*
X747600Y161450D03*
X740650Y164800D03*
X735600Y164900D03*
X740650Y158800D03*
X754726Y205037D03*
X752226D03*
X749726D03*
X754726Y207537D03*
X752226D03*
X749726D03*
X742937Y218574D03*
X758400Y159200D03*
X774582Y212033D03*
X770200Y208600D03*
X775171Y218616D03*
X787371Y215216D03*
Y217716D03*
X777700Y218600D03*
X727969Y236770D03*
X736612Y237908D03*
X727997Y239195D03*
X736625Y240308D03*
X742897Y229573D03*
X746303Y243122D03*
X746321Y240569D03*
X760304Y235827D03*
X768560Y244055D03*
X769019Y276400D03*
X762616Y270113D03*
X761480Y242720D03*
X731100Y269300D03*
Y279300D03*
X787371Y247216D03*
Y249716D03*
X775232Y221133D03*
X777700Y250600D03*
X775232Y223633D03*
X775171Y250616D03*
X775232Y253133D03*
Y255633D03*
X787371Y279216D03*
X774347Y339983D03*
X762760Y339500D03*
X727300Y302910D03*
X727474Y338363D03*
Y335363D03*
X732474D03*
Y338363D03*
X756114Y316209D03*
X729974Y338363D03*
Y335363D03*
X771278Y307918D03*
X762842Y302434D03*
X765730Y335064D03*
X777700Y282600D03*
X775232Y287633D03*
Y285133D03*
X775171Y282616D03*
X787371Y281716D03*
Y311216D03*
X777800Y314700D03*
X775171Y314616D03*
X787371Y313716D03*
X775232Y317133D03*
Y319633D03*
X727474Y344663D03*
Y367463D03*
X732474D03*
X729974D03*
X727474Y364863D03*
X732474D03*
X729974D03*
Y347663D03*
X727474D03*
X732474D03*
Y344663D03*
X727574Y373463D03*
X732574D03*
X730074D03*
X732574Y376063D03*
X730074D03*
X729974Y344663D03*
X731100Y362300D03*
X772443Y371976D03*
X760140Y362819D03*
X758952Y384100D03*
X763333Y400212D03*
X772300Y403520D03*
X775171Y346616D03*
X787371Y343216D03*
Y345716D03*
X775232Y349133D03*
X777600Y346600D03*
X775232Y351633D03*
X787321Y374916D03*
Y377316D03*
X775182Y383633D03*
Y381133D03*
X778000Y378700D03*
X775121Y378616D03*
X749640Y431797D03*
X728940Y457806D03*
X775417Y435799D03*
X777979Y436516D03*
X752496Y515974D03*
X732522Y526808D03*
Y524308D03*
X750518Y522108D03*
X734922Y526808D03*
X776224Y515714D03*
X779771Y510114D03*
X773228D03*
X769881Y517900D03*
X782567Y515814D03*
X786388Y510098D03*
X786364Y517900D03*
X732442Y529300D03*
X734842D03*
X736300Y541500D03*
X756000Y537000D03*
X737400Y529400D03*
X734900Y531800D03*
X732400D03*
X726200Y551750D03*
X754910Y556400D03*
X726200Y554750D03*
X727400Y571300D03*
X755000Y574800D03*
X752500Y585150D03*
X727106Y586550D03*
X773228Y536999D03*
X763677Y547783D03*
X776188Y530949D03*
X782567Y531100D03*
X769818Y529200D03*
X779921Y537049D03*
X782567Y553614D03*
X773228Y547914D03*
X779771D03*
X776224Y553514D03*
X786388Y536999D03*
X786414Y529150D03*
X786388Y547898D03*
X786364Y555700D03*
X769881D03*
X773228Y574799D03*
X782567Y568900D03*
X769700Y566900D03*
X776188Y568749D03*
X779921Y574849D03*
X773228Y585714D03*
X779771D03*
X786388Y574799D03*
Y585698D03*
X786414Y566950D03*
X779921Y612649D03*
X773228Y612599D03*
X786388D03*
X755000Y614500D03*
X727000Y606600D03*
X766600Y590700D03*
X769700Y604900D03*
X776188Y606549D03*
X782567Y606700D03*
Y591414D03*
X776224Y591314D03*
X786414Y604750D03*
X786364Y593500D03*
X803346Y-1751D03*
X810039Y-1801D03*
X791514Y-2050D03*
X791501Y-9864D03*
X812999Y-7851D03*
X806692D03*
X799999D03*
X816582Y9114D03*
X796653D03*
X791464Y9100D03*
X810039Y9114D03*
X803346D03*
X816732Y-1751D03*
X796653D03*
X799999Y29949D03*
X806692D03*
X812999D03*
X791501Y27936D03*
X791488Y17114D03*
X799999Y14814D03*
X813035Y14714D03*
X806692Y14814D03*
X828275Y9100D03*
X833464Y9114D03*
X840157D03*
X819378Y-7700D03*
X823199Y9098D03*
Y-1801D03*
X823225Y-9650D03*
X828312Y-9864D03*
X843503Y-7851D03*
X836810D03*
X846850Y-1801D03*
X828325Y-2050D03*
X833464Y-1751D03*
X840157D03*
X846850Y9114D03*
X819378Y14814D03*
Y30100D03*
X843503Y14814D03*
X823175Y16900D03*
X823225Y28150D03*
X828312Y27936D03*
X836810Y29949D03*
X828299Y17114D03*
X836810Y14814D03*
X843503Y29949D03*
X791488Y54914D03*
X799999Y52614D03*
X796653Y46914D03*
X791464Y46900D03*
X810039Y35999D03*
X803346Y36049D03*
X799999Y90414D03*
X791488Y92714D03*
X806692Y90414D03*
X816582Y46914D03*
X816732Y36049D03*
X799999Y67749D03*
X812999D03*
X806692D03*
X791501Y65736D03*
X803346Y46914D03*
X806692Y52614D03*
X813035Y52514D03*
X810039Y46914D03*
X791514Y35750D03*
X796653Y36049D03*
X816582Y73849D03*
X791514Y73550D03*
X796653Y73849D03*
X810039Y73799D03*
X803346Y73849D03*
X816582Y84714D03*
X813035Y90314D03*
X803346Y84714D03*
X810039D03*
X796653D03*
X791464Y84700D03*
X819378Y67900D03*
Y52614D03*
X846850Y35999D03*
X833464Y36049D03*
X840157D03*
X823225Y65950D03*
X823175Y54700D03*
X823199Y46898D03*
Y35999D03*
X828299Y54914D03*
X828275Y46900D03*
X828325Y35750D03*
X833464Y46914D03*
X836810Y52614D03*
X840157Y46914D03*
X828312Y65736D03*
X836810Y67749D03*
X843503D03*
X846850Y46914D03*
X843503Y52614D03*
X823175Y92500D03*
X823199Y84698D03*
X846850Y73799D03*
X843503Y90414D03*
X846850Y84714D03*
X828325Y73550D03*
X840157Y73849D03*
X833464D03*
X828299Y92714D03*
X836810Y90414D03*
X840157Y84714D03*
X833464D03*
X828275Y84700D03*
X819378Y90364D03*
X823199Y73799D03*
X790871Y215216D03*
Y217716D03*
X845100Y268200D03*
X847600D03*
X842600D03*
X847600Y243400D03*
X841400Y243300D03*
X847600Y238400D03*
X841400Y238300D03*
X847600Y240900D03*
X841400Y240800D03*
X789500Y231800D03*
X790900Y234000D03*
Y229700D03*
X790846Y225774D03*
X790882Y221723D03*
X790871Y247216D03*
Y249716D03*
X789471Y227742D03*
X789576Y223737D03*
X789554Y219723D03*
X790900Y253900D03*
X789432Y252000D03*
X790871Y266216D03*
X789432Y255800D03*
X790867Y257724D03*
X789432Y259800D03*
X789500Y263900D03*
X790885Y261711D03*
X790871Y279216D03*
X842600Y299900D03*
X845100D03*
X847600D03*
X845100Y331500D03*
X842600D03*
X847600D03*
X790871Y311216D03*
X789432Y284200D03*
Y288300D03*
Y292400D03*
X789400Y296200D03*
X790871Y298216D03*
X790937Y294270D03*
X790900Y290300D03*
Y286200D03*
X790871Y281716D03*
Y313716D03*
X789432Y319900D03*
Y323900D03*
X790900Y322000D03*
Y326000D03*
X790871Y330216D03*
X789500Y328000D03*
X789478Y315671D03*
X790800Y317700D03*
X847600Y363000D03*
X845100D03*
X842600D03*
X847577Y381842D03*
X789432Y348100D03*
Y352100D03*
X789597Y356105D03*
X789500Y360200D03*
X790900Y358200D03*
X790835Y354048D03*
X790867Y350024D03*
X790871Y345716D03*
Y343216D03*
Y362216D03*
X790821Y374916D03*
X790900Y389300D03*
X789500Y391300D03*
X790900Y393400D03*
Y381100D03*
X789582Y383200D03*
X790900Y385300D03*
X789500Y387300D03*
X790821Y377316D03*
X789282Y379200D03*
X816582Y510114D03*
X806692Y515814D03*
X813035Y515714D03*
X810039Y510114D03*
X791488Y518114D03*
X791464Y510100D03*
X799999Y515814D03*
X796653Y510114D03*
X803346D03*
X819378Y515764D03*
X843503Y515814D03*
X846850Y510114D03*
X823175Y517900D03*
X823199Y510098D03*
X828299Y518114D03*
X840157Y510114D03*
X833464D03*
X836810Y515814D03*
X816582Y537049D03*
Y547914D03*
X810039Y536999D03*
X806692Y530949D03*
X812999D03*
X803346Y537049D03*
X796653D03*
X799999Y530949D03*
X791501Y528936D03*
X791514Y536750D03*
X799999Y553614D03*
X810039Y547914D03*
X796653D03*
X803346D03*
X791464Y547900D03*
X806692Y553614D03*
X813035Y553514D03*
X791488Y555914D03*
X810039Y585714D03*
X806692Y568749D03*
X810039Y574799D03*
X812999Y568749D03*
X803346Y585714D03*
X796653D03*
X791514Y574550D03*
X791464Y585700D03*
X799999Y568749D03*
X796653Y574849D03*
X803346D03*
X791501Y566736D03*
X816582Y585714D03*
Y574849D03*
X819378Y553564D03*
Y531100D03*
X836810Y530949D03*
X833464Y537049D03*
X846850Y547914D03*
X833464D03*
X840157D03*
X828275Y547900D03*
X843503Y553614D03*
X836810D03*
X846850Y536999D03*
X843503Y530949D03*
X823199Y547898D03*
Y536999D03*
X823225Y529150D03*
X828325Y536750D03*
X840157Y537049D03*
X828312Y528936D03*
X819378Y568900D03*
X823175Y555700D03*
X828299Y555914D03*
X828275Y585700D03*
X823225Y566950D03*
X823199Y585698D03*
Y574799D03*
X828312Y566736D03*
X840157Y585714D03*
X833464D03*
X828325Y574550D03*
X840157Y574849D03*
X833464D03*
X836810Y568749D03*
X846850Y585714D03*
Y574799D03*
X843503Y568749D03*
X846850Y612599D03*
X840157Y612649D03*
X833464D03*
X823199Y612599D03*
X810039D03*
X803346Y612649D03*
X796653D03*
X816582D03*
X791514Y612350D03*
X806692Y606549D03*
X812999D03*
X799999D03*
X791501Y604536D03*
X806692Y591414D03*
X813035Y591314D03*
X799999Y591414D03*
X791488Y593714D03*
X819378Y606700D03*
Y591364D03*
X823225Y604750D03*
X823175Y593500D03*
X843503Y591414D03*
X828312Y604536D03*
X843503Y606549D03*
X836810D03*
X828325Y612350D03*
X836810Y591414D03*
X828299Y593714D03*
X870275Y9114D03*
X865086Y9100D03*
X860010Y9098D03*
X876968Y9114D03*
Y-1751D03*
X873621Y-7851D03*
X865123Y-9864D03*
X860036Y-9650D03*
X849810Y-7851D03*
X856189Y-7700D03*
X860010Y-1801D03*
X865136Y-2050D03*
X853543Y-1751D03*
X870275D03*
X853393Y9114D03*
X860036Y28150D03*
X859986Y16900D03*
X865110Y17114D03*
X856189Y14814D03*
X849846Y14714D03*
X873621Y14814D03*
Y29949D03*
X865123Y27936D03*
X849810Y29949D03*
X856189Y30100D03*
X896847Y-9650D03*
X910432Y-7851D03*
X883661Y-1801D03*
X880314Y-7851D03*
X886621D03*
X907086Y-1751D03*
X890354D03*
X896821Y-1801D03*
X901947Y-2050D03*
X901934Y-9864D03*
X893000Y-7700D03*
X883661Y9114D03*
X907086D03*
X896821Y9098D03*
X901897Y9100D03*
X890204Y9114D03*
X910432Y29949D03*
X896797Y16900D03*
X893000Y14814D03*
X901921Y17114D03*
X901934Y27936D03*
X893000Y30100D03*
X880314Y14814D03*
X886657Y14714D03*
X886621Y29949D03*
X880314D03*
X896847Y28150D03*
X910432Y14814D03*
X859986Y54700D03*
X870275Y36049D03*
X865136Y35750D03*
X865086Y46900D03*
X876968Y46914D03*
Y36049D03*
X873621Y67749D03*
Y52614D03*
X860010Y46898D03*
X860036Y65950D03*
X865123Y65736D03*
X849810Y67749D03*
X856189Y67900D03*
X853393Y46914D03*
X870275D03*
X865110Y54914D03*
X860010Y35999D03*
X856189Y52614D03*
X853543Y36049D03*
X849846Y52514D03*
X876968Y84714D03*
Y73849D03*
X873621Y90414D03*
X870275Y73849D03*
X853543D03*
X860010Y73799D03*
X849846Y90314D03*
X856189Y90414D03*
X865110Y92714D03*
X870275Y84714D03*
X865086Y84700D03*
X853393Y84714D03*
X860010Y84698D03*
X859986Y92500D03*
X865136Y73550D03*
X910432Y67749D03*
X893000Y67900D03*
X901934Y65736D03*
X896847Y65950D03*
X910432Y52614D03*
X890204Y46914D03*
X896821Y35999D03*
X901921Y54914D03*
X896797Y54700D03*
X883661Y35999D03*
X886621Y67749D03*
X880314D03*
X883661Y46914D03*
X880314Y52614D03*
X886657Y52514D03*
X901947Y35750D03*
X901897Y46900D03*
X896821Y46898D03*
X893000Y52614D03*
X890354Y36049D03*
X907086D03*
X883661Y73799D03*
X910432Y90414D03*
X907086Y84714D03*
X901897Y84700D03*
X907086Y46914D03*
X896821Y84698D03*
X893000Y90414D03*
X890204Y84714D03*
X896797Y92500D03*
X901921Y92714D03*
X890354Y73849D03*
X896821Y73799D03*
X901947Y73550D03*
X907086Y73849D03*
X883661Y84714D03*
X886657Y90314D03*
X880314Y90414D03*
X886657Y109884D03*
X907086Y104284D03*
X901934Y105051D03*
X896847Y105265D03*
X890204Y104284D03*
X893000Y109534D03*
X896821Y113114D03*
X901947Y112865D03*
X910432Y109984D03*
X883661Y104284D03*
X873621Y515814D03*
X876968Y510114D03*
X870275D03*
X859986Y517900D03*
X865086Y510100D03*
X860010Y510098D03*
X865110Y518114D03*
X853393Y510114D03*
X856189Y515814D03*
X849846Y515714D03*
X907000Y495800D03*
X882900Y495900D03*
X893000Y493094D03*
X886500Y493400D03*
X910432Y491044D03*
X901921Y490514D03*
X896785D03*
X901921Y498514D03*
X896785D03*
X889100Y498500D03*
X901897Y510100D03*
X893000Y515814D03*
X890204Y510114D03*
X896821Y510098D03*
X901921Y518114D03*
X896797Y517900D03*
X880314Y515814D03*
X886657Y515714D03*
X883661Y510114D03*
X910432Y515814D03*
X907086Y510114D03*
X860010Y536999D03*
X865123Y528936D03*
X873621Y530949D03*
Y553614D03*
X876968Y537049D03*
Y547914D03*
X860010Y547898D03*
X870275Y547914D03*
X853393D03*
X865086Y547900D03*
X856189Y553614D03*
X849846Y553514D03*
X870275Y537049D03*
X853543D03*
X856189Y531100D03*
X849810Y530949D03*
X865136Y536750D03*
X860036Y529150D03*
X849810Y568749D03*
X865086Y585700D03*
X860010Y585698D03*
X865136Y574550D03*
X859986Y555700D03*
X865110Y555914D03*
X860010Y574799D03*
X853393Y585714D03*
X870275D03*
X873621Y568749D03*
X876968Y574849D03*
Y585714D03*
X860036Y566950D03*
X865123Y566736D03*
X870275Y574849D03*
X853543D03*
X856189Y568900D03*
X890354Y537049D03*
X893000Y531100D03*
X896821Y536999D03*
X901934Y528936D03*
X901947Y536750D03*
X910432Y530949D03*
X907086Y537049D03*
X886621Y530949D03*
X883661Y536999D03*
X880314Y530949D03*
Y553614D03*
X886657Y553514D03*
X883661Y547914D03*
X893000Y553614D03*
X910432D03*
X890204Y547914D03*
X896821Y547898D03*
X901897Y547900D03*
X907086Y547914D03*
X880314Y568749D03*
X886621D03*
X883661Y574799D03*
Y585714D03*
X901921Y555914D03*
X896797Y555700D03*
X901934Y566736D03*
X896847Y566950D03*
X901897Y585700D03*
X890354Y574849D03*
X896821Y574799D03*
X893000Y568900D03*
X901947Y574550D03*
X896821Y585698D03*
X890204Y585714D03*
X910432Y568749D03*
X907086Y574849D03*
Y585714D03*
X890354Y612649D03*
X896821Y612599D03*
X883661D03*
X907086Y612649D03*
X870275D03*
X876968D03*
X860010Y612599D03*
X853543Y612649D03*
X859986Y593500D03*
X865110Y593714D03*
X856189Y591414D03*
X849846Y591314D03*
X860036Y604750D03*
X865123Y604536D03*
X856189Y606700D03*
X849810Y606549D03*
X865136Y612350D03*
X873621Y606549D03*
Y591414D03*
X886657Y591314D03*
X896847Y604750D03*
X901934Y604536D03*
X901947Y612350D03*
X896797Y593500D03*
X901921Y593714D03*
X893000Y591414D03*
X910432D03*
Y606549D03*
X893000Y606700D03*
X880314Y606549D03*
X886621D03*
X880314Y591414D03*
X923432Y-7851D03*
X929811Y-7700D03*
X933658Y-9650D03*
X917125Y-7851D03*
X913779Y-1751D03*
X933632Y-1801D03*
X927165Y-1751D03*
X920472Y-1801D03*
X927015Y9114D03*
X933632Y9098D03*
X913779Y9114D03*
X920472D03*
X923432Y29949D03*
X917125D03*
Y14814D03*
X929811D03*
X933608Y16900D03*
X923468Y14714D03*
X933658Y28150D03*
X929811Y30100D03*
X938745Y-9864D03*
X938758Y-2050D03*
X938708Y9100D03*
X947243Y-7851D03*
X950590Y-1751D03*
X957283Y-1843D03*
X953936Y-7851D03*
X943897Y-1751D03*
Y9114D03*
X950590D03*
X967322Y28014D03*
X960629D03*
X938745Y27936D03*
X938732Y17114D03*
X957283Y9300D03*
X953936Y14814D03*
Y29949D03*
X957600Y13200D03*
X957700Y32100D03*
X970800Y13200D03*
X947243Y29949D03*
Y14814D03*
X933658Y65950D03*
X923432Y67749D03*
X929811Y67900D03*
X917125Y67749D03*
X920472Y35999D03*
X917125Y52614D03*
X913779Y46914D03*
Y36049D03*
X927015Y73849D03*
X913779D03*
X920472Y73799D03*
X933632D03*
X913779Y84714D03*
X920472D03*
X933608Y92500D03*
X920472Y46914D03*
X933632Y35999D03*
X927165Y36049D03*
X927015Y46914D03*
X933608Y54700D03*
X933632Y46898D03*
X929811Y52614D03*
X933632Y84698D03*
X927015Y84714D03*
X923468Y90314D03*
X929811Y90414D03*
X917125D03*
X953936Y52614D03*
X957558Y50729D03*
X967322Y65814D03*
X960629D03*
X970669Y35957D03*
Y46914D03*
X967322Y54857D03*
X963976Y35957D03*
Y46914D03*
X960629Y54857D03*
X938758Y35750D03*
X938708Y46900D03*
X938732Y54914D03*
X938745Y65736D03*
X950590Y36049D03*
X953936Y67749D03*
X950590Y46914D03*
X947243Y67749D03*
X943897Y36049D03*
Y46914D03*
X947243Y52614D03*
X957283Y35957D03*
X963976Y73757D03*
X960629Y89964D03*
X963976Y87392D03*
X967322Y89964D03*
X970669Y87392D03*
Y73757D03*
X938708Y84700D03*
X938732Y92714D03*
X938758Y73550D03*
X957600Y70400D03*
X943897Y84714D03*
X947243Y90414D03*
X943897Y73849D03*
X950590D03*
X953886Y90414D03*
X950590Y84714D03*
X957774Y87394D03*
X957200Y73800D03*
X933658Y105265D03*
X929811Y109534D03*
X933632Y113114D03*
X923468Y109884D03*
X917125Y109984D03*
X920472Y104284D03*
X913779D03*
X927015D03*
X963245Y105725D03*
X938758Y112865D03*
X938745Y105051D03*
X947250Y107700D03*
X950600Y112300D03*
X953800Y105000D03*
X927607Y203260D03*
Y207159D03*
X934367D03*
Y199360D03*
X930987Y201309D03*
X934367Y214960D03*
X930987Y213009D03*
X920847Y211060D03*
X927607Y214960D03*
Y211060D03*
X937747Y216909D03*
X924227D03*
Y213009D03*
X968166Y218860D03*
X951256Y194841D03*
X958026Y201309D03*
X967036Y193507D03*
X947887Y203260D03*
Y207159D03*
X944507Y213009D03*
Y201309D03*
X947887Y199360D03*
X941127D03*
Y207159D03*
X947887Y211060D03*
Y218860D03*
X941127D03*
Y214960D03*
X962526Y205210D03*
X961406Y214960D03*
Y211060D03*
Y218860D03*
X951267Y209109D03*
X958026Y213009D03*
X954647Y211060D03*
Y218860D03*
X964786Y213009D03*
Y216909D03*
Y209109D03*
X934367Y226660D03*
X924227Y236409D03*
X920847Y238360D03*
X913787Y226660D03*
X913700Y222710D03*
X913787Y238360D03*
X924227Y232509D03*
X927607Y230559D03*
Y234460D03*
X930987Y232509D03*
X934367Y234460D03*
X924227Y228610D03*
X930987Y220809D03*
X924227Y224709D03*
X937747Y232509D03*
Y236409D03*
X924227Y240309D03*
X917467D03*
X930987D03*
X924227Y248109D03*
Y244209D03*
X917467D03*
X913787Y250060D03*
X934367Y246160D03*
X927607Y250060D03*
X924227Y220809D03*
X913787Y253960D03*
X927607D03*
X934367D03*
X937747Y252009D03*
X930987D03*
X924227D03*
X917467D03*
Y259809D03*
X924227D03*
X930987D03*
X920847Y265660D03*
X930987Y275409D03*
X937747D03*
Y271509D03*
Y255909D03*
X934367Y277360D03*
X930987Y271509D03*
X934367Y273460D03*
X927607Y269560D03*
X917467Y263709D03*
X913787Y265660D03*
X924227Y267609D03*
X934367Y265660D03*
X924227Y263709D03*
Y275409D03*
X927607Y277360D03*
X920847Y273460D03*
Y269560D03*
X924227Y255909D03*
X951267Y248109D03*
X958026Y244209D03*
X968166Y242260D03*
X944507Y228610D03*
Y224709D03*
Y244209D03*
Y248109D03*
X941127Y242260D03*
Y250060D03*
Y246160D03*
X947887D03*
X941127Y222760D03*
X947887Y226660D03*
Y234460D03*
X941127Y238360D03*
Y234460D03*
Y230559D03*
Y226660D03*
X971546Y248109D03*
X968166Y246160D03*
X951267Y240309D03*
X958026D03*
X964786D03*
X954647Y246160D03*
Y250060D03*
X958026Y228610D03*
Y236409D03*
X961406Y238360D03*
X951267Y228610D03*
X954647Y226660D03*
X958026Y224709D03*
Y232509D03*
X954647Y230559D03*
X961406Y222760D03*
X968166Y226660D03*
X971546Y236409D03*
X968166Y238360D03*
X971546Y220809D03*
X964786Y232509D03*
Y220809D03*
X947887Y253960D03*
X941127D03*
X958026Y252009D03*
X968166Y277360D03*
X951267Y275409D03*
X961406Y277360D03*
X958026Y263709D03*
X968166Y269560D03*
X961406Y261760D03*
X958026Y255909D03*
X951267Y259809D03*
X958026D03*
X954647Y277360D03*
Y265660D03*
X951267Y267609D03*
X954647Y273460D03*
X958026Y275409D03*
X954647Y269560D03*
X961406D03*
X971546Y275409D03*
Y263709D03*
X941127Y277360D03*
Y265660D03*
X944507Y275409D03*
Y263709D03*
X941127Y269560D03*
Y257860D03*
Y261760D03*
X947887Y277360D03*
Y265660D03*
X971546Y259809D03*
Y255909D03*
X964786Y279310D03*
X934367Y285160D03*
Y300760D03*
X927607D03*
Y308560D03*
X934367D03*
X927607Y285160D03*
Y292959D03*
X934367D03*
X937747Y318309D03*
Y341709D03*
Y326110D03*
X917467Y333909D03*
Y341709D03*
X913787Y339760D03*
X924227Y333909D03*
Y337809D03*
Y341709D03*
X913787Y328060D03*
X924227Y330009D03*
X920847Y328060D03*
X917467Y330009D03*
X930987Y326110D03*
X934367Y331960D03*
X927607Y328060D03*
X934367Y324160D03*
X924227Y322209D03*
X927607Y320260D03*
X930987Y318309D03*
X934367Y316360D03*
X927607D03*
X930987Y337809D03*
X924227Y326110D03*
X961406Y292959D03*
Y285160D03*
X954647Y292959D03*
Y285160D03*
X968166Y292959D03*
Y300760D03*
X971546Y310509D03*
X964786D03*
X954647Y308560D03*
X961406D03*
X954647Y300760D03*
X961406D03*
X964786Y283209D03*
X971546D03*
X947887Y308560D03*
X941127D03*
Y300760D03*
X947887D03*
X941127Y285160D03*
Y292959D03*
X947887D03*
Y285160D03*
X968166Y281260D03*
X958026Y333909D03*
Y337809D03*
Y341709D03*
Y318309D03*
X951267D03*
X954647Y316360D03*
X961406D03*
Y324160D03*
X971546Y337809D03*
X964786Y330009D03*
X971546D03*
X951267D03*
X958026D03*
X968166Y312460D03*
X964786Y314409D03*
X951267Y337809D03*
X954647Y331960D03*
Y328060D03*
X971546Y322209D03*
X968166Y320260D03*
X964786Y322209D03*
X958026Y326110D03*
X947887Y316360D03*
X941127D03*
X944507Y322209D03*
Y318309D03*
X947887Y331960D03*
Y328060D03*
X941127Y331960D03*
Y328060D03*
Y339760D03*
Y335860D03*
X944507Y333909D03*
X937747Y365109D03*
Y345609D03*
Y361209D03*
X924227Y365109D03*
X930987D03*
X927607Y367060D03*
X934367Y370959D03*
Y363160D03*
X927607D03*
X924227Y369010D03*
X913787Y343660D03*
X934367D03*
X927607D03*
Y347560D03*
X934367Y351460D03*
X930987Y357309D03*
Y345609D03*
X917467Y353409D03*
Y349509D03*
X913787Y355360D03*
X924227Y349509D03*
Y345609D03*
Y353409D03*
Y361209D03*
Y357309D03*
X920847Y355360D03*
X917167Y361209D03*
Y369010D03*
X934367Y382660D03*
X930987Y384609D03*
Y376809D03*
X934367Y390460D03*
X927607Y386560D03*
Y390460D03*
X930987Y396309D03*
X934367Y398260D03*
X927607Y394359D03*
X917467Y388509D03*
X924227Y392410D03*
X920847Y390460D03*
X924227Y372909D03*
X937747Y400209D03*
X917100Y380709D03*
X937747D03*
X924227D03*
X920847Y382660D03*
X924227Y376809D03*
X927607Y382660D03*
X968166Y370959D03*
X958026Y361209D03*
X954647Y347560D03*
X961406Y359260D03*
X958026Y357309D03*
X951267D03*
X941127Y355360D03*
Y347560D03*
Y351460D03*
X958026Y345609D03*
X951267Y349509D03*
X954647Y351460D03*
X958026Y353409D03*
X968166Y355360D03*
Y351460D03*
X964786Y357309D03*
X971546Y361209D03*
X968166Y359260D03*
X958026Y365109D03*
X964786D03*
X954647Y370959D03*
Y367060D03*
X958026Y369010D03*
X951267D03*
X971546Y349509D03*
X947887Y363160D03*
X941127D03*
X947887Y370959D03*
X941127D03*
Y367060D03*
X944507Y369010D03*
X947887Y343660D03*
X941127Y359260D03*
X944507Y349509D03*
Y353409D03*
X941127Y343660D03*
X947887Y351460D03*
X958026Y372909D03*
X941127Y374860D03*
X961406D03*
X944507Y372909D03*
X941127Y382660D03*
Y378760D03*
X947887D03*
X944507Y384609D03*
X947887Y390460D03*
Y386560D03*
X941127Y390460D03*
X947887Y398260D03*
X941127D03*
X944507Y396309D03*
X947887Y394359D03*
X964786Y376809D03*
X971546D03*
X968166Y378760D03*
Y386560D03*
X964786Y392410D03*
X968166Y390460D03*
Y394359D03*
X964786Y388509D03*
X961406Y378760D03*
X954647D03*
X958026Y384609D03*
X961406Y382660D03*
X951267Y388509D03*
X958026D03*
X954647Y394359D03*
X961406Y386560D03*
X952216Y402421D03*
X970416Y401941D03*
X971546Y380709D03*
X968166Y382660D03*
X920700Y495944D03*
X913800Y495800D03*
X927165Y495944D03*
X929811Y515814D03*
X933632Y510098D03*
X923600Y491144D03*
X917192Y491219D03*
X933632Y490644D03*
X929811D03*
X933632Y498644D03*
X933608Y517900D03*
X913779Y510114D03*
X917125Y515814D03*
X923468Y515714D03*
X920472Y510114D03*
X927015D03*
X938732Y490644D03*
X950700Y490700D03*
X943897Y490444D03*
X970669Y512792D03*
X967322Y515364D03*
X963976Y512792D03*
X960629Y515364D03*
X938708Y510100D03*
X938732Y518114D03*
Y498644D03*
X954000Y497300D03*
X953886Y515814D03*
X950590Y510114D03*
X943897D03*
X947243Y515814D03*
X947443Y497644D03*
X957774Y512794D03*
X961309Y499136D03*
X933632Y536999D03*
X929811Y531100D03*
X933658Y529150D03*
X913779Y537049D03*
X917125Y530949D03*
X927015Y537049D03*
X923432Y530949D03*
X920472Y536999D03*
X923468Y553514D03*
X917125Y553614D03*
X913779Y547914D03*
X927015D03*
X920472D03*
X933632Y547898D03*
X929811Y553614D03*
X933608Y555700D03*
X933632Y585698D03*
X933658Y566950D03*
X929811Y568900D03*
X933632Y574799D03*
X920472D03*
X927015Y585714D03*
X920472D03*
X913779Y574849D03*
X917125Y568749D03*
X913779Y585714D03*
X923432Y568749D03*
X927015Y574849D03*
X960629Y529014D03*
X963976Y536957D03*
X970669D03*
X967322Y529014D03*
X963976Y547914D03*
X970669D03*
X938745Y528936D03*
X938758Y536750D03*
X938708Y547900D03*
X957600Y533100D03*
X957701Y552000D03*
X950590Y537049D03*
X957283Y536957D03*
X953936Y530949D03*
X957283Y548200D03*
X953886Y553614D03*
X950590Y547914D03*
X947243Y530949D03*
X943897Y537049D03*
Y547914D03*
X947243Y553614D03*
X967322Y555857D03*
X960629D03*
X970669Y574757D03*
X960629Y566814D03*
X963976Y574757D03*
X967322Y566814D03*
X938732Y555914D03*
X938745Y566736D03*
X938758Y574550D03*
X938708Y585700D03*
X957600Y570900D03*
X950590Y574849D03*
Y585714D03*
X957283Y574757D03*
X957456Y588334D03*
X953936Y568749D03*
X943897Y574849D03*
X947243Y568749D03*
X943897Y585714D03*
X933632Y612599D03*
X923432Y606549D03*
X917125D03*
X933658Y604750D03*
X923468Y591314D03*
X917125Y591414D03*
X933608Y593500D03*
X929811Y591414D03*
X927015Y612449D03*
X920472Y612399D03*
X913779Y612449D03*
X929811Y606700D03*
X938758Y612350D03*
X938745Y604536D03*
X938732Y593714D03*
X957500Y591000D03*
X970731Y589800D03*
X953936Y606549D03*
X957283Y611600D03*
X950590Y612249D03*
X953886Y591414D03*
X947243Y606549D03*
X943897Y612249D03*
X947243Y591414D03*
X977362Y28014D03*
X987401D03*
X997441Y28022D03*
X983900Y13200D03*
X1028400Y6500D03*
X1030407Y-8938D03*
X1007480Y28014D03*
X1017519D03*
X1007100Y11714D03*
X1030450Y23150D03*
X1007100Y14314D03*
X987401Y65814D03*
X977362D03*
X987401Y54857D03*
X977362D03*
X990748Y46922D03*
Y35957D03*
X980708D03*
Y46914D03*
X997441Y65822D03*
Y54857D03*
Y92757D03*
X990748Y73757D03*
Y87392D03*
X977362Y92757D03*
X987401Y89964D03*
X980708Y84714D03*
Y73757D03*
X1000787Y35957D03*
Y46922D03*
X1017519Y54842D03*
X1007480Y46914D03*
X1008226Y54842D03*
X1008217Y35942D03*
X1007480Y65736D03*
X1016600Y65950D03*
X1017519Y35942D03*
Y46914D03*
X1017919Y92500D03*
X1017519Y87500D03*
X1000787Y84599D03*
Y73757D03*
X1007480Y87500D03*
X1007573Y92500D03*
X1008099Y73479D03*
X1017350Y73450D03*
X976200Y105600D03*
X983936Y199108D03*
X973808Y201308D03*
X995206Y203260D03*
X988446Y218860D03*
X995206Y214960D03*
X981686Y218860D03*
X974926Y211060D03*
X979426Y214958D03*
X1001965Y214960D03*
X1027875Y193507D03*
X1032385Y201309D03*
X1015485Y203260D03*
Y214960D03*
X1022245D03*
X1012105Y205210D03*
X1025625Y205211D03*
X1029005Y214960D03*
X1007595Y193507D03*
X1005345Y205210D03*
X1008725Y214960D03*
X988446Y234460D03*
X998586Y248109D03*
X985066D03*
X981686Y250060D03*
X974926D03*
X988446Y246160D03*
X981686Y242260D03*
X974926D03*
X988446D03*
X998586Y244209D03*
Y232509D03*
X991826Y244209D03*
Y232509D03*
X995206Y226660D03*
X988446Y238360D03*
X985066Y236409D03*
X981686Y234460D03*
X974926Y226660D03*
Y230559D03*
Y234460D03*
Y222760D03*
X978306Y232509D03*
Y220809D03*
X974926Y253960D03*
X988446D03*
X978306Y252009D03*
X985066D03*
X974926Y265660D03*
X991826Y259809D03*
X985066D03*
X981686Y269560D03*
X995206D03*
X985066Y267609D03*
X991826Y263709D03*
X988446Y265660D03*
X998586Y263709D03*
X991826Y271509D03*
X995206Y273460D03*
X991826Y279310D03*
Y275409D03*
X974926Y269560D03*
X978306Y267609D03*
Y259809D03*
X991826Y255909D03*
X995206Y265660D03*
X991826Y267609D03*
X974926Y273460D03*
X1032385Y232509D03*
X1018865Y244209D03*
X1012105D03*
X1018865Y232509D03*
X1015485Y226660D03*
X1022245D03*
X1012105Y232509D03*
X1025625D03*
X1029005Y226660D03*
X1005345Y244209D03*
X1008725Y226660D03*
X1005345Y232509D03*
X1001965Y226660D03*
X1005345Y248109D03*
X1022245Y250060D03*
X1001965Y261760D03*
X1012105Y255909D03*
X1015485Y253960D03*
X1018865Y252009D03*
X1005345Y259809D03*
X1008725Y257860D03*
X981686Y281260D03*
Y292959D03*
Y300760D03*
X988446D03*
X978306Y310509D03*
X991826D03*
X985066D03*
X974926Y300760D03*
X988446Y292959D03*
X991826Y283209D03*
X988446Y281260D03*
X985066Y283209D03*
X978306D03*
X974926Y292959D03*
Y281260D03*
X991826Y333909D03*
X995206Y335860D03*
Y339760D03*
Y328060D03*
X991826Y326110D03*
X981686Y339760D03*
X978306Y333909D03*
Y330009D03*
Y326110D03*
X981686Y331960D03*
X985066Y330009D03*
X974926Y324160D03*
X988446Y339760D03*
X974926Y312460D03*
X981686D03*
X988446D03*
X991826Y314409D03*
Y330009D03*
X995206Y331960D03*
X988446D03*
X995206Y324160D03*
X988446Y316360D03*
X991826Y318309D03*
X995206Y320260D03*
X991826Y322209D03*
X998586Y333909D03*
X974926Y339760D03*
Y335860D03*
X1017957Y312421D03*
X1025438Y312381D03*
X1022915Y312372D03*
X1020404Y312408D03*
X1028039Y312414D03*
X1008725Y339760D03*
X1005345Y337809D03*
X1001965Y335860D03*
X1012105Y341709D03*
X995206Y343660D03*
X985066Y361209D03*
X974926Y355360D03*
Y347560D03*
X981686D03*
X978306Y345609D03*
X981686Y355360D03*
X985066Y349509D03*
X998586D03*
X978306Y365109D03*
X981686Y363160D03*
X974926D03*
Y367060D03*
Y370959D03*
X988446Y367060D03*
X998586Y365109D03*
Y353409D03*
X991826Y365109D03*
X995206Y370959D03*
X991826Y353409D03*
X974926Y343660D03*
X988446Y359260D03*
Y347560D03*
X991826Y345609D03*
X988446Y351460D03*
Y355360D03*
X998586Y392410D03*
X988446Y382660D03*
X995206D03*
X985066Y372909D03*
X974926Y374860D03*
X985066Y384609D03*
X974926Y386560D03*
X974066Y399911D03*
X978306Y376809D03*
X974926Y378760D03*
X981686D03*
X985066Y380709D03*
X1005345Y365109D03*
X1008725Y370959D03*
X1001965D03*
X1005345Y353409D03*
X1018865Y365109D03*
X1012105D03*
X1025625D03*
X1022245Y370959D03*
X1015485D03*
X1018865Y353409D03*
X1012105D03*
X1025625D03*
X1029005Y370959D03*
X1032385Y365109D03*
X1005345Y349509D03*
X1018865Y345609D03*
X1022245Y347560D03*
X1015485Y343660D03*
X1025625Y345609D03*
X1029005Y347560D03*
X1032385Y349509D03*
X1007595Y402800D03*
X1008725Y382660D03*
X1001965D03*
X1005345Y392410D03*
X1029005Y390460D03*
X1025625Y392410D03*
X1022245Y382660D03*
X1015485D03*
X1012105Y392410D03*
X1018865D03*
X1029005Y382660D03*
X1027875Y402800D03*
X987401Y515364D03*
X990748Y512792D03*
X997441Y518157D03*
X976421Y499768D03*
X980708Y510114D03*
X977362Y518157D03*
X1000490Y509999D03*
X1016473Y515152D03*
Y510114D03*
X1008650Y515200D03*
X1008526Y510114D03*
X990748Y536957D03*
X977362Y529014D03*
X980708Y536957D03*
X987401Y529014D03*
X990748Y547922D03*
X980708Y547914D03*
X997441Y529022D03*
X977362Y555857D03*
X987401D03*
X997441D03*
X977362Y566814D03*
X990748Y574757D03*
X980708D03*
X997441Y566822D03*
X987401Y566814D03*
X1000787Y536957D03*
Y547922D03*
X1017300Y536200D03*
X1017519Y529057D03*
X1017300Y547914D03*
X1007518Y536727D03*
X1007480Y528942D03*
X1007280Y547914D03*
X1016800Y566814D03*
Y574742D03*
X1006406Y588366D03*
X1016473Y585714D03*
X1026500Y577500D03*
X1000787Y574757D03*
X1016819Y555842D03*
X1007518D03*
Y566814D03*
X1007480Y574742D03*
X983900Y589800D03*
X1023200Y610700D03*
X1022950Y593650D03*
X1025450D03*
X1006406Y590966D03*
X1043800Y-9700D03*
X1057792Y13200D03*
X1067716Y28007D03*
X1091141D03*
X1083116Y13200D03*
X1070976D03*
X1050984Y54842D03*
X1047637Y35942D03*
Y46907D03*
X1057677Y35942D03*
Y46907D03*
X1057676Y87392D03*
X1050983Y92757D03*
X1047637Y84599D03*
X1035000Y81200D03*
X1057677Y73742D03*
X1047637D03*
X1061024Y54857D03*
X1067716Y54842D03*
Y35942D03*
Y46907D03*
Y65807D03*
X1091141Y54842D03*
Y35942D03*
X1084450Y54857D03*
X1081102Y35942D03*
X1074409D03*
X1077757Y54857D03*
X1081102Y46907D03*
X1074409D03*
X1091141D03*
Y65807D03*
X1067716Y89964D03*
Y84599D03*
X1081102D03*
X1091141Y87392D03*
Y92657D03*
X1077755Y92757D03*
X1074409Y84714D03*
X1084448Y92757D03*
X1061023Y89964D03*
X1067716Y73742D03*
X1074409D03*
X1081102D03*
X1091141D03*
X1050983Y105800D03*
X1057734Y105750D03*
X1077304Y105800D03*
X1071111D03*
X1064428D03*
X1057314Y209109D03*
X1035765Y214960D03*
X1042524D03*
X1042506Y195041D03*
X1045904Y197359D03*
X1054000Y199100D03*
X1035765Y207159D03*
X1042524Y203260D03*
X1049284Y214960D03*
Y203260D03*
X1072202Y216196D03*
X1065242Y208397D03*
X1068822Y214247D03*
X1065242Y212296D03*
Y204496D03*
X1071072Y199583D03*
X1095861Y218147D03*
X1089101Y214247D03*
Y210346D03*
X1092481Y216196D03*
X1095861Y206446D03*
X1091351Y199841D03*
X1075582Y206446D03*
Y218147D03*
X1082341D03*
X1078962Y216196D03*
X1078961Y212296D03*
X1082341Y214247D03*
X1085721Y212296D03*
Y216196D03*
X1084591Y198931D03*
X1042524Y226660D03*
X1039145Y232509D03*
X1035765Y226660D03*
X1057314Y240309D03*
X1049284Y226660D03*
X1045904Y232509D03*
X1057314D03*
X1095861Y229847D03*
X1068822Y233746D03*
X1065242Y235696D03*
Y223996D03*
X1068822Y237647D03*
Y249347D03*
X1065242Y247396D03*
X1068822Y241547D03*
X1072202Y243496D03*
Y251296D03*
X1092481Y223996D03*
Y231797D03*
X1089101Y233746D03*
Y237647D03*
X1095861D03*
Y245447D03*
X1078962Y251296D03*
X1082341Y245447D03*
Y249347D03*
X1078962Y247396D03*
X1092481Y243496D03*
X1075582Y245447D03*
X1085721Y251296D03*
X1075582Y249347D03*
X1085721Y243496D03*
X1089101Y241547D03*
X1085721Y223996D03*
X1075582Y229847D03*
X1082341D03*
X1078962Y227896D03*
Y220096D03*
Y223996D03*
X1085721Y231797D03*
X1082341Y237647D03*
X1075582D03*
X1072202Y231797D03*
Y223996D03*
X1089101Y253247D03*
X1092481Y255196D03*
X1095861Y257147D03*
X1049284Y370959D03*
X1035765D03*
X1042524D03*
X1045904Y365109D03*
X1039145D03*
X1052664D03*
X1042524Y359260D03*
X1049284Y351460D03*
X1045904Y353409D03*
X1035765Y351460D03*
Y359260D03*
X1039145Y353409D03*
X1042524Y351460D03*
X1054914Y347000D03*
X1052664Y392410D03*
X1040265Y394359D03*
X1049284Y382660D03*
X1035765D03*
X1042524D03*
Y390460D03*
X1056176Y402471D03*
X1041395Y402800D03*
X1060694Y351460D03*
X1086841Y358547D03*
X1094731Y346546D03*
X1086841Y354647D03*
X1090221Y352696D03*
X1091351Y348497D03*
X1073322Y354647D03*
X1076702Y356596D03*
X1080082Y354647D03*
X1083462Y368296D03*
X1076702Y372197D03*
Y368296D03*
X1073322Y362447D03*
X1086841D03*
X1090221Y372197D03*
Y364396D03*
X1093601Y366347D03*
X1090221Y368296D03*
X1076702Y360496D03*
X1083462D03*
Y352696D03*
X1076702D03*
X1093601Y358547D03*
X1090221Y379996D03*
X1073323Y401449D03*
X1078962Y399496D03*
X1093601Y401447D03*
X1073322Y374146D03*
X1086841D03*
X1073323Y397548D03*
X1073322Y385847D03*
X1080082Y393647D03*
X1083462Y391696D03*
X1080082Y385847D03*
X1083462Y376096D03*
X1080082Y378047D03*
X1083462Y379996D03*
X1076702Y376096D03*
X1090221Y395595D03*
X1086841Y389747D03*
X1093601Y393647D03*
X1090221Y391696D03*
X1093601Y385847D03*
X1086841D03*
X1093601Y397546D03*
Y378047D03*
X1086841Y381947D03*
X1093601Y405347D03*
X1077832Y407800D03*
X1047637Y509999D03*
X1057676Y512792D03*
X1035000Y521556D03*
X1050983Y518157D03*
X1067716Y509999D03*
X1074409Y510114D03*
X1061023Y515364D03*
X1091141Y518057D03*
X1077755Y518157D03*
X1081102Y509999D03*
X1084448Y518157D03*
X1082800Y497650D03*
X1091141Y512792D03*
X1067716Y515364D03*
X1057677Y547907D03*
Y536942D03*
X1047637Y547907D03*
Y536942D03*
X1057677Y574742D03*
X1047637D03*
X1050984Y555842D03*
X1074409Y547907D03*
X1081102D03*
X1091141D03*
Y529007D03*
Y536942D03*
X1074409D03*
X1081102D03*
X1067716D03*
Y529007D03*
X1061024Y555857D03*
X1077757D03*
X1084450D03*
X1091141Y555842D03*
X1067716D03*
X1081102Y574742D03*
X1091141D03*
X1067716D03*
Y566807D03*
X1091141D03*
X1074409Y574742D03*
X1057792Y589800D03*
X1070242D03*
X1083108D03*
X1119453Y-9864D03*
X1097352Y-7180D03*
X1104141Y-7851D03*
X1110520Y-7700D03*
X1114340Y-1801D03*
X1107874Y-1751D03*
X1101181Y-1801D03*
X1107724Y9114D03*
X1101181D03*
X1114340Y9098D03*
X1114400Y28100D03*
X1110520Y14814D03*
X1104177Y14714D03*
X1098500Y17000D03*
X1114300Y16900D03*
X1119400Y9300D03*
X1119453Y27936D03*
X1119440Y17114D03*
X1097900Y13700D03*
Y31900D03*
X1110520Y30100D03*
X1097834Y28100D03*
X1104141Y29949D03*
X1156300Y-2000D03*
X1151152Y-1801D03*
X1131299Y9114D03*
X1124606D03*
X1151152Y9098D03*
X1137992Y9114D03*
X1144535D03*
X1127952Y-7851D03*
X1124606Y-1751D03*
X1131299D03*
X1134645Y-7851D03*
X1156265Y-9864D03*
X1151200Y-9700D03*
X1147331Y-7700D03*
X1140952Y-7851D03*
X1137992Y-1801D03*
X1144685Y-1751D03*
X1156212Y9300D03*
X1127952Y14814D03*
X1151211Y28100D03*
X1156252Y17114D03*
X1151112Y16900D03*
X1147331Y30100D03*
Y14814D03*
X1134645Y29949D03*
X1140952D03*
X1140988Y14714D03*
X1134645Y14814D03*
X1156265Y27936D03*
X1127952Y29949D03*
X1114340Y35999D03*
X1098235Y68090D03*
X1110520Y67900D03*
X1104141Y67749D03*
X1114366Y65950D03*
X1119440Y54914D03*
X1119400Y47100D03*
Y35800D03*
X1098100Y51000D03*
X1119453Y65736D03*
X1107874Y36049D03*
X1098022Y35761D03*
X1101181Y35999D03*
X1107724Y46914D03*
X1110520Y52614D03*
X1098581Y54883D03*
X1104177Y52514D03*
X1101181Y46900D03*
X1098125Y46975D03*
X1114300Y54700D03*
X1114340Y46898D03*
X1098259Y70896D03*
X1101181Y84714D03*
X1098218Y85296D03*
X1114340Y73799D03*
X1107874Y73849D03*
X1101181Y73799D03*
X1098207Y73589D03*
X1110520Y90314D03*
X1114340Y84698D03*
X1114316Y92500D03*
X1107724Y84714D03*
X1119440Y92714D03*
X1119416Y84700D03*
X1119466Y73550D03*
X1098300Y89900D03*
X1104177Y90314D03*
X1127952Y67749D03*
X1156211Y35800D03*
X1156200Y47000D03*
X1151152Y35999D03*
Y46898D03*
X1151100Y54700D03*
X1147331Y52614D03*
X1134645D03*
X1137992Y46914D03*
Y35999D03*
X1144535Y46914D03*
X1144685Y36049D03*
X1156252Y54914D03*
X1134645Y67749D03*
X1140952D03*
X1156265Y65736D03*
X1151178Y65950D03*
X1147331Y67900D03*
X1131299Y46914D03*
X1124606D03*
X1127952Y52614D03*
X1131299Y36049D03*
X1124606D03*
X1131299Y73849D03*
X1124606D03*
X1127952Y90414D03*
X1131299Y84714D03*
X1124606D03*
X1147331Y90414D03*
X1137992Y73799D03*
X1144535Y84714D03*
X1140988Y90314D03*
X1137992Y84714D03*
X1134645Y90414D03*
X1144685Y73849D03*
X1156252Y92714D03*
X1151128Y92500D03*
X1151152Y84698D03*
X1156228Y84700D03*
X1156278Y73550D03*
X1151152Y73799D03*
X1138242Y104314D03*
X1144685D03*
X1156278Y112865D03*
X1151152Y113114D03*
X1141038Y109564D03*
X1147331D03*
X1156265Y105051D03*
X1151178Y105265D03*
X1116141Y206446D03*
X1136420Y210346D03*
X1099241Y216196D03*
Y212296D03*
X1109381Y214247D03*
X1116141Y218147D03*
X1106001Y212296D03*
X1102621Y218147D03*
Y214247D03*
X1119521Y216196D03*
X1119520Y212296D03*
X1104871Y198050D03*
X1106001Y216196D03*
X1112761D03*
X1129660Y206447D03*
X1126280Y216196D03*
Y212296D03*
X1125300Y199900D03*
X1122900Y214247D03*
Y218147D03*
X1129660Y214247D03*
X1147950Y209900D03*
X1136420Y218147D03*
Y214247D03*
X1151060Y212296D03*
X1157820D03*
X1099241Y227896D03*
Y220096D03*
X1102621Y229847D03*
X1099241Y223996D03*
X1109381Y233746D03*
X1112761Y231797D03*
Y223996D03*
X1116141Y237647D03*
X1109381D03*
X1106001Y223996D03*
X1102621Y237647D03*
Y245447D03*
X1112761Y251296D03*
X1116141Y245447D03*
X1106001Y243496D03*
X1112761D03*
X1109381Y241547D03*
X1106001Y251296D03*
X1099241D03*
Y247396D03*
X1119521Y223996D03*
Y220096D03*
Y227896D03*
Y247396D03*
Y251296D03*
X1106001Y231797D03*
X1116141Y229847D03*
X1107561Y269038D03*
X1116141Y264947D03*
X1111631Y271300D03*
X1106001Y262996D03*
Y259096D03*
X1099241Y255196D03*
Y259096D03*
X1119521Y270796D03*
X1118391Y274997D03*
X1119521Y255196D03*
X1102621Y261047D03*
Y257147D03*
X1109381Y261047D03*
X1116141Y257147D03*
X1112761Y259096D03*
X1110648Y276899D03*
X1100200Y273300D03*
X1129660Y237647D03*
X1126280Y223996D03*
Y231797D03*
X1122900Y229847D03*
Y237647D03*
X1129660Y233746D03*
Y241547D03*
X1126280Y251296D03*
Y243496D03*
X1122900Y245447D03*
X1144300Y243496D03*
X1151060Y247396D03*
X1154440Y245447D03*
X1144300Y247396D03*
Y251296D03*
X1136420Y245447D03*
X1154440Y241547D03*
X1136420D03*
X1157820Y239596D03*
X1147680Y222047D03*
X1144300Y235696D03*
X1136420Y229847D03*
Y233746D03*
Y222047D03*
Y225947D03*
Y237647D03*
X1133040Y223996D03*
Y235696D03*
Y243496D03*
Y251296D03*
X1147680Y225947D03*
X1151060Y223996D03*
X1147680Y233746D03*
X1154440Y229847D03*
X1157820Y220096D03*
Y223996D03*
Y231797D03*
X1154440Y253247D03*
X1130780Y278596D03*
X1129660Y261047D03*
X1130780Y274696D03*
X1126280Y259096D03*
X1122900Y257147D03*
X1157820Y278596D03*
Y270796D03*
X1151060Y266896D03*
Y274696D03*
X1137540D03*
X1151060Y259096D03*
X1144300Y255196D03*
X1133040Y259096D03*
X1134160Y268847D03*
X1136420Y257147D03*
X1144300Y278596D03*
Y270796D03*
X1137540Y278596D03*
X1119521Y286396D03*
Y305896D03*
X1108251Y338746D03*
X1117261Y340996D03*
X1104871Y340697D03*
X1119521Y321496D03*
X1130780Y290296D03*
X1127400Y288347D03*
X1130780Y309797D03*
Y301996D03*
X1127400Y303947D03*
Y307847D03*
X1157820Y290296D03*
X1151060Y298096D03*
Y290296D03*
Y282496D03*
X1144300Y286396D03*
Y294196D03*
X1157820D03*
X1140920Y300047D03*
X1134160Y292247D03*
Y300047D03*
X1140920Y292247D03*
X1137540Y282496D03*
X1144300Y309797D03*
X1137540D03*
X1147680Y303947D03*
X1154440Y307847D03*
X1130780Y313696D03*
X1157820D03*
X1124021Y340996D03*
Y337096D03*
X1127400Y327347D03*
X1157820Y337096D03*
Y333196D03*
X1134160Y323446D03*
X1151060Y340996D03*
Y333196D03*
X1154440Y319547D03*
X1157820Y317596D03*
X1137540D03*
X1157820Y329296D03*
X1147680Y327347D03*
X1154440Y335147D03*
X1144300Y340996D03*
Y337096D03*
X1140920Y339047D03*
Y331247D03*
X1154440Y323446D03*
Y315647D03*
X1147680Y319547D03*
X1157820Y325396D03*
X1154440Y339047D03*
Y331247D03*
X1127400Y319547D03*
Y315647D03*
X1100361Y350747D03*
X1113881D03*
Y358547D03*
X1117261Y348796D03*
X1100361Y358547D03*
X1103741Y348796D03*
Y352696D03*
X1110501D03*
X1107121Y346847D03*
Y354647D03*
Y358547D03*
Y362447D03*
X1103741Y372197D03*
X1110501Y364396D03*
X1103741D03*
X1113881Y366347D03*
X1117261Y372197D03*
Y368296D03*
X1110501Y372197D03*
X1096981Y368296D03*
Y372197D03*
X1100361Y366347D03*
X1113881Y401447D03*
X1110501Y391696D03*
Y395595D03*
X1107121Y389747D03*
X1100361Y385847D03*
X1107121D03*
X1100361Y393647D03*
X1103741Y391696D03*
X1100361Y397547D03*
X1113881Y385847D03*
Y397546D03*
Y393647D03*
X1103741Y379996D03*
X1113881Y378047D03*
X1117261Y376096D03*
X1110501Y379996D03*
X1107121Y381947D03*
X1096981Y376096D03*
X1100361Y378047D03*
X1151060Y368296D03*
X1147680Y366347D03*
X1120641Y350747D03*
Y358547D03*
Y366347D03*
X1127400Y362447D03*
X1124021Y348796D03*
Y352696D03*
X1127400Y354647D03*
Y358547D03*
X1130780Y360496D03*
X1127400Y342947D03*
X1134160Y346847D03*
Y362447D03*
Y366347D03*
Y370247D03*
X1147680Y342947D03*
X1151060Y356596D03*
Y360496D03*
X1144300D03*
X1137540D03*
X1144300Y356596D03*
X1140920Y358547D03*
X1147680Y346847D03*
Y350747D03*
X1151060Y352696D03*
Y348796D03*
X1147680Y358547D03*
X1157820Y360496D03*
X1154440Y358547D03*
Y342947D03*
Y354647D03*
X1157820Y352696D03*
X1147680Y354647D03*
X1144300Y348796D03*
X1140920Y346847D03*
Y350747D03*
X1144300Y344896D03*
X1151060D03*
X1154440Y346847D03*
X1140920Y362447D03*
X1154440Y366347D03*
X1144300Y372197D03*
X1137540D03*
Y368296D03*
X1140920Y366347D03*
Y370247D03*
X1151060Y364396D03*
X1144300D03*
X1137540D03*
X1147680Y362447D03*
X1130780Y352696D03*
Y344896D03*
X1124021Y372197D03*
X1130780D03*
X1124021Y364396D03*
X1137540Y403396D03*
Y399496D03*
X1124021Y391696D03*
X1130780Y395596D03*
X1127400Y385847D03*
Y389747D03*
X1130780Y391696D03*
X1124021Y379996D03*
X1127400Y381947D03*
X1130780Y379996D03*
X1137540Y395597D03*
X1140920Y397546D03*
X1137540Y376096D03*
X1157820Y387796D03*
X1140920Y378047D03*
Y381947D03*
X1147680Y393647D03*
X1120641Y385847D03*
Y393647D03*
Y378047D03*
Y401447D03*
X1140920Y374146D03*
X1151060Y395597D03*
Y391696D03*
X1147680Y385847D03*
Y397546D03*
X1151060Y379996D03*
X1154440Y378047D03*
Y381947D03*
X1140920Y389747D03*
X1134160Y393647D03*
Y385847D03*
Y378047D03*
X1140920Y385847D03*
X1144300Y391696D03*
X1117261Y407296D03*
X1113881Y405347D03*
X1096699Y407782D03*
X1134160Y405347D03*
X1119440Y518114D03*
X1114316Y517900D03*
X1114340Y510098D03*
X1110520Y515714D03*
X1097343Y512794D03*
X1104177Y515714D03*
X1101181Y510114D03*
X1098300Y515300D03*
X1107724Y510114D03*
X1137992Y495887D03*
X1144385D03*
X1140988Y493744D03*
X1156252Y490867D03*
X1147331Y493494D03*
X1151168Y490867D03*
X1127952Y515814D03*
X1124606Y510114D03*
X1131299D03*
X1156252Y518114D03*
X1147331Y515814D03*
X1151128Y517900D03*
X1156252Y498867D03*
X1151168D03*
X1151152Y510098D03*
X1134645Y515814D03*
X1137992Y510114D03*
X1140988Y515714D03*
X1144535Y510114D03*
X1156228Y510100D03*
X1104141Y530949D03*
X1098040Y536723D03*
X1098160Y533809D03*
X1119416Y547900D03*
X1119466Y536750D03*
X1119453Y528936D03*
X1098300Y553100D03*
X1114340Y547898D03*
X1107724Y547914D03*
X1101181D03*
X1110520Y553514D03*
X1104177D03*
X1098118Y549843D03*
X1098018Y531156D03*
X1114366Y529150D03*
X1114340Y536999D03*
X1110520Y531100D03*
X1107874Y537049D03*
X1101181Y536999D03*
X1119440Y555914D03*
X1114316Y555700D03*
X1119416Y585700D03*
X1119466Y574550D03*
X1119453Y566736D03*
X1104141Y568749D03*
X1097899Y574773D03*
X1101181Y585714D03*
X1097834Y569200D03*
X1107724Y585714D03*
X1107874Y574849D03*
X1110520Y568900D03*
X1101181Y574799D03*
X1114340D03*
Y585698D03*
X1114366Y566950D03*
X1140988Y553514D03*
X1151152Y547898D03*
X1156228Y547900D03*
X1137992Y547914D03*
X1144535D03*
X1127952Y553614D03*
X1131299Y547914D03*
X1124606D03*
X1131299Y537049D03*
X1124606D03*
X1127952Y530949D03*
X1151178Y529150D03*
X1151152Y536999D03*
X1147331Y531100D03*
X1156278Y536750D03*
X1156265Y528936D03*
X1134645Y530949D03*
X1140952D03*
X1137992Y536999D03*
X1144685Y537049D03*
X1147331Y553614D03*
X1134645D03*
X1156252Y555914D03*
X1151128Y555700D03*
X1156265Y566736D03*
X1151178Y566950D03*
X1134645Y568749D03*
X1137992Y585714D03*
X1144535D03*
X1140952Y568749D03*
X1137992Y574799D03*
X1144685Y574849D03*
X1151152Y585698D03*
Y574799D03*
X1147331Y568900D03*
X1156228Y585700D03*
X1156278Y574550D03*
X1131299Y585714D03*
X1124606D03*
X1131299Y574849D03*
X1127952Y568749D03*
X1124606Y574849D03*
X1137992Y612599D03*
X1144685Y612649D03*
X1151152Y612599D03*
X1124606Y612649D03*
X1131299D03*
X1114340Y612599D03*
X1107874Y612649D03*
X1101181Y612599D03*
X1097352Y607220D03*
X1110520Y606700D03*
X1119453Y604536D03*
X1119466Y612350D03*
X1119440Y593714D03*
X1104177Y591314D03*
X1110520D03*
X1114316Y593500D03*
X1098300Y590900D03*
X1114366Y604750D03*
X1104141Y606549D03*
X1156265Y604536D03*
X1147331Y606700D03*
X1134645Y606549D03*
X1140952D03*
X1156278Y612350D03*
X1134645Y591414D03*
X1140988Y591314D03*
X1151128Y593500D03*
X1147331Y591414D03*
X1156252Y593714D03*
X1151178Y604750D03*
X1127952Y606549D03*
Y591414D03*
X1161417Y9114D03*
X1168110D03*
X1174803D03*
X1171456Y-7851D03*
X1164763D03*
X1177763D03*
X1168110Y-1751D03*
X1161417D03*
X1174803Y-1801D03*
X1171456Y14814D03*
X1164763Y29949D03*
X1171456D03*
X1164763Y14814D03*
X1177799Y14714D03*
X1177763Y29949D03*
X1181496Y-1751D03*
X1181346Y9114D03*
X1187963Y9098D03*
X1204921Y9114D03*
X1198228D03*
X1188011Y-9700D03*
X1193076Y-9864D03*
X1184142Y-7700D03*
X1193111Y-2000D03*
X1187963Y-1801D03*
X1201574Y-7851D03*
X1204921Y-1751D03*
X1198228D03*
X1218307D03*
X1211614Y-1801D03*
X1214574Y-7851D03*
X1208267D03*
X1218157Y9114D03*
X1211614D03*
X1193023Y9300D03*
X1184142Y30100D03*
Y14814D03*
X1188023Y28100D03*
X1187923Y16900D03*
X1193063Y17114D03*
X1193076Y27936D03*
X1201574Y14814D03*
Y29949D03*
X1208267Y14814D03*
Y29949D03*
X1214600Y14714D03*
X1214574Y29949D03*
X1161417Y36049D03*
X1164763Y52614D03*
X1168110Y36049D03*
Y46914D03*
X1161417D03*
X1174803D03*
X1171456Y52614D03*
X1174803Y35999D03*
X1177763Y67749D03*
X1171456D03*
X1164763D03*
X1177799Y90314D03*
X1174803Y84714D03*
X1168110D03*
Y73849D03*
X1161417D03*
X1174803Y73799D03*
X1161417Y84714D03*
X1164763Y90414D03*
X1171456D03*
X1181346Y46914D03*
X1181496Y36049D03*
X1184142Y52614D03*
X1193012Y47000D03*
X1187963Y46898D03*
Y35999D03*
X1187912Y54700D03*
X1187989Y65950D03*
X1193076Y65736D03*
X1193063Y54914D03*
X1193023Y35800D03*
X1204921Y36049D03*
X1198228D03*
Y46914D03*
X1204921D03*
X1201574Y52614D03*
X1184142Y67900D03*
X1201574Y67749D03*
X1218307Y36049D03*
X1211614Y35999D03*
X1214960Y52864D03*
X1211614Y46914D03*
X1218157D03*
X1208267Y52614D03*
X1211614Y73799D03*
X1218307Y73849D03*
X1208267Y90414D03*
X1218157Y84714D03*
X1211614D03*
X1214574Y67749D03*
X1208267D03*
X1181346Y84714D03*
X1181496Y73849D03*
X1184142Y90414D03*
X1193039Y84700D03*
X1193063Y92714D03*
X1187939Y92500D03*
X1187963Y84698D03*
Y73799D03*
X1193089Y73550D03*
X1198228Y73849D03*
X1204921D03*
X1198228Y84714D03*
X1204921D03*
X1201574Y90414D03*
X1177799Y109914D03*
X1161632Y104314D03*
X1170721Y109564D03*
X1164428D03*
X1168075Y104314D03*
X1174742D03*
X1208267Y110014D03*
X1181346Y104314D03*
X1187963Y113114D03*
X1193089Y112865D03*
X1184142Y109564D03*
X1193076Y105051D03*
X1187989Y105265D03*
X1201574Y110014D03*
X1198228Y104314D03*
X1204921D03*
X1161200Y206446D03*
X1167960Y206447D03*
Y218147D03*
X1171339Y208397D03*
X1174719Y218147D03*
Y206447D03*
X1178099Y208397D03*
Y216196D03*
X1161200Y210346D03*
Y218147D03*
X1181479Y206447D03*
X1188239Y210346D03*
Y206447D03*
X1201759Y218147D03*
X1205759Y206682D03*
X1197492Y201356D03*
X1198379Y212296D03*
X1194999Y210346D03*
X1184859Y204496D03*
X1188239Y214247D03*
X1164580Y235696D03*
X1167960Y229847D03*
X1164580Y223996D03*
Y227896D03*
Y239596D03*
X1178099Y247396D03*
X1161200Y241547D03*
X1164580Y247396D03*
X1161200Y249347D03*
X1171339Y247396D03*
X1178099Y243496D03*
X1171339Y235696D03*
Y220096D03*
Y231797D03*
X1178099Y227896D03*
Y235696D03*
Y220096D03*
X1174719Y237647D03*
X1167960Y253247D03*
X1174719D03*
X1164580Y270796D03*
X1171339Y274696D03*
X1174719Y280547D03*
X1171339Y266896D03*
X1164580Y278596D03*
X1159578Y265117D03*
X1171339Y259096D03*
X1178099Y274696D03*
X1181479Y222047D03*
X1188239D03*
X1191619Y239596D03*
X1188239Y225947D03*
X1184859Y235696D03*
X1188239Y237647D03*
X1184859Y247396D03*
X1188239Y249347D03*
X1201759Y229847D03*
Y225947D03*
Y233746D03*
X1198379Y235696D03*
Y243496D03*
X1201759Y241547D03*
Y249347D03*
X1198379Y239596D03*
X1194999Y225947D03*
Y222047D03*
Y233746D03*
X1184859Y239596D03*
Y251296D03*
X1212199D03*
Y243496D03*
X1208519Y233746D03*
X1215700Y223600D03*
X1194999Y264947D03*
Y268847D03*
Y272747D03*
Y280547D03*
X1188239Y257147D03*
X1208519Y272747D03*
X1208819Y280547D03*
X1181479Y261047D03*
Y268847D03*
Y276646D03*
X1212199Y274696D03*
X1217200Y270500D03*
X1213808Y264800D03*
X1208519Y264947D03*
X1184859Y259096D03*
X1191619Y274696D03*
X1205139D03*
X1198379Y278596D03*
X1201759Y261047D03*
X1198379Y255196D03*
X1201759Y257147D03*
X1174719Y300047D03*
Y284447D03*
X1164580Y294196D03*
Y290296D03*
Y286396D03*
X1161200Y284447D03*
X1178099Y294196D03*
Y298096D03*
Y286396D03*
X1164580Y301996D03*
X1171339D03*
X1161200Y307847D03*
Y335147D03*
Y339047D03*
X1164580Y329296D03*
Y333196D03*
Y337096D03*
X1167960Y339047D03*
Y327347D03*
X1161200Y331247D03*
Y327347D03*
X1178099Y337096D03*
Y317596D03*
X1164580Y321496D03*
Y317596D03*
X1161200Y323446D03*
Y319547D03*
Y315647D03*
X1167960Y323446D03*
Y315647D03*
Y319547D03*
X1174719Y315647D03*
X1171339Y317596D03*
X1164580Y325396D03*
X1171339D03*
X1174719Y335147D03*
X1205500Y309797D03*
X1198379D03*
X1194999Y288347D03*
Y292247D03*
Y296147D03*
Y300047D03*
Y307847D03*
Y303947D03*
X1191619Y298096D03*
X1181479Y300047D03*
Y288347D03*
Y292247D03*
Y311747D03*
Y307847D03*
Y303947D03*
X1188239Y288347D03*
Y284447D03*
Y292247D03*
X1184859Y294196D03*
Y290296D03*
X1191619Y294196D03*
X1184859Y309797D03*
X1188239Y311747D03*
X1184859Y301996D03*
X1201759Y284447D03*
Y288347D03*
X1205439Y298096D03*
X1198379Y286396D03*
X1205439Y305896D03*
X1194999Y335147D03*
Y331247D03*
X1212200Y333196D03*
X1208519Y339047D03*
X1208826Y319544D03*
X1181479Y327347D03*
Y319547D03*
Y335147D03*
X1198379Y313696D03*
X1188239Y319547D03*
X1184859Y321496D03*
X1188239Y339047D03*
Y335147D03*
X1184859Y329296D03*
X1191619Y321496D03*
X1198379Y325396D03*
Y340996D03*
X1201759Y323446D03*
X1205139Y333196D03*
X1194999Y319547D03*
Y315647D03*
X1167960Y370247D03*
X1164580Y372197D03*
X1171339Y356596D03*
Y360496D03*
X1164580Y356596D03*
X1167960Y342947D03*
X1171339Y348796D03*
X1174719Y354647D03*
Y342947D03*
X1161200Y370247D03*
X1171339Y372197D03*
X1167960Y362447D03*
X1178099Y364396D03*
X1171339Y399496D03*
X1164580Y403396D03*
X1178099D03*
X1167960Y389747D03*
X1161200Y397546D03*
X1167960Y397547D03*
X1174719Y393647D03*
X1161200Y378047D03*
X1164580Y379996D03*
X1174719Y381947D03*
X1194999Y346847D03*
Y354647D03*
X1209219Y370247D03*
X1212199Y356597D03*
Y344896D03*
Y352696D03*
X1181479Y346847D03*
X1188239Y366347D03*
X1194999D03*
X1191619Y348796D03*
X1184859Y356596D03*
X1191619Y360496D03*
X1201759Y350747D03*
X1205139Y360496D03*
X1181479Y374146D03*
Y389747D03*
X1209769Y374146D03*
X1184859Y383896D03*
X1188239Y393647D03*
X1201759Y389747D03*
X1197258Y397546D03*
X1194999Y385847D03*
X1188239Y378047D03*
X1201759D03*
X1208819Y393647D03*
Y381897D03*
X1195555Y405773D03*
X1192200Y409550D03*
X1185989Y407800D03*
X1180400Y495787D03*
X1167500Y495800D03*
X1174203Y495787D03*
X1161320Y495800D03*
X1170656Y491144D03*
X1164363Y491044D03*
X1177849Y490944D03*
X1168110Y510114D03*
X1164763Y515814D03*
X1161417Y510114D03*
X1177799Y515714D03*
X1171456Y515814D03*
X1174803Y510114D03*
X1208267Y493444D03*
X1200974Y490744D03*
X1193063Y490909D03*
X1187978Y490609D03*
X1184142Y490794D03*
X1181346Y510114D03*
X1204400Y495887D03*
X1198100Y495800D03*
X1208267Y515814D03*
X1211614Y510114D03*
X1218157D03*
X1187963Y510098D03*
X1204921Y510114D03*
X1198228D03*
X1201574Y515814D03*
X1184142D03*
X1187939Y517900D03*
X1193039Y510100D03*
X1193063Y518114D03*
X1187978Y498609D03*
X1193063Y498909D03*
X1161417Y547914D03*
X1168110D03*
X1174803D03*
X1177799Y553514D03*
X1177763Y530949D03*
X1168110Y537049D03*
X1164763Y530949D03*
X1161417Y537049D03*
X1171456Y530949D03*
X1174803Y536999D03*
X1164763Y553614D03*
X1171456D03*
X1174803Y574799D03*
X1161417Y574849D03*
X1171456Y568749D03*
X1168110Y585714D03*
X1161417D03*
X1168110Y574849D03*
X1164763Y568749D03*
X1174803Y585714D03*
X1177763Y568749D03*
X1181496Y537049D03*
X1181346Y547914D03*
X1211614Y536999D03*
X1214574Y530949D03*
X1184142Y531100D03*
X1193076Y528936D03*
X1198228Y547914D03*
X1204921D03*
X1201574Y553614D03*
Y530949D03*
X1204921Y537049D03*
X1198228D03*
X1193039Y547900D03*
X1187963Y547898D03*
X1184142Y553614D03*
X1193089Y536750D03*
X1187989Y529150D03*
X1187963Y536999D03*
X1218307Y537049D03*
X1211614Y547914D03*
X1208267Y553614D03*
Y530949D03*
X1218157Y547914D03*
X1181346Y585714D03*
X1181496Y574849D03*
X1193063Y555914D03*
X1187939Y555700D03*
X1218157Y585714D03*
X1218307Y574849D03*
X1208267Y568749D03*
X1214574D03*
X1211614Y574799D03*
Y585714D03*
X1184142Y568900D03*
X1187989Y566950D03*
X1193076Y566736D03*
X1193039Y585700D03*
X1187963Y585698D03*
X1193089Y574550D03*
X1187963Y574799D03*
X1198228Y585714D03*
Y574849D03*
X1204921Y585714D03*
Y574849D03*
X1201574Y568749D03*
X1181496Y612649D03*
X1218307D03*
X1211614Y612599D03*
X1187963D03*
X1204921Y612649D03*
X1198228D03*
X1168110D03*
X1161417D03*
X1174803Y612599D03*
X1171456Y606549D03*
X1164763D03*
Y591414D03*
X1171456D03*
X1177799Y591314D03*
X1177763Y606549D03*
X1208267Y591414D03*
X1214574Y606549D03*
X1208267D03*
X1187939Y593500D03*
X1184142Y591414D03*
X1193063Y593714D03*
X1187989Y604750D03*
X1193076Y604536D03*
X1193089Y612350D03*
X1184142Y606700D03*
X1201574Y591414D03*
Y606549D03*
X1238385Y29949D03*
Y14814D03*
X1245078Y29949D03*
Y14814D03*
X1251771Y16999D03*
X1248425Y27899D03*
X1269700Y13078D03*
X1267960Y28494D03*
X1241732Y-1751D03*
X1238385Y-7851D03*
X1241732Y9114D03*
X1248425Y-1751D03*
Y-9901D03*
X1251771D03*
X1245078Y-7851D03*
X1248425Y9157D03*
X1269800Y-5822D03*
X1235039Y9114D03*
X1224774Y9098D03*
X1224822Y-9700D03*
X1229887Y-9864D03*
X1224774Y-1801D03*
X1235039Y-1751D03*
X1229922Y-2000D03*
X1220953Y-7700D03*
X1229800Y9300D03*
X1224790Y16900D03*
X1229874Y17114D03*
X1229887Y27936D03*
X1220953Y30100D03*
X1224800Y28100D03*
X1220953Y14814D03*
X1241732Y36049D03*
Y46914D03*
X1238385Y52614D03*
Y67749D03*
X1245078Y52614D03*
X1251771Y65699D03*
X1248425D03*
Y36049D03*
Y46957D03*
X1245078Y67749D03*
X1267976Y73676D03*
X1268022Y54443D03*
X1241732Y84714D03*
Y73849D03*
X1238385Y90414D03*
X1251771Y92599D03*
X1245078Y90414D03*
X1248425Y84757D03*
Y73849D03*
X1268581Y92706D03*
X1224774Y84698D03*
X1224750Y92500D03*
X1224774Y73799D03*
X1235039Y84714D03*
Y73849D03*
X1229800Y35750D03*
X1229874Y54914D03*
X1235039Y46914D03*
Y36049D03*
X1224774Y46898D03*
X1220953Y52614D03*
X1224774Y35999D03*
X1229887Y65736D03*
X1224800Y65950D03*
X1220953Y67900D03*
X1229900Y73550D03*
X1229850Y84700D03*
X1229874Y92714D03*
X1220953Y90414D03*
X1240927Y154932D03*
X1266200Y122500D03*
X1254024Y128013D03*
X1246251Y130066D03*
X1257800Y110900D03*
X1260500Y117500D03*
X1247326Y122802D03*
X1254300Y105200D03*
X1277660Y109450D03*
X1277230Y117570D03*
X1237400Y103100D03*
X1241712Y187710D03*
X1220167Y194407D03*
X1220017Y220323D03*
X1220194Y243384D03*
X1223100Y258600D03*
X1223508Y262600D03*
X1259800Y463300D03*
X1255530Y474770D03*
X1269050Y486650D03*
X1269600Y480800D03*
X1272830Y471660D03*
X1257720Y493060D03*
X1255388Y483557D03*
X1256130Y467820D03*
X1241732Y510114D03*
X1238385Y515814D03*
X1269000Y514700D03*
X1245078Y515814D03*
X1251771Y517999D03*
X1248425Y510157D03*
X1235039Y510114D03*
X1220953Y515814D03*
X1229874Y518114D03*
X1229850Y510100D03*
X1224750Y517900D03*
X1224774Y510098D03*
X1241732Y547914D03*
Y537049D03*
X1238385Y530949D03*
Y553614D03*
X1269800Y532978D03*
X1251771Y528899D03*
X1248425Y537049D03*
Y528899D03*
X1245078Y553614D03*
Y530949D03*
X1248425Y547957D03*
X1241732Y574849D03*
Y585714D03*
X1238385Y568749D03*
X1268500Y555800D03*
X1267900Y574300D03*
X1248425Y585757D03*
Y574849D03*
Y566699D03*
X1245078Y568749D03*
X1220953Y531100D03*
X1229887Y528936D03*
X1229900Y536750D03*
X1224800Y529150D03*
X1224774Y536999D03*
X1235039Y537049D03*
Y547914D03*
X1229850Y547900D03*
X1224774Y547898D03*
X1220953Y553614D03*
X1229874Y555914D03*
X1224750Y555700D03*
X1220953Y568900D03*
X1229900Y574550D03*
X1224774Y574799D03*
X1229850Y585700D03*
X1224774Y585698D03*
X1229887Y566736D03*
X1224800Y566950D03*
X1235039Y585714D03*
Y574849D03*
X1241732Y612649D03*
X1238385Y606549D03*
Y591414D03*
X1263800Y606800D03*
X1267800Y593600D03*
X1248425Y612649D03*
X1251771Y604499D03*
X1248425D03*
X1245078Y606549D03*
X1251771Y593599D03*
X1245078Y591414D03*
X1224774Y612599D03*
X1235039Y612649D03*
X1220953Y591414D03*
X1229874Y593714D03*
X1224750Y593500D03*
X1224800Y604750D03*
X1229887Y604536D03*
X1220953Y606700D03*
X1229900Y612350D03*
X1304940Y32350D03*
X1296928Y48700D03*
X1301000Y62000D03*
X1323500Y68000D03*
X1318341Y60000D03*
X1321841Y63000D03*
X1304000Y62000D03*
X1318341Y63000D03*
X1341400Y46100D03*
X1336900Y89896D03*
X1323500Y75000D03*
Y71500D03*
X1286000Y134500D03*
Y139500D03*
Y137000D03*
X1298400Y144500D03*
X1288500Y137000D03*
Y139500D03*
Y134500D03*
X1286000Y132000D03*
X1288500D03*
X1322628Y100134D03*
X1323800Y104250D03*
X1326800D03*
Y107250D03*
X1323800D03*
X1326600Y123450D03*
X1323600D03*
X1326600Y126450D03*
X1323600D03*
X1340100Y145000D03*
X1335100Y155000D03*
Y145000D03*
X1330100Y150000D03*
X1340100D03*
Y155000D03*
X1315100Y145000D03*
X1335100Y150000D03*
X1330100Y145000D03*
Y155000D03*
Y160000D03*
X1340100D03*
X1306363Y169928D03*
X1335100Y160000D03*
X1324938Y209251D03*
X1322500D03*
X1320390Y216824D03*
X1303838Y169922D03*
X1320400Y234959D03*
X1325900D03*
X1314900D03*
X1336900D03*
X1331400D03*
X1342400D03*
X1334113Y273115D03*
X1340866Y268795D03*
X1327625Y275971D03*
X1336480Y309755D03*
X1336793Y303784D03*
X1342500Y312100D03*
X1316300Y282000D03*
X1325300Y282600D03*
X1341920Y309755D03*
X1342480Y303852D03*
X1319906Y338025D03*
X1338500Y319600D03*
X1326626Y464400D03*
X1300100Y442500D03*
X1301000Y460900D03*
X1305100Y432500D03*
X1320100Y427500D03*
Y432500D03*
X1325100Y427500D03*
Y432500D03*
X1305181Y427834D03*
X1310100Y427500D03*
Y432500D03*
X1315100Y427500D03*
Y432500D03*
X1340100Y427500D03*
X1330100Y432500D03*
Y427500D03*
X1335100Y457500D03*
Y452500D03*
Y447500D03*
Y442500D03*
X1330100D03*
X1305100D03*
X1310100D03*
X1320100D03*
X1315100D03*
X1325100D03*
X1340100Y457500D03*
Y452500D03*
Y447500D03*
Y442500D03*
X1319738Y477497D03*
X1326877Y469279D03*
X1319699Y472327D03*
X1301000Y466500D03*
X1319300Y525450D03*
X1321800D03*
X1311772Y501000D03*
X1319075D03*
X1316675Y500983D03*
X1314272Y501000D03*
X1343100Y566300D03*
X1340700D03*
X1338000D03*
X1340526Y563337D03*
X1343026D03*
X1338026D03*
X1333026D03*
X1335526D03*
Y566237D03*
X1321800Y532750D03*
X1319300Y532650D03*
X1321800Y527850D03*
X1319300D03*
Y530250D03*
X1321800D03*
X1333026Y566237D03*
X1298100Y598300D03*
Y595800D03*
Y590000D03*
Y592500D03*
X1307600Y620100D03*
X1357400Y-19800D03*
X1360400Y10600D03*
X1350654Y-18411D03*
X1348154Y-15911D03*
Y-18411D03*
X1357600Y5140D03*
X1345518Y-18476D03*
X1353154Y-18411D03*
X1375676Y7630D03*
X1385608Y-17485D03*
X1388294Y-5675D03*
X1389523Y4966D03*
X1355950Y-16507D03*
X1359450Y-7D03*
X1355950D03*
X1357489Y-1924D03*
X1359450Y2493D03*
X1355950D03*
X1357489Y-14424D03*
Y-10524D03*
Y-6124D03*
X1355889Y-8524D03*
X1355847Y-12275D03*
X1355989Y-3924D03*
X1356261Y32017D03*
X1356300Y20100D03*
X1356376Y24167D03*
X1356200Y28200D03*
X1357900Y30200D03*
X1357800Y26100D03*
X1357803Y22200D03*
X1356261Y15517D03*
X1357700Y17800D03*
X1359761Y32317D03*
X1371650Y-907D03*
X1371589Y-3424D03*
Y-5924D03*
X1371900Y28600D03*
Y26100D03*
Y31100D03*
X1369408Y50479D03*
X1375500Y76000D03*
X1397500Y51000D03*
X1365855Y46972D03*
X1359800Y37300D03*
X1357300D03*
X1344000Y83000D03*
X1402700Y51100D03*
X1381817Y46484D03*
X1388627Y35032D03*
X1380500Y54500D03*
X1380900Y59820D03*
X1372400Y37785D03*
X1389138Y58499D03*
X1370100Y82500D03*
X1366100D03*
X1364700Y86550D03*
X1389068Y78556D03*
X1389100Y74600D03*
X1350830Y60730D03*
X1356261Y34517D03*
X1356950Y54370D03*
X1356760Y66660D03*
X1357000Y60500D03*
X1359761Y34817D03*
X1350800Y66600D03*
X1351190Y54710D03*
X1363170Y54280D03*
X1362900Y60500D03*
X1363040Y66660D03*
X1380500Y50500D03*
X1356230Y126500D03*
X1359230D03*
X1360730Y129000D03*
X1362230Y126500D03*
X1355100Y155000D03*
Y145000D03*
Y150000D03*
X1360100Y155000D03*
Y145000D03*
Y150000D03*
X1345100D03*
X1350100Y155000D03*
Y150000D03*
Y145000D03*
X1345100D03*
Y155000D03*
X1397994Y103350D03*
X1397952Y105998D03*
X1395326Y100913D03*
Y103413D03*
X1395347Y106040D03*
X1386700Y125450D03*
Y128450D03*
X1383700Y125450D03*
Y128450D03*
X1380700Y125450D03*
Y128450D03*
X1376100Y116100D03*
X1376669Y121763D03*
Y118763D03*
X1376100Y124950D03*
X1373850Y114450D03*
X1369730Y129000D03*
X1363730D03*
X1366730D03*
X1373850Y117450D03*
X1368230Y126500D03*
X1373850Y123450D03*
X1365230Y126500D03*
X1397193Y112602D03*
X1394253Y116989D03*
X1385100Y155000D03*
X1375100D03*
X1365100D03*
X1380100D03*
Y145000D03*
X1385100D03*
X1380100Y150000D03*
X1385100D03*
X1365100Y145000D03*
Y150000D03*
X1375100D03*
X1370100Y155000D03*
Y145000D03*
X1375100D03*
X1370100Y150000D03*
X1352200Y104950D03*
Y108400D03*
X1357700D03*
Y104950D03*
X1373850Y120450D03*
X1380100Y160000D03*
X1360100D03*
X1355100D03*
X1345100D03*
X1350100D03*
X1390100D03*
X1370100D03*
X1390100Y170000D03*
X1385100Y160000D03*
Y165000D03*
Y170000D03*
X1365100Y160000D03*
X1375100D03*
X1390100Y165000D03*
X1383753Y265548D03*
X1397400Y234959D03*
X1391900D03*
X1386400D03*
X1358900D03*
X1353400D03*
X1347900D03*
X1349500Y265500D03*
X1359100Y265600D03*
X1380900Y234959D03*
X1369900D03*
X1364400D03*
X1375400Y235100D03*
X1369100Y265500D03*
X1374864Y265629D03*
X1398062Y315743D03*
X1403100Y321350D03*
X1383639Y315274D03*
X1389600Y315200D03*
X1384024Y320225D03*
X1386048Y310310D03*
X1386265Y304310D03*
X1389600Y320100D03*
X1397640Y310631D03*
X1397880Y304640D03*
X1392380D03*
X1392340Y310625D03*
X1403260Y310623D03*
X1403300Y304640D03*
X1388208Y341489D03*
X1348080Y309825D03*
X1353142Y309761D03*
X1358792Y309760D03*
X1358800Y303700D03*
X1353359Y303767D03*
X1348190Y303810D03*
X1346550Y322350D03*
X1350650Y315050D03*
X1357452Y319395D03*
X1369540Y310125D03*
X1374900Y310130D03*
X1381100Y304360D03*
X1380910Y310300D03*
X1364044Y309691D03*
X1364213Y303694D03*
X1375040Y304135D03*
X1369540D03*
X1371000Y322400D03*
X1363059Y314514D03*
X1368947Y313993D03*
X1358500Y338400D03*
X1370200D03*
X1364300Y338300D03*
X1392144Y364617D03*
X1389450Y372250D03*
X1384700Y359700D03*
X1392500Y344600D03*
X1392805Y360466D03*
X1388500Y350864D03*
X1391200Y386300D03*
X1384531Y382957D03*
X1394760Y394720D03*
X1362510Y360717D03*
X1354024Y398985D03*
X1352338Y404153D03*
X1351379Y399227D03*
X1352239Y401593D03*
X1358512Y371792D03*
X1360450Y402100D03*
X1359360Y398810D03*
X1357880Y403760D03*
X1356560Y398910D03*
X1362250Y399160D03*
X1354681Y401444D03*
X1354982Y404154D03*
X1357542Y401381D03*
X1364856Y366666D03*
X1382017Y367584D03*
X1363250Y401700D03*
X1371200Y402100D03*
X1381500Y396200D03*
X1375201Y396303D03*
X1365731Y360698D03*
X1358500Y374500D03*
X1360200Y377400D03*
X1358655Y379352D03*
X1362068Y393385D03*
X1360300Y381100D03*
X1360200Y384700D03*
Y389000D03*
X1358700Y386700D03*
X1358568Y390885D03*
Y393385D03*
X1358600Y382800D03*
X1362068Y390885D03*
X1374268Y389985D03*
X1374207Y384968D03*
Y387468D03*
X1370300Y350200D03*
X1358300Y344200D03*
X1358400Y350100D03*
X1370200Y343900D03*
X1364100Y350200D03*
X1385416Y410502D03*
X1404558Y416575D03*
X1402725Y408136D03*
X1402520Y413246D03*
X1388085Y410479D03*
X1403998Y429775D03*
X1404558Y421575D03*
X1398275Y453561D03*
X1397975Y457561D03*
X1403998Y434775D03*
X1382849Y410471D03*
X1380449Y410479D03*
X1358990Y411040D03*
X1358910Y408480D03*
X1358980Y406060D03*
X1355100Y427500D03*
Y432500D03*
X1361558Y410527D03*
X1345100Y442500D03*
X1350100D03*
X1345100Y437500D03*
X1350100D03*
X1355100D03*
Y442500D03*
X1369034Y458075D03*
X1369907Y410513D03*
X1372535Y410512D03*
X1375239Y410590D03*
X1377928Y410451D03*
X1366984Y410481D03*
X1364403Y410496D03*
X1380100Y447500D03*
X1370100Y442500D03*
X1365100Y452500D03*
X1379857Y458108D03*
X1365100Y442500D03*
X1375100D03*
X1380100Y452500D03*
X1365100Y447500D03*
X1388900Y525230D03*
X1395581Y525357D03*
X1383600Y482504D03*
X1386041Y493723D03*
X1383519Y487445D03*
X1390330Y516690D03*
X1385033Y516848D03*
X1387568Y516892D03*
X1388865Y519788D03*
X1388850Y522266D03*
X1386033Y498811D03*
X1344073Y508263D03*
X1363800Y481600D03*
X1363662Y486636D03*
X1365741Y492723D03*
X1382578Y516805D03*
X1377492Y516892D03*
X1369757Y517465D03*
X1365719Y497545D03*
X1352490Y515470D03*
X1346870Y515450D03*
X1352590Y519170D03*
X1346970Y519150D03*
X1401777Y557632D03*
X1385033Y544267D03*
X1390623Y574986D03*
X1400830Y564090D03*
X1400288Y570099D03*
X1404420Y576330D03*
X1404519Y560280D03*
Y557380D03*
X1361600Y559400D03*
X1358529Y537492D03*
X1361163Y540052D03*
X1358518Y540073D03*
X1356018D03*
X1356029Y537492D03*
X1363674Y537471D03*
X1355548Y559959D03*
X1361926Y584037D03*
Y586537D03*
X1359100Y586200D03*
X1357400Y588400D03*
X1360100D03*
X1344613Y556376D03*
Y561376D03*
Y558876D03*
X1347700Y554100D03*
X1353520Y537480D03*
X1344613Y553876D03*
X1361174Y537471D03*
X1358439Y559959D03*
X1375479Y540117D03*
X1375500Y537717D03*
X1366265Y537437D03*
X1363663Y540052D03*
X1363568Y550589D03*
X1380521Y535276D03*
X1378021D03*
X1375621Y535254D03*
X1371265Y537437D03*
X1368765D03*
X1366459Y550589D03*
X1377979Y537717D03*
Y540117D03*
X1380479Y537717D03*
X1368596Y539889D03*
X1371096D03*
X1366096D03*
X1380479Y540117D03*
X1376800Y584328D03*
X1364426Y586637D03*
Y584137D03*
X1360500Y570900D03*
Y574700D03*
X1360261Y578873D03*
X1360247Y567390D03*
X1360261Y562373D03*
Y581373D03*
X1362000Y576700D03*
Y572800D03*
X1362100Y569100D03*
X1362000Y565600D03*
X1363761Y581373D03*
X1375961Y577973D03*
X1376000Y575456D03*
Y572956D03*
X1387050Y615350D03*
X1392500Y592000D03*
X1376556Y615756D03*
X1357726Y591037D03*
X1360226D03*
X1363761Y612573D03*
X1360261D03*
X1360200Y597800D03*
X1361600Y599900D03*
X1361500Y595700D03*
X1360100Y610100D03*
X1360200Y606300D03*
Y602000D03*
X1361900Y608200D03*
X1361500Y604200D03*
X1360261Y593573D03*
X1363761Y610073D03*
X1375961Y609173D03*
X1375900Y604156D03*
Y606656D03*
X1454715Y2784D03*
X1450508Y2756D03*
X1410571Y13170D03*
X1420019Y13466D03*
X1448367Y13533D03*
X1438918D03*
X1429469Y13466D03*
X1457814D03*
X1436131Y5248D03*
X1432661Y5220D03*
X1406674Y46120D03*
X1411254Y46018D03*
X1412250Y65359D03*
X1407150Y58859D03*
X1410150D03*
X1407150Y52859D03*
X1410150D03*
X1409250Y65359D03*
X1407150Y55859D03*
X1410150D03*
X1413721Y36749D03*
X1412250Y68359D03*
X1409250D03*
X1409150Y71259D03*
X1412150D03*
X1442067Y34830D03*
X1423170Y36635D03*
X1432619Y34830D03*
X1451516D03*
X1460965D03*
X1452648Y103788D03*
X1451273Y148905D03*
X1449847Y202322D03*
X1439000Y208500D03*
X1442251Y180818D03*
X1418300Y199900D03*
X1440150Y175550D03*
X1440124Y166180D03*
X1451427Y167818D03*
X1434800Y248900D03*
X1462700Y221700D03*
X1464200Y231400D03*
X1458800Y254882D03*
X1410800Y316100D03*
X1408580Y310632D03*
X1408760Y304637D03*
X1410550Y320800D03*
X1419343Y310652D03*
X1419283Y304570D03*
X1413983Y304645D03*
X1413943Y310628D03*
X1417656Y367547D03*
X1420101Y396236D03*
X1418138Y386361D03*
X1415000Y399000D03*
X1412220Y388360D03*
X1417217Y379129D03*
X1417349Y382137D03*
X1417773Y374107D03*
X1464124Y353776D03*
X1465500Y395400D03*
X1456750Y381850D03*
X1459033Y395334D03*
X1446700Y387900D03*
X1437897Y402315D03*
X1443100Y368950D03*
X1439934Y403730D03*
X1411900Y429775D03*
X1405375Y453561D03*
X1405608Y456761D03*
X1411900Y434775D03*
X1435479Y423107D03*
X1439350Y406900D03*
X1459200Y459800D03*
Y454100D03*
X1459000Y449997D03*
X1451400Y454100D03*
Y459800D03*
X1445000Y437000D03*
X1429000Y437059D03*
X1444800Y442500D03*
X1444500Y448000D03*
X1429100Y453400D03*
X1429000Y448000D03*
Y442600D03*
X1448800Y427800D03*
X1412447Y416368D03*
X1412545Y421974D03*
X1413300Y454400D03*
X1413075Y457561D03*
X1448800Y416500D03*
X1464300Y404900D03*
X1439000Y423000D03*
X1464600Y428000D03*
X1459300Y430000D03*
X1464525Y420014D03*
X1464731Y432942D03*
X1445100Y431500D03*
X1459200Y465500D03*
X1451400D03*
X1408753Y527518D03*
X1415541Y489523D03*
X1416100Y483500D03*
X1415800Y477500D03*
Y495200D03*
X1420200Y520500D03*
X1447749Y485395D03*
X1439314Y477723D03*
X1439400Y483600D03*
X1439341Y489323D03*
X1453700Y501600D03*
X1458357Y523271D03*
X1461100Y523600D03*
X1439400Y494700D03*
X1409693Y560343D03*
X1412093D03*
X1410850Y564210D03*
X1410340Y570370D03*
X1407019Y557380D03*
X1412019D03*
X1409519D03*
X1406993Y560343D03*
X1447852Y575687D03*
X1445800Y574300D03*
X1445750Y539000D03*
X1461500Y540000D03*
X1439861Y540497D03*
X1461653Y580762D03*
X1461707Y583162D03*
X1461878Y585556D03*
X1441805Y570887D03*
X1443797Y572482D03*
X1422500Y579800D03*
X1414800D03*
X1461930Y587956D03*
X1409500Y538000D03*
X1420500Y549800D03*
X1420400Y538000D03*
X1462039Y590354D03*
X1462155Y592761D03*
X1465334Y618564D03*
X1451314Y623298D03*
X1458000Y623400D03*
X1455000D03*
X1461000D03*
X1442200D03*
X1445200D03*
X1448200D03*
X1463419Y606912D03*
X1527700Y6963D03*
X1506900Y3500D03*
X1469807Y2967D03*
X1473674Y2953D03*
X1476712Y13466D03*
X1467264Y13533D03*
X1492900Y4000D03*
X1489600D03*
X1495611Y13466D03*
X1486162Y13500D03*
X1470414Y34830D03*
X1479863D03*
X1497711Y34427D03*
X1489311Y34830D03*
X1499613Y84046D03*
X1515294Y91306D03*
X1523563Y93565D03*
X1511700Y84600D03*
X1482300Y118400D03*
X1469747Y148276D03*
X1483093Y130796D03*
X1523950Y104050D03*
X1523889Y99033D03*
X1523557Y116165D03*
X1523813Y120546D03*
X1523756Y108762D03*
X1501603Y108500D03*
X1499618Y124520D03*
X1497699Y112140D03*
X1511634Y121195D03*
X1511635Y114535D03*
X1511650Y109400D03*
Y103400D03*
X1511651Y98675D03*
X1500775Y98101D03*
X1501700Y103300D03*
X1513023Y140630D03*
X1511664Y133603D03*
X1488350Y149450D03*
X1523719Y149488D03*
X1499800Y199300D03*
X1491196Y218527D03*
X1523400Y217900D03*
X1483523Y181100D03*
X1517328Y186208D03*
X1527500Y167726D03*
X1502192Y164871D03*
X1494783Y177907D03*
X1469150Y242931D03*
X1479500Y238500D03*
X1498685Y224715D03*
X1491700Y241661D03*
X1491407Y258353D03*
X1523470Y242580D03*
X1472500Y341074D03*
X1526722Y295400D03*
X1501583Y339389D03*
X1521817Y330937D03*
X1526000Y341000D03*
X1517600Y320940D03*
X1487426Y330100D03*
X1514722Y293257D03*
X1515482Y280800D03*
X1512300Y280847D03*
X1511900Y287500D03*
X1472550Y397500D03*
X1470800Y402250D03*
X1472680Y380630D03*
X1483172Y351806D03*
X1474500Y365500D03*
X1478500D03*
X1483500D03*
X1482000Y395098D03*
Y399035D03*
Y383287D03*
Y387224D03*
X1473255Y376254D03*
X1528146Y349842D03*
X1519626Y365817D03*
X1488394Y365466D03*
X1497275Y401174D03*
X1508975D03*
X1483950Y401650D03*
X1491425Y391034D03*
X1503125Y377514D03*
X1491425D03*
X1526525D03*
X1514825D03*
X1526525Y384274D03*
Y391034D03*
X1514825Y384274D03*
X1520675Y387654D03*
Y380894D03*
X1514825Y391034D03*
X1508975Y387654D03*
Y380894D03*
X1503125Y384274D03*
Y391034D03*
X1497275Y380894D03*
X1491425Y384274D03*
X1497275Y387654D03*
Y394414D03*
X1491425Y397794D03*
X1503125D03*
X1508975Y394414D03*
X1514825Y397794D03*
X1524575Y401174D03*
X1491425Y418074D03*
X1487525D03*
X1472449Y439421D03*
X1467000Y454100D03*
Y459800D03*
X1466800Y449997D03*
X1467401Y411557D03*
X1471900Y406900D03*
X1472530Y432731D03*
X1472400Y428063D03*
X1472800Y420689D03*
X1467000Y465500D03*
X1482000Y418720D03*
Y406909D03*
Y410846D03*
Y414783D03*
Y422658D03*
Y426595D03*
X1483400Y438100D03*
X1482603Y442418D03*
X1482000Y462028D03*
X1483115Y454379D03*
X1483200Y450455D03*
X1482500Y434600D03*
X1503125Y404554D03*
X1509200Y413600D03*
X1510925Y404554D03*
X1497275Y414694D03*
X1503125Y424834D03*
X1497275Y428214D03*
X1495325Y424834D03*
X1503125Y433406D03*
X1491425D03*
X1495325D03*
X1524950Y419900D03*
X1518650D03*
X1483818Y430597D03*
X1528100Y410550D03*
X1501219Y416596D03*
X1487525Y404554D03*
X1526525D03*
X1515500Y416750D03*
X1518700Y406500D03*
X1491425Y404554D03*
X1495325Y411314D03*
X1512350Y445100D03*
X1509200D03*
Y454550D03*
X1512400Y454500D03*
X1503125Y440166D03*
X1501175Y436786D03*
X1495325Y440166D03*
X1497275Y436786D03*
X1510925Y460446D03*
X1505442Y443900D03*
X1507025Y460446D03*
X1503125Y453786D03*
Y460446D03*
X1501175Y457066D03*
X1487525Y453686D03*
X1497275Y457066D03*
Y450306D03*
X1495325Y446926D03*
Y453686D03*
X1497275Y443546D03*
X1501175Y463826D03*
X1493375D03*
X1515500Y445100D03*
X1514825Y460446D03*
X1520675Y457066D03*
X1518725Y460446D03*
X1521800Y441950D03*
Y448250D03*
X1526525Y460446D03*
X1522625D03*
X1524950Y441950D03*
X1473140Y525407D03*
X1482000Y481713D03*
Y469902D03*
X1476800Y498900D03*
X1482300D03*
X1476800Y507300D03*
X1481700Y524200D03*
X1473800Y495800D03*
X1499225Y480726D03*
X1508975Y477346D03*
X1510925Y480726D03*
X1508975Y470586D03*
X1510925Y473966D03*
X1505075Y470586D03*
X1501175D03*
X1503125Y467206D03*
X1507025Y487486D03*
X1487525Y473966D03*
X1491425D03*
X1489475Y470586D03*
X1490100Y489700D03*
X1487525Y487486D03*
X1489475Y484106D03*
X1516775D03*
X1514825Y480726D03*
Y473966D03*
X1516775Y470586D03*
X1518725Y487486D03*
Y480726D03*
Y473966D03*
Y467206D03*
X1522625D03*
Y473966D03*
Y487486D03*
X1526525D03*
Y473966D03*
Y467206D03*
X1514825Y487486D03*
X1511752Y498780D03*
X1490929Y507104D03*
X1506060Y508180D03*
X1501490Y504988D03*
X1501934Y513047D03*
X1505743Y516117D03*
X1511215Y507781D03*
X1512400Y519020D03*
X1493930Y522800D03*
X1488410Y517810D03*
X1497267Y505323D03*
X1496174Y514221D03*
X1509000Y498750D03*
X1488500Y498900D03*
X1526500Y498671D03*
Y506400D03*
X1485300Y498962D03*
X1483804Y509928D03*
X1484200Y524200D03*
X1475316Y527194D03*
X1468101Y573963D03*
X1527698Y578870D03*
X1474776Y572315D03*
X1491776Y573571D03*
X1479893Y572315D03*
X1482293D03*
X1477493D03*
X1487093D03*
X1489493D03*
X1484693D03*
X1518000Y562330D03*
X1510740Y557860D03*
X1494422Y574000D03*
X1481400Y539700D03*
X1494200Y530600D03*
X1497106Y531368D03*
X1511388Y531045D03*
X1503200Y530500D03*
X1505600D03*
X1508772Y530416D03*
X1514118Y530411D03*
X1483900Y539700D03*
X1525500Y582674D03*
Y580184D03*
X1525837Y574700D03*
X1523416Y573949D03*
X1527822Y576130D03*
X1525500Y577684D03*
X1499900Y574000D03*
X1496900D03*
X1469701Y599554D03*
X1470353Y592128D03*
X1469767Y596353D03*
X1503008Y620018D03*
X1472412Y596032D03*
Y599532D03*
X1479029Y596132D03*
X1477129Y597656D03*
X1474912Y596032D03*
X1480760Y611602D03*
X1485429Y597571D03*
X1491412Y596032D03*
X1489229Y597571D03*
X1487329Y596032D03*
X1512500Y598639D03*
X1510450Y597300D03*
X1507950D03*
X1510450Y600800D03*
X1508031Y599922D03*
X1524800Y598778D03*
X1522900Y597300D03*
X1526950D03*
X1518800Y597200D03*
X1520813Y598508D03*
X1516800Y598639D03*
X1514500Y597300D03*
X1511350Y613000D03*
X1513867Y612939D03*
X1516367D03*
X1475812Y611732D03*
X1474912Y599532D03*
X1478329Y611671D03*
X1483104Y596072D03*
X1481229Y597571D03*
X1584447Y-6702D03*
X1579447D03*
X1570200Y12900D03*
X1579773Y13257D03*
X1589259Y10241D03*
X1541400Y12500D03*
X1528384Y28040D03*
X1551309Y12792D03*
X1560700Y13000D03*
X1589500Y-600D03*
X1589900Y84422D03*
X1583621Y87213D03*
X1588700Y94288D03*
X1573473Y37216D03*
X1582923D03*
X1532800Y78590D03*
X1542179Y39695D03*
X1554573Y37216D03*
X1564023D03*
X1578000Y113000D03*
X1585500Y101000D03*
X1555000Y139000D03*
X1548955Y101358D03*
X1558189Y107067D03*
X1554800Y129100D03*
Y98200D03*
X1558100D03*
X1558383Y121500D03*
X1554945Y133400D03*
X1583600Y207495D03*
X1535399Y190920D03*
X1533132Y158068D03*
X1531565Y176645D03*
X1537298Y162703D03*
X1557634Y175948D03*
X1562079Y163580D03*
X1530200Y257200D03*
X1528460Y244371D03*
X1563440Y250955D03*
X1559577Y236300D03*
X1547000Y263500D03*
Y269400D03*
X1541000Y263500D03*
Y269500D03*
X1544000Y266500D03*
X1578630Y293430D03*
X1580150Y329483D03*
X1528250Y311900D03*
X1530033Y340799D03*
X1539400Y320200D03*
X1544904Y334008D03*
X1557250Y315410D03*
X1554800Y290600D03*
X1586400Y392900D03*
X1567475Y380894D03*
Y387654D03*
X1582420Y377830D03*
X1582350Y374567D03*
X1582124Y381164D03*
X1573000Y391161D03*
X1571366Y401154D03*
X1582000Y396250D03*
X1567475Y394414D03*
X1570672Y362134D03*
X1567121Y365817D03*
X1576380Y362890D03*
X1582500Y369600D03*
X1573521Y365500D03*
X1532375Y380894D03*
Y387654D03*
Y394414D03*
X1538225Y377514D03*
Y384274D03*
X1544075Y380894D03*
Y387654D03*
X1538225Y391034D03*
Y397794D03*
X1544075Y394414D03*
X1558996Y365817D03*
X1555775Y394414D03*
X1549925Y397794D03*
X1561625D03*
X1555775Y401174D03*
X1549925Y377514D03*
X1561625D03*
Y391034D03*
Y384274D03*
X1549925Y391034D03*
Y384274D03*
X1555775Y387654D03*
Y380894D03*
X1571375Y421454D03*
X1569425Y418074D03*
X1571375Y414694D03*
X1559675Y463826D03*
X1563575Y421454D03*
X1557725Y424834D03*
X1567475Y450306D03*
X1565525Y440166D03*
X1571375Y457066D03*
X1567475D03*
X1569425Y460446D03*
X1582200Y456200D03*
X1565525Y431594D03*
X1569425D03*
Y404554D03*
X1583208Y412815D03*
X1569425Y411314D03*
X1571390Y464480D03*
X1567475Y421454D03*
X1531250Y419900D03*
Y451400D03*
Y441950D03*
X1530425Y460446D03*
X1551875Y407934D03*
Y414694D03*
X1563575Y407934D03*
X1559675Y414694D03*
X1546025Y404554D03*
X1561625Y424834D03*
X1551990Y421158D03*
X1551875Y428214D03*
X1561625Y431594D03*
X1563575Y428214D03*
X1555775Y443546D03*
Y436786D03*
X1563575Y457066D03*
X1549938Y453714D03*
X1547975Y457066D03*
X1549925Y446926D03*
X1557725D03*
X1561625Y460446D03*
X1555775Y457066D03*
X1551875D03*
X1557725Y453686D03*
X1559675Y443546D03*
Y436786D03*
X1547975Y463826D03*
X1551875D03*
X1555775D03*
X1534400Y419900D03*
X1540700D03*
X1543850Y429350D03*
Y426200D03*
X1537550Y419900D03*
X1534325Y404554D03*
X1538225D03*
X1542125D03*
X1540700Y410450D03*
X1534400Y451400D03*
Y441950D03*
X1537550D03*
X1534325Y460446D03*
X1537550Y451400D03*
X1544075Y457066D03*
X1540175D03*
X1540700Y451400D03*
Y441950D03*
X1540175Y463826D03*
X1543850Y435650D03*
X1537550D03*
X1582644Y495077D03*
X1568600Y494500D03*
X1565210Y509160D03*
X1567817Y499735D03*
X1569425Y473966D03*
X1571375Y470586D03*
X1565525Y480726D03*
X1570062Y487039D03*
X1587970Y472370D03*
X1587433Y490425D03*
X1567475Y470586D03*
X1532375D03*
X1530425Y473966D03*
X1528475Y470586D03*
Y477346D03*
X1534180Y498580D03*
X1534039Y502906D03*
X1531580Y510790D03*
X1534325Y487486D03*
X1536275Y484106D03*
X1544075Y470586D03*
X1542125Y473966D03*
X1540175Y477346D03*
X1536275Y470586D03*
X1544075Y477346D03*
X1538225Y473966D03*
X1542475Y504400D03*
X1542425Y512200D03*
X1546025Y467206D03*
X1553825Y487486D03*
Y480726D03*
X1557725D03*
X1549925Y473966D03*
X1547975Y470586D03*
X1553825Y473966D03*
Y467206D03*
X1555775Y470586D03*
X1557725Y473966D03*
X1555775Y477346D03*
Y484106D03*
X1549925Y487486D03*
X1546025Y480726D03*
X1548300Y499000D03*
X1564600Y500414D03*
X1555424Y504609D03*
X1555832Y512288D03*
X1548300Y506600D03*
X1580360Y565524D03*
X1580400Y568000D03*
X1580300Y563000D03*
Y560500D03*
X1566000Y575820D03*
X1565940Y573120D03*
X1565800Y570600D03*
X1565600Y568100D03*
Y565700D03*
X1529944Y574725D03*
X1529894Y577342D03*
X1532354Y577283D03*
X1532642Y579853D03*
X1529600Y582300D03*
X1532400D03*
X1529942Y579853D03*
X1563800Y564100D03*
X1561300Y564000D03*
X1558800Y563900D03*
X1563448Y566766D03*
X1563432Y569340D03*
X1589604Y585896D03*
X1581704D03*
X1587504Y605496D03*
Y607996D03*
X1563827Y621376D03*
X1554800Y620910D03*
X1537711Y613397D03*
X1538679Y615641D03*
X1534928Y610532D03*
X1538337Y601097D03*
X1534948Y613302D03*
X1545000Y591100D03*
X1581704Y590196D03*
X1589604D03*
X1558800Y599300D03*
X1560400Y611600D03*
X1564300Y599400D03*
X1564400Y605500D03*
X1561700Y602200D03*
X1552400Y607600D03*
X1554900Y607100D03*
X1556200Y602400D03*
X1554400Y599300D03*
X1564300Y611500D03*
X1602504Y-17346D03*
X1646200Y5300D03*
X1646400Y13400D03*
X1597700Y9000D03*
X1615000Y12000D03*
X1634200Y9700D03*
X1627500Y11700D03*
X1608123Y13302D03*
X1619100Y6500D03*
X1626400Y4600D03*
X1606700D03*
X1636500D03*
X1591270Y93940D03*
X1592200Y37700D03*
X1590464Y77962D03*
X1637700Y67400D03*
X1639623Y38100D03*
X1649073Y38200D03*
X1620050Y35550D03*
X1608500Y72688D03*
X1606730Y84230D03*
X1632000Y83000D03*
X1625451Y84288D03*
X1605184Y61044D03*
X1610450Y37300D03*
X1627380Y36652D03*
X1630121Y37609D03*
X1595943Y71522D03*
X1603138Y65890D03*
X1602840Y37382D03*
X1635900Y83000D03*
X1595335Y98135D03*
X1641600Y96500D03*
X1638500D03*
X1595522Y127278D03*
X1650300Y195251D03*
X1648400Y214100D03*
X1643887Y181841D03*
X1604401Y213500D03*
X1618500Y181680D03*
X1625524Y184531D03*
X1635100Y182800D03*
X1620036Y196186D03*
X1635112Y195181D03*
X1605250Y197250D03*
X1591174Y225017D03*
X1640871Y235210D03*
X1608489Y252095D03*
X1635503Y340146D03*
X1629503D03*
X1603307Y393224D03*
X1591912Y391052D03*
X1650624Y357884D03*
X1650480Y368215D03*
X1642126Y357894D03*
X1642114Y368142D03*
X1601060Y401010D03*
X1599100Y399100D03*
X1610828Y381387D03*
X1596151D03*
X1596168Y375135D03*
X1609761Y372584D03*
X1613474Y391105D03*
X1620447Y373926D03*
X1610642Y375135D03*
X1608020Y356500D03*
X1619889Y352841D03*
X1607443Y398649D03*
X1629503Y346146D03*
X1635503Y346046D03*
X1632503Y343146D03*
X1621010Y435870D03*
X1620500Y463727D03*
X1634500Y418500D03*
X1603650Y415469D03*
X1646540Y441240D03*
X1604200Y464387D03*
X1594880Y494880D03*
X1646700Y480300D03*
X1639394Y507798D03*
X1627032Y510226D03*
X1627068Y512626D03*
X1606200Y487100D03*
X1623814Y471400D03*
X1614000Y469500D03*
X1617700Y489700D03*
X1615200D03*
X1611506Y474768D03*
X1620500Y475000D03*
X1603500Y495300D03*
X1597178Y472226D03*
X1599900Y487100D03*
X1603802Y487205D03*
X1629530Y496374D03*
X1644800Y532800D03*
X1636848Y533794D03*
X1649900Y583500D03*
X1638674Y556178D03*
X1622040Y554827D03*
X1609829Y556599D03*
X1624293Y561747D03*
X1615030Y584260D03*
X1610080Y561367D03*
X1603060Y582920D03*
X1603120Y578020D03*
X1599170Y572780D03*
X1602000Y565700D03*
X1590004Y605496D03*
Y607996D03*
X1601504Y591526D03*
X1613721Y592325D03*
X1614700Y597000D03*
X1615862Y605507D03*
X1601489Y602812D03*
X1601270Y597200D03*
X1602150Y610720D03*
X1654800Y13518D03*
X1711863Y13276D03*
X1672427Y9700D03*
X1664200Y5400D03*
X1656600Y6300D03*
X1664823Y13287D03*
X1685500Y3000D03*
X1682985Y2901D03*
X1675800Y4100D03*
X1702421Y13231D03*
X1684902Y13472D03*
X1691541Y13226D03*
X1700710Y73292D03*
X1700300Y94703D03*
X1672000Y51500D03*
X1669350Y69962D03*
X1709600Y45800D03*
X1692573Y85833D03*
X1702513Y79885D03*
X1668009Y37000D03*
X1706500D03*
X1678000D03*
X1687500D03*
X1696795Y38260D03*
X1658559Y37890D03*
X1659038Y95111D03*
X1659000Y85500D03*
X1670250Y87873D03*
X1674455Y169991D03*
X1677605Y169986D03*
X1687950Y186150D03*
X1708250Y164950D03*
X1671556Y208379D03*
X1657498Y277300D03*
Y267100D03*
X1657949Y257240D03*
X1653091Y331618D03*
X1652991Y318741D03*
Y323941D03*
X1657500Y287800D03*
X1657600Y304500D03*
X1681192Y454286D03*
X1668000Y416200D03*
X1695658Y486945D03*
X1694410Y499830D03*
X1692120Y501410D03*
X1699900Y512300D03*
X1709400Y513000D03*
X1652500Y575600D03*
X1667277Y535221D03*
X1698600Y584800D03*
X1664113Y548380D03*
X1658466D03*
X1661880Y583900D03*
X1686036Y548251D03*
X1677300Y550200D03*
X1680007Y547917D03*
X1669121Y547923D03*
X1708140Y547538D03*
X1697839Y545759D03*
X1709183Y588700D03*
X1654100Y615790D03*
X1653970Y607340D03*
X1652700Y591300D03*
Y600850D03*
X1662580Y593200D03*
X1661200Y601300D03*
Y607300D03*
X1730550Y21160D03*
X1721559Y13500D03*
X1730768Y13313D03*
X1763100Y21500D03*
X1768807Y21512D03*
X1753903Y22116D03*
X1749941Y21163D03*
X1741000Y21200D03*
X1715259Y35602D03*
X1715100Y46100D03*
X1713550Y56000D03*
X1716900Y87900D03*
X1753059Y35300D03*
X1735150Y60650D03*
X1748500Y79500D03*
X1748854Y58533D03*
X1717600Y46100D03*
X1724758Y38600D03*
X1720600Y70200D03*
X1733910Y38233D03*
X1757054Y66059D03*
X1758100Y37000D03*
X1749364Y38971D03*
X1743500Y39300D03*
X1768450Y77376D03*
X1765900Y83700D03*
X1754703Y84053D03*
X1771459Y52695D03*
X1733900Y92200D03*
X1754600Y109200D03*
X1767250Y99500D03*
Y104500D03*
X1770850Y109500D03*
X1714189Y159550D03*
X1714528Y190189D03*
X1758650Y158650D03*
X1750189Y159550D03*
X1745689D03*
X1741189D03*
X1727689D03*
X1723189D03*
X1718689D03*
X1732189D03*
X1736689D03*
X1745777Y179574D03*
X1751975Y179374D03*
X1739377D03*
X1733178Y179574D03*
X1758375D03*
X1764673Y179374D03*
X1770973Y179574D03*
X1726700Y179400D03*
X1740900Y198800D03*
X1744000D03*
X1769100Y209700D03*
X1765950Y209600D03*
X1769016Y198872D03*
X1765866Y198772D03*
X1731260Y209600D03*
X1740709D03*
X1756000Y210000D03*
X1753400Y209900D03*
X1743900Y209700D03*
X1728616Y198872D03*
X1753311Y198700D03*
X1756600Y198800D03*
X1731216Y198872D03*
X1763554Y237712D03*
X1762795Y232106D03*
X1772244D03*
X1752554Y237712D03*
X1771451D03*
X1724944Y250324D03*
X1727444D03*
X1771243Y250100D03*
X1729944Y250324D03*
X1768516Y249983D03*
X1744603Y232489D03*
X1753347Y232106D03*
X1763300Y250100D03*
X1766100Y447900D03*
X1762992Y447938D03*
X1740963Y448476D03*
X1753543Y448100D03*
X1750393Y448037D03*
X1737795Y448100D03*
X1722000Y513000D03*
X1742900Y485000D03*
X1734000Y488100D03*
X1755000Y485000D03*
X1748600D03*
X1749396Y493969D03*
X1751868Y494045D03*
X1770325Y490255D03*
X1773500Y472100D03*
X1767300Y472700D03*
X1765325Y490255D03*
X1758500Y493800D03*
X1760900Y472800D03*
X1772459Y467005D03*
X1769309D03*
X1759860D03*
X1756710D03*
X1747262D03*
X1744112D03*
X1734663D03*
X1729200Y519000D03*
X1733830Y502650D03*
X1768900Y521124D03*
X1749090Y513790D03*
X1740400Y496300D03*
X1726600Y519000D03*
X1728700Y502600D03*
X1713600Y513000D03*
X1756417Y563840D03*
X1746000Y574000D03*
X1718000Y587723D03*
X1749000Y552863D03*
X1769000Y576378D03*
X1742381Y585530D03*
X1730814Y568814D03*
X1733000Y560000D03*
X1767455Y571695D03*
X1767000Y563500D03*
X1728245Y585244D03*
X1746052Y614796D03*
X1724092Y618700D03*
X1772158Y610960D03*
X1750739Y618718D03*
X1742509Y595869D03*
X1742381Y591530D03*
X1763500Y599100D03*
X1727843Y597142D03*
X1732443Y592342D03*
Y597142D03*
X1727743Y592342D03*
X1832449Y-8950D03*
X1785612Y10729D03*
X1782371Y26832D03*
X1804508Y11858D03*
X1798676Y11726D03*
X1830344Y13397D03*
X1828824Y3699D03*
X1816693Y13331D03*
X1819800Y35500D03*
X1790700Y34900D03*
X1799774Y34890D03*
X1808444Y37152D03*
X1800000Y80000D03*
X1827000Y87000D03*
X1834300Y41100D03*
X1788200Y93000D03*
Y89000D03*
Y85000D03*
X1818383Y133277D03*
X1788448Y98820D03*
X1788648Y101490D03*
X1807745Y104500D03*
X1803400Y114000D03*
X1796059Y104402D03*
X1801366Y151937D03*
X1811348Y143448D03*
X1800264Y143789D03*
X1800000Y132627D03*
X1820648Y155537D03*
X1816348D03*
X1777172Y179374D03*
X1778466Y198772D03*
X1783572Y179574D03*
X1802369Y179374D03*
X1808769Y179574D03*
X1815000Y179300D03*
X1789870Y179374D03*
X1796170Y179574D03*
X1795348Y172037D03*
X1797848D03*
X1792748Y171937D03*
X1821367Y179574D03*
X1827565Y179174D03*
X1833388Y179500D03*
X1791150Y209600D03*
X1794300Y209700D03*
X1794216Y198872D03*
X1791066Y198772D03*
X1819457Y198872D03*
X1828700Y198800D03*
X1820349Y209586D03*
X1828950Y209600D03*
X1832274Y209734D03*
X1816266Y198772D03*
X1804166Y198472D03*
X1807751Y209586D03*
X1803072Y209728D03*
X1806821Y198600D03*
X1815670Y209728D03*
X1781700Y209700D03*
X1778550Y209600D03*
X1781616Y198872D03*
X1816348Y163437D03*
X1818500Y159500D03*
X1820648Y163437D03*
X1782452Y237712D03*
X1820281Y250498D03*
X1809281D03*
X1801384D03*
X1790383D03*
X1791141Y232106D03*
X1828936Y249900D03*
X1819488Y232106D03*
X1810040D03*
X1800591D03*
X1781693D03*
X1775590Y448100D03*
X1778740D03*
X1828600Y450100D03*
X1825984Y448030D03*
X1816535Y448300D03*
X1813385Y447945D03*
X1804000Y447900D03*
X1800787Y447943D03*
X1791338Y448400D03*
X1788189Y448300D03*
X1779700Y472100D03*
X1784525Y491830D03*
X1781907Y467005D03*
X1785057D03*
X1779303Y497246D03*
X1832301Y467005D03*
X1835550Y466870D03*
X1789774Y476403D03*
X1801500Y471055D03*
X1795164Y476406D03*
X1789525Y491830D03*
X1801125D03*
X1796125D03*
X1817325Y481320D03*
X1806600Y471055D03*
X1812325Y481320D03*
X1806975Y491630D03*
X1830220Y479950D03*
X1824960Y473980D03*
X1824125Y491830D03*
X1822852Y467005D03*
X1819702D03*
X1819125Y491830D03*
X1807104Y467005D03*
X1810254D03*
X1811975Y491630D03*
X1797655Y467005D03*
X1794505D03*
X1810508Y515900D03*
X1804000Y498176D03*
X1834540Y519600D03*
X1796400Y498000D03*
X1781510Y546362D03*
X1786500Y562200D03*
X1783700Y579200D03*
X1828800Y546500D03*
X1828700Y540252D03*
X1828900Y552300D03*
X1834000Y534900D03*
X1811704Y554341D03*
X1807600Y552047D03*
X1806200Y549200D03*
X1786900Y552500D03*
X1801200Y529800D03*
X1806200Y582900D03*
X1810387Y571435D03*
X1794000Y568800D03*
X1793320Y557968D03*
X1828700Y569474D03*
X1836281Y589122D03*
X1828800Y575600D03*
X1828875Y563674D03*
X1828824Y557663D03*
X1810385Y568821D03*
X1807958Y565690D03*
X1812452Y538501D03*
Y533601D03*
X1807852D03*
X1807752Y538501D03*
X1779000Y598900D03*
X1787500Y597791D03*
X1825014Y593695D03*
X1811500Y603500D03*
X1808152Y591601D03*
X1812852Y596401D03*
X1808252D03*
X1812852Y591601D03*
X1893094Y-10142D03*
X1838100Y3900D03*
X1889218Y43530D03*
Y53530D03*
X1846800Y95400D03*
X1847000Y86500D03*
X1848000Y56500D03*
X1850500D03*
X1890803Y63189D03*
X1884500Y79300D03*
X1882000D03*
X1895330Y64390D03*
X1877270Y63473D03*
X1880230Y76820D03*
X1879500Y79300D03*
X1880986Y53299D03*
X1860995Y84509D03*
X1856873Y91200D03*
X1856778Y87397D03*
X1864208Y87724D03*
X1864195Y84509D03*
X1864153Y91241D03*
X1860815Y91184D03*
X1875100Y51300D03*
X1872340Y147236D03*
X1895800Y149200D03*
X1885400Y147000D03*
X1878550Y99470D03*
X1882550D03*
X1894834Y139286D03*
X1863908Y140992D03*
X1878950Y137400D03*
X1871855Y104188D03*
X1856700Y110167D03*
X1869000Y153900D03*
X1887830Y102227D03*
X1852600Y97500D03*
X1887300Y121500D03*
X1850700Y156000D03*
X1875700Y115700D03*
Y121500D03*
X1881500Y115700D03*
Y121500D03*
Y127300D03*
X1887300D03*
X1875700D03*
X1887300Y115700D03*
X1846663Y153748D03*
X1839500Y212700D03*
X1857044Y186292D03*
X1863750Y163750D03*
X1868375Y171900D03*
X1846163Y168448D03*
X1886800Y210600D03*
X1871708Y213442D03*
X1854663Y158248D03*
X1846663D03*
X1852300Y252000D03*
X1858400Y251200D03*
X1843700Y253400D03*
X1839400Y450440D03*
X1838768Y454120D03*
X1847185Y454368D03*
X1860158Y450322D03*
X1864300Y447900D03*
X1882677Y447930D03*
X1895275Y454422D03*
X1898425Y447930D03*
Y454422D03*
X1845330Y466870D03*
X1843000Y505000D03*
X1857480Y466800D03*
X1861300D03*
X1881285Y467049D03*
X1849795Y493379D03*
X1850290Y486610D03*
X1872908Y471338D03*
X1870138Y485732D03*
X1852340Y509140D03*
X1877518Y527560D03*
X1889800Y580200D03*
X1878000Y539000D03*
X1861080Y537090D03*
X1842500Y534500D03*
X1844100Y551000D03*
X1848900Y545500D03*
X1878450Y548650D03*
X1870250Y541950D03*
X1896500Y555300D03*
X1879800Y579000D03*
X1858000Y574000D03*
X1870892Y583245D03*
X1874825Y564125D03*
X1859167Y559350D03*
X1894299Y557790D03*
X1906438Y-15968D03*
X1909406Y76790D03*
X1907986Y82393D03*
X1907929Y84793D03*
X1907907Y87223D03*
X1918379Y84788D03*
X1905501Y79790D03*
X1902796Y79820D03*
X1900100Y145100D03*
X1921199Y140499D03*
X1929711Y155759D03*
X1904136Y140160D03*
X1937000Y150000D03*
X1906871Y106049D03*
X1911231Y137097D03*
X1908715Y104512D03*
X1912100Y142600D03*
X1915030Y147250D03*
X1911440Y128840D03*
X1952440Y98520D03*
X1942637Y100877D03*
X1914152Y115928D03*
X1950983Y147344D03*
X1928100Y136078D03*
X1953200Y195530D03*
X1937100Y206800D03*
X1908967Y201609D03*
X1909186Y211906D03*
X1944500Y183900D03*
X1903524Y208156D03*
X1905074Y198163D03*
X1943200Y214800D03*
X1928400Y212500D03*
X1926000Y212400D03*
X1933898Y216707D03*
X1945156Y160236D03*
X1950994Y173745D03*
X1939316Y173600D03*
X1900740Y178720D03*
X1900700Y172990D03*
Y167290D03*
X1906440Y178720D03*
X1906500Y173100D03*
X1906400Y167290D03*
X1912190Y178870D03*
X1912230Y167330D03*
Y173030D03*
X1946105Y230344D03*
X1902909Y223195D03*
X1943517Y223637D03*
X1943800Y241800D03*
X1943900Y238500D03*
X1934750Y242700D03*
Y240300D03*
X1925600Y242700D03*
X1929000Y445800D03*
X1910500Y435600D03*
X1927100Y436200D03*
X1930100D03*
X1904724Y454422D03*
X1901574Y447930D03*
X1907500Y435600D03*
X1911023Y448400D03*
X1907874Y454422D03*
Y448400D03*
X1933100Y436200D03*
X1957100Y502990D03*
X1955790Y499790D03*
X1947380Y482450D03*
X1915100Y480050D03*
X1905010Y479410D03*
X1939000Y479400D03*
X1952500Y508000D03*
X1959260Y506010D03*
X1938410Y490650D03*
X1929480Y472880D03*
X1905000Y533900D03*
X1906050Y569100D03*
X1923600Y554200D03*
X1955400Y530500D03*
X1923600Y572300D03*
X1908400Y556800D03*
X1915593Y576807D03*
X1953500Y551900D03*
X1943300Y535700D03*
X1921800Y586100D03*
X1936770Y607210D03*
X1906200Y607800D03*
X1916050Y604450D03*
X1924000Y611391D03*
X1968179Y77969D03*
X1965679D03*
Y75369D03*
X1968179D03*
X1965679Y82969D03*
Y80469D03*
X1968179D03*
X1966212Y72897D03*
X1970679Y75369D03*
Y80469D03*
Y77969D03*
X1962800Y143700D03*
X1971200Y152500D03*
X1965400Y149700D03*
X1961472Y165760D03*
X1967817Y201029D03*
X1965900Y184600D03*
X1965057Y176447D03*
X1966542Y179606D03*
X1965973Y166190D03*
X1970270Y474640D03*
X1968870Y481710D03*
X1970500Y502720D03*
X1963500Y521000D03*
X1961500Y561700D03*
Y582700D03*
X1972700Y552700D03*
G54D31*
X1887327Y532541D03*
X1929453Y511202D03*
G54D22*
G01X308166Y87394D02*
X306794D01*
G01X307592Y73800D02*
X306800D01*
G01X307950Y50729D02*
X306771D01*
G01X1098300Y515300D02*
X1100000D01*
X320784Y203219D03*
X330948Y201258D03*
X401377Y28022D03*
X411416D03*
X401377Y65822D03*
X411416D03*
X401377Y529022D03*
X411416D03*
X401377Y566822D03*
X411416D03*
X428149Y28022D03*
X434842Y28268D03*
X421456Y35957D03*
X434842Y65822D03*
X428149D03*
X458640Y200596D03*
X428149Y529022D03*
X434842D03*
X428149Y566822D03*
X434842D03*
X970392Y203219D03*
X980556Y201258D03*
X1050985Y28022D03*
X1061024D03*
X1077757D03*
X1084450Y28098D03*
X1050985Y65822D03*
X1071064Y35957D03*
X1061024Y65822D03*
X1084450D03*
X1077757D03*
X1050985Y529022D03*
Y566822D03*
X1061024Y529022D03*
X1084450D03*
X1077757D03*
X1067716Y547907D03*
X1071064Y574757D03*
X1061024Y566822D03*
X1084450D03*
X1077757D03*
X1108248Y200596D03*
X1111631Y198327D03*
X1451753Y276753D03*
X1454902Y279902D03*
X1445454Y270454D03*
X1448603Y273603D03*
X1454902Y305098D03*
X1448603Y311397D03*
X1458051Y301949D03*
X1464351Y295649D03*
Y289351D03*
X1458051Y283051D03*
X1489546Y270454D03*
X1486397Y273603D03*
X1483247Y276753D03*
X1470649Y295649D03*
Y289351D03*
X1480098Y305098D03*
X1476949Y301949D03*
X1486397Y311397D03*
X1489546Y314546D03*
X1483247Y308247D03*
X1476949Y283051D03*
X1606470Y93759D03*
X1638938Y109192D03*
X1638250Y125750D03*
X1651536Y121790D03*
X1638938Y118641D03*
X1645378Y128378D03*
X1638902Y112305D03*
X1648430Y150163D03*
X1638937Y131239D03*
Y143837D03*
Y137538D03*
X1638938Y153286D03*
X1616900Y153200D03*
X1629489Y150136D03*
X1616891Y146987D03*
X1616893Y140782D03*
X1635788Y137538D03*
Y143837D03*
Y131239D03*
X1616891Y134389D03*
X1629489Y137538D03*
Y143837D03*
Y131239D03*
X1620040Y106042D03*
X1623189Y118640D03*
X1629489D03*
X1610793Y109190D03*
X1607441Y118640D03*
X1616891Y124939D03*
X1596220Y109470D03*
X1613741Y115491D03*
X1602717Y102240D03*
X1620040Y162735D03*
X1627998Y172854D03*
X1601142Y172185D03*
X1674685Y134217D03*
X1693625Y133220D03*
X1680402Y128652D03*
X1678127Y117293D03*
X1673883Y124308D03*
X1654685Y146987D03*
X1654678Y137530D03*
X1657835Y134389D03*
X1671000Y103000D03*
X1709000Y127200D03*
X1691207Y139891D03*
X1667284Y137537D03*
X1657835Y124940D03*
Y150136D03*
X1667284Y121790D03*
Y128089D03*
Y150136D03*
X1664134Y140688D03*
X1668213Y172608D03*
X1729444Y123782D03*
X1726294Y101785D03*
X1742212Y117451D03*
X1717014Y108000D03*
Y139500D03*
X1739064Y108000D03*
X1742214Y101700D03*
X1745364Y114300D03*
X1755089Y150750D03*
X1752189Y136750D03*
X1752389Y132250D03*
X1754189Y124250D03*
X1757689Y123850D03*
X1752889Y146250D03*
X1745364Y145800D03*
X1731903Y133712D03*
X1720164Y97550D03*
Y111150D03*
X1723314D03*
Y117450D03*
X1720164Y120600D03*
Y133200D03*
Y126800D03*
X1751800Y141700D03*
X1742214Y98550D03*
Y126900D03*
X1745364Y120600D03*
X1742214Y111150D03*
X1739064Y114300D03*
G54D13*
X-15748Y101221D03*
Y148465D03*
Y357362D03*
Y373110D03*
Y388858D03*
Y404606D03*
X12205Y156339D03*
X-4331D03*
X17323Y101221D03*
Y116969D03*
Y132717D03*
Y148465D03*
X787Y101221D03*
Y116969D03*
Y148465D03*
X33858Y101221D03*
Y116969D03*
Y132717D03*
Y148465D03*
X28740Y109095D03*
Y156339D03*
X12205Y109095D03*
Y140591D03*
X-4331Y109095D03*
Y124843D03*
Y140591D03*
X17323Y357362D03*
Y373110D03*
Y388858D03*
Y404606D03*
X787Y357362D03*
Y373110D03*
Y388858D03*
Y404606D03*
X33858Y357362D03*
Y373110D03*
Y388858D03*
Y404606D03*
X28740Y365236D03*
Y380984D03*
Y396732D03*
X12205Y365236D03*
Y380984D03*
Y396732D03*
X-4331Y365236D03*
Y380984D03*
Y396732D03*
X12205Y412480D03*
X-4331D03*
X28740D03*
G54D40*
G01X-9569Y-9569D02*
X0Y0D01*
G01D02*
X9569Y9569D01*
G01X-9569D02*
X0Y0D01*
G01D02*
X9569Y-9569D01*
G01X1602685Y292308D02*
X1613069Y302692D01*
G01D02*
X1623453Y313076D01*
G01X1602685D02*
X1613069Y302692D01*
G01D02*
X1623453Y292308D01*
X1961890Y211043D03*
Y238405D03*
G54D41*
G01X105174Y102925D02*
X107249Y105000D01*
G01D02*
X109324Y107075D01*
G01X105174D02*
X107249Y105000D01*
G01D02*
X109324Y102925D01*
G01X1562041Y-17959D02*
X1565000Y-15000D01*
G01D02*
X1567959Y-12041D01*
G01X1562041D02*
X1565000Y-15000D01*
G01D02*
X1567959Y-17959D01*
G01X1816918Y615916D02*
X1819665Y618663D01*
G01D02*
X1822412Y621410D01*
G01X1816918D02*
X1819665Y618663D01*
G01D02*
X1822412Y615916D01*
G01X1893410Y19119D02*
X1895945Y21654D01*
G01X1893410Y24189D02*
X1895945Y21654D01*
G01X1891282Y490182D02*
X1894100Y493000D01*
G01D02*
X1896918Y495818D01*
G01X1891282D02*
X1894100Y493000D01*
G01D02*
X1896918Y490182D01*
G01X1848892Y558642D02*
X1851250Y561000D01*
G01D02*
X1853608Y563358D01*
G01X1848892D02*
X1851250Y561000D01*
G01D02*
X1853608Y558642D01*
G01X1848892Y574390D02*
X1851250Y576748D01*
G01D02*
X1853608Y579106D01*
G01X1848892D02*
X1851250Y576748D01*
G01D02*
X1853608Y574390D01*
G01X1888268Y599287D02*
X1891086Y602105D01*
G01D02*
X1893904Y604923D01*
G01X1888268D02*
X1891086Y602105D01*
G01D02*
X1893904Y599287D01*
G01X1919960Y516040D02*
X1922248Y518328D01*
G01D02*
X1924536Y520616D01*
G01X1919960D02*
X1922248Y518328D01*
G01D02*
X1924536Y516040D01*
G01X1950115Y603067D02*
X1952756Y605708D01*
G01D02*
X1955397Y608349D01*
G01X1950115D02*
X1952756Y605708D01*
G01D02*
X1955397Y603067D01*
G54D32*
X1851250Y576748D03*
Y561000D03*
G54D14*
X30500Y-42250D03*
Y-52250D03*
X12290Y264640D03*
X18450Y267010D03*
X22970Y244400D03*
X28720Y244450D03*
X17120Y244220D03*
X24200Y267060D03*
X50500Y-42250D03*
X70500D03*
X90500D03*
X110500D03*
X50500Y-52250D03*
X70500D03*
X90500D03*
X110500D03*
X130500Y-42250D03*
Y-52250D03*
X457246Y-52301D03*
Y-42301D03*
X477246Y-52301D03*
Y-42301D03*
X497246Y-52301D03*
Y-42301D03*
X517246Y-52301D03*
Y-42301D03*
X537246Y-52301D03*
Y-42301D03*
X557246Y-52301D03*
Y-42301D03*
X788984Y-52057D03*
Y-42057D03*
X808984Y-52057D03*
Y-42057D03*
X828984Y-52057D03*
Y-42057D03*
X848984Y-52057D03*
Y-42057D03*
X868984Y-52057D03*
Y-42057D03*
X888984Y-52057D03*
Y-42057D03*
X1125583Y-52285D03*
Y-42285D03*
X1145583Y-52285D03*
Y-42285D03*
X1382258Y-52257D03*
Y-42257D03*
X1402258Y-52257D03*
Y-42257D03*
X1422258Y-52257D03*
Y-42257D03*
X1442258Y-52257D03*
Y-42257D03*
G54D23*
X1392264Y23976D03*
X1513918D03*
G54D42*
G01X1887327Y508300D02*
Y511202D01*
G01D02*
Y514104D01*
G01X1883225Y511202D02*
X1887327D01*
G01D02*
X1891429D01*
G01X1887327Y529639D02*
Y532541D01*
G01D02*
Y535443D01*
G01X1881825Y532541D02*
X1887327D01*
G01D02*
X1892829D01*
G01X1929453Y508300D02*
Y511202D01*
G01D02*
Y514104D01*
G01X1923951Y511202D02*
X1929453D01*
G01D02*
X1934955D01*
G54D33*
X1952756Y-14960D03*
Y58268D03*
G54D15*
X18228Y178386D03*
X-1969D03*
X44291D03*
G54D24*
X1526871Y23968D03*
X1819665Y618663D03*
X1881595Y23968D03*
G54D43*
G01X548049Y-193422D02*
Y-210922D01*
G01X543027Y-193422D02*
X553071D01*
G01X565549Y-199256D02*
Y-210922D01*
G01Y-194589D02*
X565112Y-194297D01*
Y-193714D01*
X565549Y-193422D01*
X565986Y-193714D01*
Y-194297D01*
X565549Y-194589D01*
G01X583049Y-210922D02*
X581739Y-210630D01*
X580429Y-209464D01*
X579555Y-207422D01*
X579119Y-205089D01*
X579555Y-202755D01*
X580429Y-200714D01*
X581739Y-199547D01*
X583049Y-199256D01*
X584359Y-199547D01*
X585669Y-200714D01*
X586542Y-202755D01*
X586761Y-205089D01*
X586542Y-207422D01*
X585669Y-209464D01*
X584359Y-210630D01*
X583049Y-210922D01*
G01X597492Y-215297D02*
X599021Y-216464D01*
X600767Y-216755D01*
X602295Y-216464D01*
X603606Y-215006D01*
X604479Y-212964D01*
Y-199256D01*
G01Y-201589D02*
X603606Y-200422D01*
X602295Y-199547D01*
X600767Y-199256D01*
X599021Y-199839D01*
X597929Y-201005D01*
X597055Y-203047D01*
X596619Y-205089D01*
X596837Y-206839D01*
X597711Y-208881D01*
X599021Y-210339D01*
X600767Y-210922D01*
X602077Y-210630D01*
X603606Y-209464D01*
X604479Y-208298D01*
G01X621979Y-210922D02*
Y-199256D01*
G01Y-201297D02*
X621106Y-200131D01*
X619795Y-199547D01*
X618267Y-199256D01*
X616739Y-199839D01*
X615429Y-201005D01*
X614555Y-202755D01*
X614119Y-205089D01*
X614555Y-207422D01*
X615429Y-209172D01*
X616739Y-210339D01*
X618267Y-210922D01*
X619795Y-210630D01*
X621106Y-209756D01*
X621979Y-208589D01*
G01X648682Y-210922D02*
Y-193422D01*
X653922D01*
X655669Y-194297D01*
X656979Y-196339D01*
X657416Y-198672D01*
X656979Y-201005D01*
X655887Y-202755D01*
X653922Y-203631D01*
X648682D01*
G01X674479Y-210922D02*
Y-199256D01*
G01Y-201297D02*
X673606Y-200131D01*
X672295Y-199547D01*
X670767Y-199256D01*
X669239Y-199839D01*
X667929Y-201005D01*
X667055Y-202755D01*
X666619Y-205089D01*
X667055Y-207422D01*
X667929Y-209172D01*
X669239Y-210339D01*
X670767Y-210922D01*
X672295Y-210630D01*
X673606Y-209756D01*
X674479Y-208589D01*
G01X684774Y-208881D02*
X685866Y-210047D01*
X687394Y-210922D01*
X688704D01*
X690014Y-210339D01*
X690887Y-209464D01*
X691324Y-208298D01*
X691106Y-206547D01*
X690232Y-205672D01*
X686302Y-203922D01*
X685429Y-201880D01*
X685866Y-200422D01*
X686739Y-199547D01*
X688049Y-199256D01*
X689359Y-199547D01*
X690669Y-200422D01*
G01X702274Y-208881D02*
X703366Y-210047D01*
X704894Y-210922D01*
X706204D01*
X707514Y-210339D01*
X708387Y-209464D01*
X708824Y-208298D01*
X708606Y-206547D01*
X707732Y-205672D01*
X703802Y-203922D01*
X702929Y-201880D01*
X703366Y-200422D01*
X704239Y-199547D01*
X705549Y-199256D01*
X706859Y-199547D01*
X708169Y-200422D01*
G01X735746Y-210922D02*
Y-193422D01*
X740112D01*
X741859Y-194297D01*
X743169Y-195464D01*
X744261Y-197213D01*
X745134Y-199256D01*
X745352Y-202172D01*
X745134Y-205089D01*
X744261Y-207131D01*
X743169Y-208881D01*
X741859Y-210047D01*
X740112Y-210922D01*
X735746D01*
G01X752590Y-193422D02*
X758049Y-210922D01*
X763508Y-193422D01*
G01X775549D02*
Y-210922D01*
G01X770527Y-193422D02*
X780571D01*
G01X804872Y-210922D02*
Y-193422D01*
X810549Y-208005D01*
X816226Y-193422D01*
Y-210922D01*
G01X829795Y-201589D02*
X830669Y-200714D01*
X831324Y-199256D01*
X831761Y-197213D01*
X831324Y-195464D01*
X830451Y-194297D01*
X828922Y-193422D01*
X823027D01*
Y-210922D01*
X830232D01*
X831761Y-209756D01*
X832634Y-208005D01*
X833071Y-205964D01*
X832634Y-203922D01*
X831324Y-202172D01*
X829795Y-201589D01*
X823027D01*
G01X647372Y-165922D02*
Y-148422D01*
X653049Y-163005D01*
X658726Y-148422D01*
Y-165922D01*
G01X670549D02*
X669239Y-165630D01*
X667929Y-164464D01*
X667055Y-162422D01*
X666619Y-160089D01*
X667055Y-157755D01*
X667929Y-155714D01*
X669239Y-154547D01*
X670549Y-154256D01*
X671859Y-154547D01*
X673169Y-155714D01*
X674042Y-157755D01*
X674261Y-160089D01*
X674042Y-162422D01*
X673169Y-164464D01*
X671859Y-165630D01*
X670549Y-165922D01*
G01X691979Y-148422D02*
Y-165922D01*
G01Y-163298D02*
X691106Y-164756D01*
X689795Y-165630D01*
X688267Y-165922D01*
X686521Y-165339D01*
X685211Y-163881D01*
X684337Y-162131D01*
X684119Y-160089D01*
X684337Y-158047D01*
X685211Y-156297D01*
X686521Y-154839D01*
X688267Y-154256D01*
X689795Y-154547D01*
X690887Y-155131D01*
X691979Y-156297D01*
G01X702274Y-158047D02*
X709261D01*
X708606Y-156005D01*
X707514Y-154839D01*
X705986Y-154256D01*
X704457Y-154547D01*
X703147Y-155422D01*
X702274Y-157464D01*
X701837Y-159214D01*
Y-160964D01*
X702274Y-162714D01*
X703366Y-164464D01*
X704676Y-165630D01*
X706204Y-165922D01*
X707732Y-165339D01*
X709261Y-163589D01*
G01X723049Y-165922D02*
Y-148422D01*
G01X975549Y-210922D02*
Y-193422D01*
X972929Y-196922D01*
G01Y-210922D02*
X978169D01*
G01X988246Y-208298D02*
X989555Y-209756D01*
X991084Y-210630D01*
X993049Y-210922D01*
X995014Y-210339D01*
X996542Y-209172D01*
X997634Y-207131D01*
X997852Y-204797D01*
X997416Y-202464D01*
X996324Y-201005D01*
X994795Y-199839D01*
X993267Y-199547D01*
X991739Y-199839D01*
X989774Y-201005D01*
X990429Y-193422D01*
X996324D01*
G01X1010549Y-210922D02*
Y-193422D01*
X1007929Y-196922D01*
G01Y-210922D02*
X1013169D01*
G01X1023901Y-196339D02*
X1025211Y-194589D01*
X1026739Y-193714D01*
X1028486Y-193422D01*
X1030669Y-194005D01*
X1032197Y-195464D01*
X1032634Y-197213D01*
X1032416Y-198964D01*
X1031542Y-200422D01*
X1027176Y-203339D01*
X1025211Y-205380D01*
X1023901Y-208298D01*
X1023464Y-210922D01*
X1032634D01*
G01X1041401Y-203631D02*
X1042929Y-201589D01*
X1044239Y-200422D01*
X1045986Y-199839D01*
X1047514Y-200422D01*
X1048606Y-201589D01*
X1049479Y-203339D01*
X1049697Y-205380D01*
X1049479Y-207131D01*
X1048606Y-208881D01*
X1047295Y-210339D01*
X1045767Y-210922D01*
X1044021Y-210339D01*
X1042492Y-208589D01*
X1041619Y-205964D01*
X1041401Y-203047D01*
X1041837Y-199256D01*
X1042492Y-197213D01*
X1043584Y-195172D01*
X1045112Y-193714D01*
X1046641Y-193422D01*
X1048169Y-194005D01*
X1049261Y-195464D01*
G01X962432Y-165922D02*
Y-148422D01*
X967672D01*
X969419Y-149297D01*
X970729Y-151339D01*
X971166Y-153672D01*
X970729Y-156005D01*
X969637Y-157755D01*
X967672Y-158631D01*
X962432D01*
G01X989102Y-149881D02*
X987792Y-149005D01*
X986264Y-148422D01*
X984517D01*
X982552Y-149297D01*
X981024Y-150755D01*
X979932Y-152506D01*
X979059Y-155422D01*
X978840Y-158047D01*
X979277Y-160672D01*
X979932Y-162422D01*
X981242Y-164172D01*
X982771Y-165339D01*
X984299Y-165922D01*
X985827D01*
X987356Y-165339D01*
X988666Y-164464D01*
X989758Y-163298D01*
G01X1003545Y-156589D02*
X1004419Y-155714D01*
X1005074Y-154256D01*
X1005511Y-152213D01*
X1005074Y-150464D01*
X1004201Y-149297D01*
X1002672Y-148422D01*
X996777D01*
Y-165922D01*
X1003982D01*
X1005511Y-164756D01*
X1006384Y-163005D01*
X1006821Y-160964D01*
X1006384Y-158922D01*
X1005074Y-157172D01*
X1003545Y-156589D01*
X996777D01*
G01X1012749Y-171755D02*
X1025849D01*
G01X1031777Y-165922D02*
Y-148422D01*
X1041821Y-165922D01*
Y-148422D01*
G01X1054299Y-165922D02*
X1052552Y-165630D01*
X1051024Y-164464D01*
X1049714Y-162714D01*
X1048840Y-160672D01*
X1048404Y-158339D01*
Y-156005D01*
X1048840Y-153672D01*
X1049714Y-151630D01*
X1051024Y-149881D01*
X1052552Y-148714D01*
X1054299Y-148422D01*
X1056045Y-148714D01*
X1057574Y-149881D01*
X1058884Y-151630D01*
X1059758Y-153672D01*
X1060194Y-156005D01*
Y-158339D01*
X1059758Y-160672D01*
X1058884Y-162714D01*
X1057574Y-164464D01*
X1056045Y-165630D01*
X1054299Y-165922D01*
G01X1128099Y-210922D02*
Y-193422D01*
X1125479Y-196922D01*
G01Y-210922D02*
X1130719D01*
G01X1147345Y-201589D02*
X1148219Y-200714D01*
X1148874Y-199256D01*
X1149311Y-197213D01*
X1148874Y-195464D01*
X1148001Y-194297D01*
X1146472Y-193422D01*
X1140577D01*
Y-210922D01*
X1147782D01*
X1149311Y-209756D01*
X1150184Y-208005D01*
X1150621Y-205964D01*
X1150184Y-203922D01*
X1148874Y-202172D01*
X1147345Y-201589D01*
X1140577D01*
G01X1105140Y-148422D02*
X1110599Y-165922D01*
X1116058Y-148422D01*
G01X1132466Y-165922D02*
X1123732D01*
Y-148422D01*
X1132466D01*
G01X1128972Y-156880D02*
X1123732D01*
G01X1141232Y-165922D02*
Y-148422D01*
X1146691D01*
X1148437Y-149297D01*
X1149529Y-150464D01*
X1149966Y-152797D01*
X1149529Y-155131D01*
X1148219Y-156589D01*
X1146691Y-157464D01*
X1141232D01*
G01X1146691D02*
X1149966Y-165922D01*
G01X1163099Y-166505D02*
X1162662Y-166214D01*
Y-165630D01*
X1163099Y-165339D01*
X1163536Y-165630D01*
Y-166214D01*
X1163099Y-166505D01*
G01X1238682Y-193422D02*
Y-210922D01*
X1247416D01*
G01X1256401Y-203631D02*
X1257929Y-201589D01*
X1259239Y-200422D01*
X1260986Y-199839D01*
X1262514Y-200422D01*
X1263606Y-201589D01*
X1264479Y-203339D01*
X1264697Y-205380D01*
X1264479Y-207131D01*
X1263606Y-208881D01*
X1262295Y-210339D01*
X1260767Y-210922D01*
X1259021Y-210339D01*
X1257492Y-208589D01*
X1256619Y-205964D01*
X1256401Y-203047D01*
X1256837Y-199256D01*
X1257492Y-197213D01*
X1258584Y-195172D01*
X1260112Y-193714D01*
X1261641Y-193422D01*
X1263169Y-194005D01*
X1264261Y-195464D01*
G01X1279359Y-202172D02*
X1283726D01*
Y-207422D01*
X1282416Y-209172D01*
X1280887Y-210339D01*
X1278704Y-210922D01*
X1276521Y-210339D01*
X1274992Y-209172D01*
X1273682Y-207422D01*
X1272809Y-205380D01*
X1272372Y-203047D01*
Y-201005D01*
X1272809Y-199256D01*
X1273682Y-197213D01*
X1274992Y-195464D01*
X1276302Y-194297D01*
X1278049Y-193422D01*
X1279577D01*
X1281324Y-194005D01*
X1282634Y-195172D01*
G01X1290527Y-210922D02*
Y-193422D01*
X1300571Y-210922D01*
Y-193422D01*
G01X1308246Y-210922D02*
Y-193422D01*
X1312612D01*
X1314359Y-194297D01*
X1315669Y-195464D01*
X1316761Y-197213D01*
X1317634Y-199256D01*
X1317852Y-202172D01*
X1317634Y-205089D01*
X1316761Y-207131D01*
X1315669Y-208881D01*
X1314359Y-210047D01*
X1312612Y-210922D01*
X1308246D01*
G01X1238682Y-148422D02*
Y-165922D01*
X1247416D01*
G01X1264479D02*
Y-154256D01*
G01Y-156297D02*
X1263606Y-155131D01*
X1262295Y-154547D01*
X1260767Y-154256D01*
X1259239Y-154839D01*
X1257929Y-156005D01*
X1257055Y-157755D01*
X1256619Y-160089D01*
X1257055Y-162422D01*
X1257929Y-164172D01*
X1259239Y-165339D01*
X1260767Y-165922D01*
X1262295Y-165630D01*
X1263606Y-164756D01*
X1264479Y-163589D01*
G01X1273464Y-171172D02*
X1274774Y-171755D01*
X1276521Y-171172D01*
X1277612Y-170006D01*
X1278486Y-168547D01*
X1279795Y-163881D01*
X1282634Y-154256D01*
G01X1275647D02*
X1279795Y-163881D01*
G01X1292274Y-158047D02*
X1299261D01*
X1298606Y-156005D01*
X1297514Y-154839D01*
X1295986Y-154256D01*
X1294457Y-154547D01*
X1293147Y-155422D01*
X1292274Y-157464D01*
X1291837Y-159214D01*
Y-160964D01*
X1292274Y-162714D01*
X1293366Y-164464D01*
X1294676Y-165630D01*
X1296204Y-165922D01*
X1297732Y-165339D01*
X1299261Y-163589D01*
G01X1309992Y-165922D02*
Y-154256D01*
G01Y-156589D02*
X1311084Y-155422D01*
X1312176Y-154547D01*
X1313704Y-154256D01*
X1314795Y-154547D01*
X1316106Y-155422D01*
G01X1380796Y-165922D02*
Y-148422D01*
X1385162D01*
X1386909Y-149297D01*
X1388219Y-150464D01*
X1389311Y-152213D01*
X1390184Y-154256D01*
X1390402Y-157172D01*
X1390184Y-160089D01*
X1389311Y-162131D01*
X1388219Y-163881D01*
X1386909Y-165047D01*
X1385162Y-165922D01*
X1380796D01*
G01X1399824Y-158047D02*
X1406811D01*
X1406156Y-156005D01*
X1405064Y-154839D01*
X1403536Y-154256D01*
X1402007Y-154547D01*
X1400697Y-155422D01*
X1399824Y-157464D01*
X1399387Y-159214D01*
Y-160964D01*
X1399824Y-162714D01*
X1400916Y-164464D01*
X1402226Y-165630D01*
X1403754Y-165922D01*
X1405282Y-165339D01*
X1406811Y-163589D01*
G01X1417324Y-163881D02*
X1418416Y-165047D01*
X1419944Y-165922D01*
X1421254D01*
X1422564Y-165339D01*
X1423437Y-164464D01*
X1423874Y-163298D01*
X1423656Y-161547D01*
X1422782Y-160672D01*
X1418852Y-158922D01*
X1417979Y-156880D01*
X1418416Y-155422D01*
X1419289Y-154547D01*
X1420599Y-154256D01*
X1421909Y-154547D01*
X1423219Y-155422D01*
G01X1438099Y-154256D02*
Y-165922D01*
G01Y-149589D02*
X1437662Y-149297D01*
Y-148714D01*
X1438099Y-148422D01*
X1438536Y-148714D01*
Y-149297D01*
X1438099Y-149589D01*
G01X1452542Y-170297D02*
X1454071Y-171464D01*
X1455817Y-171755D01*
X1457345Y-171464D01*
X1458656Y-170006D01*
X1459529Y-167964D01*
Y-154256D01*
G01Y-156589D02*
X1458656Y-155422D01*
X1457345Y-154547D01*
X1455817Y-154256D01*
X1454071Y-154839D01*
X1452979Y-156005D01*
X1452105Y-158047D01*
X1451669Y-160089D01*
X1451887Y-161839D01*
X1452761Y-163881D01*
X1454071Y-165339D01*
X1455817Y-165922D01*
X1457127Y-165630D01*
X1458656Y-164464D01*
X1459529Y-163298D01*
G01X1469387Y-165922D02*
Y-154256D01*
G01Y-157172D02*
X1470261Y-155714D01*
X1471571Y-154547D01*
X1473317Y-154256D01*
X1474845Y-154547D01*
X1476156Y-155714D01*
X1476811Y-157755D01*
Y-165922D01*
G01X1487324Y-158047D02*
X1494311D01*
X1493656Y-156005D01*
X1492564Y-154839D01*
X1491036Y-154256D01*
X1489507Y-154547D01*
X1488197Y-155422D01*
X1487324Y-157464D01*
X1486887Y-159214D01*
Y-160964D01*
X1487324Y-162714D01*
X1488416Y-164464D01*
X1489726Y-165630D01*
X1491254Y-165922D01*
X1492782Y-165339D01*
X1494311Y-163589D01*
G01X1505042Y-165922D02*
Y-154256D01*
G01Y-156589D02*
X1506134Y-155422D01*
X1507226Y-154547D01*
X1508754Y-154256D01*
X1509845Y-154547D01*
X1511156Y-155422D01*
G01X1426729Y-193422D02*
X1431969D01*
G01X1429349D02*
Y-210922D01*
G01X1426729D02*
X1431969D01*
G01X1441390Y-193422D02*
X1446849Y-210922D01*
X1452308Y-193422D01*
G01X1464349Y-210922D02*
Y-203047D01*
X1459982Y-193422D01*
G01X1468716D02*
X1464349Y-203047D01*
G01X1551799Y-193422D02*
X1550052Y-194005D01*
X1548742Y-195464D01*
X1547869Y-197213D01*
X1547214Y-199547D01*
X1546996Y-202172D01*
X1547214Y-204797D01*
X1547869Y-207131D01*
X1548742Y-208881D01*
X1550052Y-210339D01*
X1551799Y-210922D01*
X1553545Y-210339D01*
X1554856Y-208881D01*
X1555729Y-207131D01*
X1556384Y-204797D01*
X1556602Y-202172D01*
X1556384Y-199547D01*
X1555729Y-197213D01*
X1554856Y-195464D01*
X1553545Y-194005D01*
X1551799Y-193422D01*
G01X1565151Y-196339D02*
X1566461Y-194589D01*
X1567989Y-193714D01*
X1569736Y-193422D01*
X1571919Y-194005D01*
X1573447Y-195464D01*
X1573884Y-197213D01*
X1573666Y-198964D01*
X1572792Y-200422D01*
X1568426Y-203339D01*
X1566461Y-205380D01*
X1565151Y-208298D01*
X1564714Y-210922D01*
X1573884D01*
G01X1582869Y-211505D02*
X1590729Y-193422D01*
G01X1604299Y-210922D02*
Y-193422D01*
X1601679Y-196922D01*
G01Y-210922D02*
X1606919D01*
G01X1621799Y-193422D02*
X1620052Y-194005D01*
X1618742Y-195464D01*
X1617869Y-197213D01*
X1617214Y-199547D01*
X1616996Y-202172D01*
X1617214Y-204797D01*
X1617869Y-207131D01*
X1618742Y-208881D01*
X1620052Y-210339D01*
X1621799Y-210922D01*
X1623545Y-210339D01*
X1624856Y-208881D01*
X1625729Y-207131D01*
X1626384Y-204797D01*
X1626602Y-202172D01*
X1626384Y-199547D01*
X1625729Y-197213D01*
X1624856Y-195464D01*
X1623545Y-194005D01*
X1621799Y-193422D01*
G01X1635369Y-211505D02*
X1643229Y-193422D01*
G01X1652651Y-196339D02*
X1653961Y-194589D01*
X1655489Y-193714D01*
X1657236Y-193422D01*
X1659419Y-194005D01*
X1660947Y-195464D01*
X1661384Y-197213D01*
X1661166Y-198964D01*
X1660292Y-200422D01*
X1655926Y-203339D01*
X1653961Y-205380D01*
X1652651Y-208298D01*
X1652214Y-210922D01*
X1661384D01*
G01X1674299Y-193422D02*
X1672552Y-194005D01*
X1671242Y-195464D01*
X1670369Y-197213D01*
X1669714Y-199547D01*
X1669496Y-202172D01*
X1669714Y-204797D01*
X1670369Y-207131D01*
X1671242Y-208881D01*
X1672552Y-210339D01*
X1674299Y-210922D01*
X1676045Y-210339D01*
X1677356Y-208881D01*
X1678229Y-207131D01*
X1678884Y-204797D01*
X1679102Y-202172D01*
X1678884Y-199547D01*
X1678229Y-197213D01*
X1677356Y-195464D01*
X1676045Y-194005D01*
X1674299Y-193422D01*
G01X1691799Y-210922D02*
Y-193422D01*
X1689179Y-196922D01*
G01Y-210922D02*
X1694419D01*
G01X1708862D02*
X1709299Y-207131D01*
X1709954Y-203922D01*
X1710827Y-201005D01*
X1711919Y-197797D01*
X1713666Y-193422D01*
X1704932D01*
G01X1599496Y-165922D02*
Y-148422D01*
X1603862D01*
X1605609Y-149297D01*
X1606919Y-150464D01*
X1608011Y-152213D01*
X1608884Y-154256D01*
X1609102Y-157172D01*
X1608884Y-160089D01*
X1608011Y-162131D01*
X1606919Y-163881D01*
X1605609Y-165047D01*
X1603862Y-165922D01*
X1599496D01*
G01X1625729D02*
Y-154256D01*
G01Y-156297D02*
X1624856Y-155131D01*
X1623545Y-154547D01*
X1622017Y-154256D01*
X1620489Y-154839D01*
X1619179Y-156005D01*
X1618305Y-157755D01*
X1617869Y-160089D01*
X1618305Y-162422D01*
X1619179Y-164172D01*
X1620489Y-165339D01*
X1622017Y-165922D01*
X1623545Y-165630D01*
X1624856Y-164756D01*
X1625729Y-163589D01*
G01X1639299Y-148422D02*
Y-165922D01*
G01X1636242Y-154256D02*
X1642356D01*
G01X1653524Y-158047D02*
X1660511D01*
X1659856Y-156005D01*
X1658764Y-154839D01*
X1657236Y-154256D01*
X1655707Y-154547D01*
X1654397Y-155422D01*
X1653524Y-157464D01*
X1653087Y-159214D01*
Y-160964D01*
X1653524Y-162714D01*
X1654616Y-164464D01*
X1655926Y-165630D01*
X1657454Y-165922D01*
X1658982Y-165339D01*
X1660511Y-163589D01*
G01X1969500Y100000D02*
Y95000D01*
G54D34*
X1949650Y220787D03*
Y228661D03*
G54D25*
X1565000Y-15000D03*
X1723503Y-5000D03*
Y-15000D03*
X1753503Y-5000D03*
Y-15000D03*
G54D16*
X3937Y204370D03*
X-3937D03*
X-11811D03*
X35433D03*
X27559D03*
X19685D03*
X3937Y227992D03*
X-3937D03*
X-11811D03*
X35433D03*
X27559D03*
X19685D03*
X3937Y313504D03*
X-3937D03*
X-11811D03*
X3937Y337126D03*
X-3937D03*
X-11811D03*
X35433D03*
X27559D03*
X19685D03*
X35433Y313504D03*
X27559D03*
X19685D03*
G54D44*
G01X1459612Y310690D02*
Y315367D01*
G01X1462796Y310602D02*
Y312164D01*
G01X1463668Y309831D02*
X1465134D01*
G01X1463443Y306632D02*
X1465213D01*
G01X1457291Y306699D02*
X1458894D01*
G01X1459596Y304373D02*
Y305827D01*
G01X1655358Y123414D02*
X1654012D01*
G01X1650818Y126493D02*
X1652289D01*
G01X1653136Y125711D02*
Y124042D01*
G01X1652223Y129650D02*
X1650586D01*
G01X1660214Y123389D02*
X1661883D01*
G01X1660214Y148587D02*
X1661883D01*
G01X1660214Y126539D02*
X1661883D01*
G01X1656209Y130629D02*
Y131871D01*
G36*
G01X1956463Y209274D02*
G02X1954500Y205493I-1963J-1381D01*
G01X1950000D01*
G02X1947600Y207893I0J2400D01*
G01Y210293D01*
G02X1952400I2400J0D01*
G01X1954500D01*
G02X1954986Y210243I-1J-2400D01*
G03X1956463Y209274I1904J1292D01*
G37*
G54D26*
X1647327Y-315D03*
G54D17*
X15512Y434094D03*
X119980Y145531D03*
G54D27*
X1613069Y302692D03*
G54D36*
X1952250Y240355D03*
G54D18*
X42724Y644684D03*
Y644656D03*
Y654684D03*
Y654656D03*
X67724Y644684D03*
Y644656D03*
Y654684D03*
Y654656D03*
X221656Y644656D03*
X196656D03*
X231446Y644756D03*
Y644784D03*
X221656Y644684D03*
X196656D03*
X221656Y654656D03*
X196656D03*
X231446Y654756D03*
Y654784D03*
X221656Y654684D03*
X196656D03*
X256446Y644756D03*
Y644784D03*
Y654756D03*
Y654784D03*
X409240Y644564D03*
X384240D03*
X418914Y644486D03*
Y644514D03*
X409240Y644536D03*
X384240D03*
X409240Y654564D03*
X384240D03*
X418914Y654486D03*
Y654514D03*
X409240Y654536D03*
X384240D03*
X443914Y644486D03*
Y644514D03*
Y654486D03*
Y654514D03*
X596707Y644293D03*
X571707D03*
X596708Y644266D03*
X571708D03*
X596707Y654293D03*
X571707D03*
X596708Y654266D03*
X571708D03*
X606462Y644245D03*
X631462D03*
X606462Y644217D03*
X631462D03*
X606462Y654245D03*
X631462D03*
X606462Y654217D03*
X631462D03*
X912351Y644245D03*
X887351D03*
X912351Y644273D03*
X887351D03*
X912351Y654245D03*
X887351D03*
X912351Y654273D03*
X887351D03*
X922116Y644206D03*
X947116D03*
X922116Y644234D03*
X947116D03*
X922116Y654206D03*
X947116D03*
X922116Y654234D03*
X947116D03*
X1200877Y644262D03*
Y644234D03*
Y654262D03*
Y654234D03*
X1225877Y644262D03*
X1235614Y644236D03*
X1260614D03*
X1235614Y644264D03*
X1260614D03*
X1225877Y644234D03*
Y654262D03*
X1235614Y654236D03*
X1260614D03*
X1235614Y654264D03*
X1260614D03*
X1225877Y654234D03*
X1514375Y644292D03*
Y644264D03*
Y654292D03*
Y654264D03*
X1539375Y644292D03*
Y644264D03*
Y654292D03*
Y654264D03*
G54D19*
X107249Y105000D03*
G54D37*
X1922248Y518328D03*
G54D28*
X1643803Y585591D03*
X1640850Y582835D03*
X1631992D03*
X1623134D03*
X1640850Y567874D03*
X1631992D03*
X1623134D03*
X1646756Y595039D03*
X1623134Y612756D03*
X1640850Y597795D03*
X1631992D03*
X1623134D03*
X1640850Y612756D03*
X1631992D03*
X1691047Y585591D03*
X1688094Y582835D03*
X1679236D03*
X1670378D03*
X1688094Y567874D03*
X1679236D03*
X1670378D03*
X1694000Y595039D03*
X1688094Y612756D03*
X1679236D03*
X1670378D03*
X1688094Y597795D03*
X1679236D03*
X1670378D03*
G54D38*
X1952756Y605708D03*
G54D29*
X1895945Y21654D03*
G54D39*
X1969883Y207007D03*
Y242441D03*
M02*
